(kicad_pcb
	(version 20241229)
	(generator "pcbnew")
	(generator_version "9.0")
	(general
		(thickness 1.61)
		(legacy_teardrops no)
	)
	(paper "A3")
	(title_block
		(title "SO-DIMM DDR5 Tester")
		(date "2025-11-26")
		(rev "1.3.0")
	)
	(layers
		(0 "F.Cu" signal)
		(4 "In1.Cu" power)
		(6 "In2.Cu" mixed)
		(8 "In3.Cu" power)
		(10 "In4.Cu" mixed)
		(12 "In5.Cu" power)
		(14 "In6.Cu" mixed)
		(16 "In7.Cu" power)
		(18 "In8.Cu" power)
		(20 "In9.Cu" mixed)
		(22 "In10.Cu" power)
		(2 "B.Cu" signal)
		(9 "F.Adhes" user "F.Adhesive")
		(11 "B.Adhes" user "B.Adhesive")
		(13 "F.Paste" user)
		(15 "B.Paste" user)
		(5 "F.SilkS" user "F.Silkscreen")
		(7 "B.SilkS" user "B.Silkscreen")
		(1 "F.Mask" user)
		(3 "B.Mask" user)
		(17 "Dwgs.User" user "User.Drawings")
		(19 "Cmts.User" user "User.Comments")
		(21 "Eco1.User" user "User.Eco1")
		(23 "Eco2.User" user "User.Eco2")
		(25 "Edge.Cuts" user)
		(27 "Margin" user)
		(31 "F.CrtYd" user "F.Courtyard")
		(29 "B.CrtYd" user "B.Courtyard")
		(35 "F.Fab" user)
		(33 "B.Fab" user)
	)
	(setup
		(stackup
			(layer "F.SilkS"
				(type "Top Silk Screen")
				(color "White")
			)
			(layer "F.Paste"
				(type "Top Solder Paste")
			)
			(layer "F.Mask"
				(type "Top Solder Mask")
				(color "Black")
				(thickness 0.01)
			)
			(layer "F.Cu"
				(type "copper")
				(thickness 0.035)
			)
			(layer "dielectric 1"
				(type "prepreg")
				(thickness 0.07)
				(material "PR1080")
				(epsilon_r 3.92)
				(loss_tangent 0.021) addsublayer
				(thickness 0.07)
				(material "PR1080")
				(epsilon_r 3.92)
				(loss_tangent 0.021)
			)
			(layer "In1.Cu"
				(type "copper")
				(thickness 0.018)
			)
			(layer "dielectric 2"
				(type "core")
				(thickness 0.1)
				(material "Isola 370HR")
				(epsilon_r 4.04)
				(loss_tangent 0.021)
			)
			(layer "In2.Cu"
				(type "copper")
				(thickness 0.018)
			)
			(layer "dielectric 3"
				(type "prepreg")
				(thickness 0.07)
				(material "PR1080")
				(epsilon_r 3.92)
				(loss_tangent 0.021) addsublayer
				(thickness 0.07)
				(material "PR1080")
				(epsilon_r 3.92)
				(loss_tangent 0.021)
			)
			(layer "In3.Cu"
				(type "copper")
				(thickness 0.018)
			)
			(layer "dielectric 4"
				(type "core")
				(thickness 0.1)
				(material "Isola 370HR")
				(epsilon_r 4.04)
				(loss_tangent 0.021)
			)
			(layer "In4.Cu"
				(type "copper")
				(thickness 0.018)
			)
			(layer "dielectric 5"
				(type "prepreg")
				(thickness 0.07)
				(material "PR1080")
				(epsilon_r 3.92)
				(loss_tangent 0.021) addsublayer
				(thickness 0.07)
				(material "PR1080")
				(epsilon_r 3.92)
				(loss_tangent 0.021)
			)
			(layer "In5.Cu"
				(type "copper")
				(thickness 0.018)
			)
			(layer "dielectric 6"
				(type "core")
				(thickness 0.1)
				(material "Isola 370HR")
				(epsilon_r 4.04)
				(loss_tangent 0.021)
			)
			(layer "In6.Cu"
				(type "copper")
				(thickness 0.018)
			)
			(layer "dielectric 7"
				(type "prepreg")
				(thickness 0.07)
				(material "PR1080")
				(epsilon_r 3.92)
				(loss_tangent 0.021) addsublayer
				(thickness 0.07)
				(material "PR1080")
				(epsilon_r 3.92)
				(loss_tangent 0.021)
			)
			(layer "In7.Cu"
				(type "copper")
				(thickness 0.018)
			)
			(layer "dielectric 8"
				(type "core")
				(thickness 0.1)
				(material "Isola 370HR")
				(epsilon_r 4.04)
				(loss_tangent 0.021)
			)
			(layer "In8.Cu"
				(type "copper")
				(thickness 0.018)
			)
			(layer "dielectric 9"
				(type "prepreg")
				(thickness 0.07)
				(material "PR1080")
				(epsilon_r 3.92)
				(loss_tangent 0.021) addsublayer
				(thickness 0.07)
				(material "PR1080")
				(epsilon_r 3.92)
				(loss_tangent 0.021)
			)
			(layer "In9.Cu"
				(type "copper")
				(thickness 0.018)
			)
			(layer "dielectric 10"
				(type "core")
				(thickness 0.1)
				(material "Isola 370HR")
				(epsilon_r 4.04)
				(loss_tangent 0.021)
			)
			(layer "In10.Cu"
				(type "copper")
				(thickness 0.018)
			)
			(layer "dielectric 11"
				(type "prepreg")
				(thickness 0.07)
				(material "PR1080")
				(epsilon_r 3.92)
				(loss_tangent 0.021) addsublayer
				(thickness 0.07)
				(material "PR1080")
				(epsilon_r 3.92)
				(loss_tangent 0.021)
			)
			(layer "B.Cu"
				(type "copper")
				(thickness 0.035)
			)
			(layer "B.Mask"
				(type "Bottom Solder Mask")
				(color "Black")
				(thickness 0.01)
			)
			(layer "B.Paste"
				(type "Bottom Solder Paste")
			)
			(layer "B.SilkS"
				(type "Bottom Silk Screen")
				(color "White")
			)
			(copper_finish "ENIG")
			(dielectric_constraints no)
			(edge_connector bevelled)
		)
		(pad_to_mask_clearance 0)
		(allow_soldermask_bridges_in_footprints no)
		(tenting front back)
		(aux_axis_origin 251.9 83.2)
		(pcbplotparams
			(layerselection 0x00000000_00000000_55555555_57000001)
			(plot_on_all_layers_selection 0x00000000_00000000_00000000_00000000)
			(disableapertmacros no)
			(usegerberextensions no)
			(usegerberattributes no)
			(usegerberadvancedattributes no)
			(creategerberjobfile no)
			(dashed_line_dash_ratio 12.000000)
			(dashed_line_gap_ratio 3.000000)
			(svgprecision 6)
			(plotframeref no)
			(mode 1)
			(useauxorigin no)
			(hpglpennumber 1)
			(hpglpenspeed 20)
			(hpglpendiameter 15.000000)
			(pdf_front_fp_property_popups yes)
			(pdf_back_fp_property_popups yes)
			(pdf_metadata yes)
			(pdf_single_document no)
			(dxfpolygonmode yes)
			(dxfimperialunits yes)
			(dxfusepcbnewfont yes)
			(psnegative no)
			(psa4output no)
			(plot_black_and_white yes)
			(sketchpadsonfab no)
			(plotpadnumbers no)
			(hidednponfab no)
			(sketchdnponfab yes)
			(crossoutdnponfab yes)
			(subtractmaskfromsilk no)
			(outputformat 1)
			(mirror no)
			(drillshape 0)
			(scaleselection 1)
			(outputdirectory "./fab")
		)
	)
	(net 0 "")
	(net 1 "GND")
	(net 2 "/Debug FTDI/VBUS")
	(net 3 "/Debug FTDI/FTDI_VPLL")
	(net 4 "/Debug FTDI/FTDI_XI")
	(net 5 "/Debug FTDI/FTDI_VPHY")
	(net 6 "/Debug FTDI/FTDI_3V3")
	(net 7 "/Debug FTDI/FTDI_XO")
	(net 8 "/Debug FTDI/FTDI_VCORE")
	(net 9 "/HDMI + SD Card/HDMI_CONN_5V")
	(net 10 "/FPGA banks HP/VREF")
	(net 11 "+12V")
	(net 12 "/FPGA MGT Interface/PCIE.CLK_P")
	(net 13 "/FPGA MGT Interface/GTR_REFCLK0_P")
	(net 14 "/FPGA MGT Interface/PCIE.CLK_N")
	(net 15 "/FPGA MGT Interface/GTR_REFCLK0_N")
	(net 16 "/FPGA MGT Interface/PCIE.TXD3_P")
	(net 17 "/FPGA MGT Interface/GTX_TX0_P")
	(net 18 "/FPGA MGT Interface/PCIE.TXD2_P")
	(net 19 "/FPGA MGT Interface/GTX_TX1_P")
	(net 20 "/FPGA MGT Interface/PCIE.TXD1_P")
	(net 21 "/FPGA MGT Interface/GTX_TX2_P")
	(net 22 "/FPGA MGT Interface/PCIE.TXD0_P")
	(net 23 "/FPGA MGT Interface/GTX_TX3_P")
	(net 24 "/FPGA MGT Interface/PCIE.TXD3_N")
	(net 25 "/FPGA MGT Interface/GTX_TX0_N")
	(net 26 "/FPGA MGT Interface/PCIE.TXD2_N")
	(net 27 "/FPGA MGT Interface/GTX_TX1_N")
	(net 28 "/FPGA MGT Interface/PCIE.TXD0_N")
	(net 29 "/FPGA MGT Interface/GTX_TX3_N")
	(net 30 "/FPGA MGT Interface/GTX_TX2_N")
	(net 31 "/FPGA MGT Interface/PCIE.TXD1_N")
	(net 32 "Net-(C234-Pad1)")
	(net 33 "Net-(D8-Pad2)")
	(net 34 "/HDMI + SD Card/HDMI_5V")
	(net 35 "/Supply/spare_local")
	(net 36 "DAC_VREF")
	(net 37 "/Debug FTDI/FTDI_SDA_OUT")
	(net 38 "VDC")
	(net 39 "/Supply/QDCDC1_VCC")
	(net 40 "/Supply/QDCDC2_VCC")
	(net 41 "+3V3_AON")
	(net 42 "/Supply/MGTAVCC_local")
	(net 43 "/Debug FTDI/FTDI_SDA_IN")
	(net 44 "/FPGA bank 14/EMCCLK")
	(net 45 "/Debug FTDI/JTAG.TMS")
	(net 46 "/Debug FTDI/JTAG.TCK")
	(net 47 "/Debug FTDI/JTAG.TDO")
	(net 48 "/Debug FTDI/JTAG.TDI")
	(net 49 "/DDR5 SODIMM/HSA")
	(net 50 "/DDR5 SODIMM/DDR.SCL")
	(net 51 "/Supply/1V8_local")
	(net 52 "/Supply/3V3_local")
	(net 53 "/Supply/1V1_local")
	(net 54 "/DDR5 SODIMM/DDR.SDA")
	(net 55 "/DDR5 SODIMM/A.DQ0")
	(net 56 "/Supply/1V2_local")
	(net 57 "/DDR5 SODIMM/A.DQ1")
	(net 58 "/Supply/1V7_local")
	(net 59 "/DDR5 SODIMM/A.DQ2")
	(net 60 "/Supply/5V_local")
	(net 61 "/DDR5 SODIMM/A.DQ3")
	(net 62 "/Supply/SEQ_EN")
	(net 63 "/Supply/1V0_VCC")
	(net 64 "/Supply/1V7")
	(net 65 "/DDR5 SODIMM/A.~{DM0}")
	(net 66 "/Supply/1V0_SW")
	(net 67 "/Supply/1V0_BS")
	(net 68 "/DDR5 SODIMM/A.DQS0_N")
	(net 69 "/DDR5 SODIMM/A.DQS0_P")
	(net 70 "/DDR5 SODIMM/A.DQ4")
	(net 71 "/DDR5 SODIMM/A.DQ5")
	(net 72 "/DDR5 SODIMM/A.DQ6")
	(net 73 "/DDR5 SODIMM/A.DQ7")
	(net 74 "/DDR5 SODIMM/A.DQ8")
	(net 75 "/Supply/1V0_SS")
	(net 76 "/Supply/MGTAVTT_OUT")
	(net 77 "/DDR5 SODIMM/A.DQ9")
	(net 78 "/Supply/1V0_REG")
	(net 79 "/DDR5 SODIMM/A.DQ10")
	(net 80 "/DDR5 SODIMM/A.DQ11")
	(net 81 "/DDR5 SODIMM/A.DQS1_N")
	(net 82 "/DDR5 SODIMM/A.DQS1_P")
	(net 83 "/DDR5 SODIMM/A.~{DM1}")
	(net 84 "/DDR5 SODIMM/A.DQ12")
	(net 85 "/DDR5 SODIMM/A.DQ13")
	(net 86 "/Supply/MGTAVCC_SEN_+")
	(net 87 "/DDR5 SODIMM/A.DQ14")
	(net 88 "/DDR5 SODIMM/A.DQ15")
	(net 89 "/DDR5 SODIMM/A.DQ16")
	(net 90 "/Supply/1V2_SEN_+")
	(net 91 "/DDR5 SODIMM/A.DQ17")
	(net 92 "/DDR5 SODIMM/A.DQ18")
	(net 93 "/DDR5 SODIMM/A.DQ19")
	(net 94 "/DDR5 SODIMM/A.~{DM2}")
	(net 95 "/DDR5 SODIMM/A.DQS2_N")
	(net 96 "/DDR5 SODIMM/A.DQS2_P")
	(net 97 "/DDR5 SODIMM/A.DQ20")
	(net 98 "/DDR5 SODIMM/A.DQ21")
	(net 99 "/DDR5 SODIMM/A.DQ22")
	(net 100 "/DDR5 SODIMM/A.DQ23")
	(net 101 "RFU_2")
	(net 102 "/DDR5 SODIMM/A.DQ24")
	(net 103 "/DDR5 SODIMM/A.DQ25")
	(net 104 "/DDR5 SODIMM/A.DQ26")
	(net 105 "/DDR5 SODIMM/A.DQ27")
	(net 106 "HOT_SWAP_BUTTON")
	(net 107 "/DDR5 SODIMM/A.DQS3_N")
	(net 108 "/DDR5 SODIMM/A.DQS3_P")
	(net 109 "/DDR5 SODIMM/A.~{DM3}")
	(net 110 "/DDR5 SODIMM/A.DQ28")
	(net 111 "/DDR5 SODIMM/A.DQ29")
	(net 112 "/DDR5 SODIMM/A.DQ30")
	(net 113 "/DDR5 SODIMM/A.DQ31")
	(net 114 "/DDR5 SODIMM/A.CB0")
	(net 115 "/DDR5 SODIMM/A.CB1")
	(net 116 "/DDR5 SODIMM/A.CB2")
	(net 117 "/DDR5 SODIMM/A.DQS4_N")
	(net 118 "/DDR5 SODIMM/A.DQS4_P")
	(net 119 "/DDR5 SODIMM/A.CB3")
	(net 120 "/DDR5 SODIMM/A.~{CS0}")
	(net 121 "/DDR5 SODIMM/A.CA0")
	(net 122 "/DDR5 SODIMM/Control.~{ALERT}")
	(net 123 "/Ethernet/ETH3_P")
	(net 124 "/Ethernet/ETH2_P")
	(net 125 "/Ethernet/ETH1_P")
	(net 126 "/Ethernet/ETH4_P")
	(net 127 "/Ethernet/ETH2_N")
	(net 128 "/Ethernet/ETH1_N")
	(net 129 "/Ethernet/ETH3_N")
	(net 130 "/Ethernet/ETH4_N")
	(net 131 "/Supply/1V7_SEN_+")
	(net 132 "/Ethernet/AVDDL")
	(net 133 "/Ethernet/AVDDL_PLL")
	(net 134 "/Ethernet/AVDDH")
	(net 135 "PCIE.PWRGD")
	(net 136 "/DDR5 SODIMM/A.CA1")
	(net 137 "/DDR5 SODIMM/RFU1")
	(net 138 "/DDR5 SODIMM/A.~{CS1}")
	(net 139 "/DDR5 SODIMM/A.CA2")
	(net 140 "/DDR5 SODIMM/VSS_DET1")
	(net 141 "/Supply/5V_SEN_+")
	(net 142 "/Supply/1V1_SEN_+")
	(net 143 "/Supply/MGTAVCC_SEN_-")
	(net 144 "/Supply/1V2_SEN_-")
	(net 145 "/Supply/1V7_SEN_-")
	(net 146 "/Supply/5V_SEN_-")
	(net 147 "/DDR5 SODIMM/A.CA3")
	(net 148 "/DDR5 SODIMM/A.CA4")
	(net 149 "/DDR5 SODIMM/A.CA5")
	(net 150 "/DDR5 SODIMM/A.CA6")
	(net 151 "/DDR5 SODIMM/A.CA7")
	(net 152 "/DDR5 SODIMM/A.CA8")
	(net 153 "/DDR5 SODIMM/A.CA9")
	(net 154 "/DDR5 SODIMM/A.CA10")
	(net 155 "/DDR5 SODIMM/A.CA11")
	(net 156 "/DDR5 SODIMM/A.CA12")
	(net 157 "/DDR5 SODIMM/A.CK0_P")
	(net 158 "/DDR5 SODIMM/A.CK1_P")
	(net 159 "/DDR5 SODIMM/A.CK0_N")
	(net 160 "/DDR5 SODIMM/A.CK1_N")
	(net 161 "/DDR5 SODIMM/B.CK0_P")
	(net 162 "/DDR5 SODIMM/B.CK1_P")
	(net 163 "/DDR5 SODIMM/B.CK0_N")
	(net 164 "/DDR5 SODIMM/B.CK1_N")
	(net 165 "/DDR5 SODIMM/B.CA12")
	(net 166 "/DDR5 SODIMM/B.CA11")
	(net 167 "/DDR5 SODIMM/B.CA10")
	(net 168 "/DDR5 SODIMM/B.CA9")
	(net 169 "/DDR5 SODIMM/B.CA8")
	(net 170 "/DDR5 SODIMM/B.CA7")
	(net 171 "/DDR5 SODIMM/RFU2")
	(net 172 "/DDR5 SODIMM/VSS_DET2")
	(net 173 "/DDR5 SODIMM/RFU3")
	(net 174 "/DDR5 SODIMM/B.CA6")
	(net 175 "/Supply/1V1_SEN_-")
	(net 176 "/DDR5 SODIMM/B.CA5")
	(net 177 "/DDR5 SODIMM/B.CA4")
	(net 178 "/DDR5 SODIMM/B.CA3")
	(net 179 "/DDR5 SODIMM/B.CA2")
	(net 180 "/DDR5 SODIMM/B.~{CS0}")
	(net 181 "/DDR5 SODIMM/B.CA1")
	(net 182 "/DDR5 SODIMM/Control.~{RESET}")
	(net 183 "/DDR5 SODIMM/B.CA0")
	(net 184 "/DDR5 SODIMM/B.~{CS1}")
	(net 185 "/Supply/~{PB_CTRL_CLR}")
	(net 186 "/Supply/PB_CTRL_OUT")
	(net 187 "+1V0_MGTAVCC")
	(net 188 "+1V8")
	(net 189 "/DDR5 SODIMM/B.CB0")
	(net 190 "/DDR5 SODIMM/B.DQS4_N")
	(net 191 "/DDR5 SODIMM/B.DQS4_P")
	(net 192 "/DDR5 SODIMM/B.CB1")
	(net 193 "/DDR5 SODIMM/B.CB3")
	(net 194 "/DDR5 SODIMM/B.CB2")
	(net 195 "/DDR5 SODIMM/B.DQ0")
	(net 196 "/DDR5 SODIMM/B.DQ1")
	(net 197 "/DDR5 SODIMM/B.DQ2")
	(net 198 "/DDR5 SODIMM/B.DQ3")
	(net 199 "+1V2")
	(net 200 "+3V3")
	(net 201 "+5V")
	(net 202 "/DDR5 SODIMM/B.~{DM0}")
	(net 203 "/DDR5 SODIMM/B.DQS0_N")
	(net 204 "/DDR5 SODIMM/B.DQS0_P")
	(net 205 "/DDR5 SODIMM/B.DQ4")
	(net 206 "+1V1")
	(net 207 "/Supply/~{PB_CTRL_INT}")
	(net 208 "/Supply/FB6")
	(net 209 "/Supply/FB5")
	(net 210 "/Supply/FB1")
	(net 211 "/Supply/FB2")
	(net 212 "/DDR5 SODIMM/B.DQ5")
	(net 213 "/DDR5 SODIMM/B.DQ6")
	(net 214 "Net-(C135-Pad2)")
	(net 215 "Net-(C137-Pad2)")
	(net 216 "/Supply/FB3")
	(net 217 "/Supply/FB7")
	(net 218 "/Supply/FB8")
	(net 219 "/DDR5 SODIMM/B.DQ7")
	(net 220 "/Supply/FB4")
	(net 221 "/Supply/EN1")
	(net 222 "/Supply/EN2")
	(net 223 "/Supply/EN3")
	(net 224 "/Supply/MGTAVTT_ILIM")
	(net 225 "/Supply/1V0_FB")
	(net 226 "+1V2_MGTAVTT")
	(net 227 "+1V0")
	(net 228 "/DDR5 SODIMM/B.DQ8")
	(net 229 "/PCIe connector/PRSNT#1")
	(net 230 "/PCIe connector/x1")
	(net 231 "/PCIe connector/x4")
	(net 232 "/Supply/sp_SEN_+")
	(net 233 "/DDR5 SODIMM/B.DQ9")
	(net 234 "HOT_SWAP_YELLOW")
	(net 235 "HOT_SWAP_GREEN")
	(net 236 "HOT_SWAP_RED")
	(net 237 "/Supply/sp_SEN_-")
	(net 238 "/DDR5 SODIMM/B.DQ10")
	(net 239 "/Supply/spare")
	(net 240 "POWER")
	(net 241 "FPGA_POWER_CYCLE")
	(net 242 "FPGA_POWER_OFF")
	(net 243 "/Supply/3V3_SEN_+")
	(net 244 "/Supply/1V8_SEN_+")
	(net 245 "/Supply/3V3_SEN_-")
	(net 246 "/Supply/1V8_SEN_-")
	(net 247 "/DDR5 SODIMM/B.DQ11")
	(net 248 "~{DDR_PRESENCE}")
	(net 249 "TB_DETECT")
	(net 250 "/DDR5 SODIMM/B.DQS1_N")
	(net 251 "Net-(C132-Pad1)")
	(net 252 "/Supply/~{PB_CTRL_IN}")
	(net 253 "/DDR5 SODIMM/B.DQS1_P")
	(net 254 "/DDR5 SODIMM/B.~{DM1}")
	(net 255 "/DDR5 SODIMM/B.DQ12")
	(net 256 "/DDR5 SODIMM/B.DQ13")
	(net 257 "/DDR5 SODIMM/B.DQ14")
	(net 258 "/DDR5 SODIMM/B.DQ15")
	(net 259 "/DDR5 SODIMM/B.DQ16")
	(net 260 "/DDR5 SODIMM/B.DQ17")
	(net 261 "/DDR5 SODIMM/B.DQ18")
	(net 262 "/DDR5 SODIMM/B.DQ19")
	(net 263 "FTDI_DIS")
	(net 264 "/DDR5 SODIMM/B.~{DM2}")
	(net 265 "/DDR5 SODIMM/B.DQS2_N")
	(net 266 "/DDR5 SODIMM/B.DQS2_P")
	(net 267 "VDDSPD")
	(net 268 "/DDR5 SODIMM/B.DQ20")
	(net 269 "/DDR5 SODIMM/B.DQ21")
	(net 270 "/DDR5 SODIMM/B.DQ22")
	(net 271 "/DDR5 SODIMM/B.DQ23")
	(net 272 "FAN_PWM")
	(net 273 "RFU_1")
	(net 274 "RFU_3")
	(net 275 "/DDR5 SODIMM/B.DQ24")
	(net 276 "/DDR5 SODIMM/B.DQ25")
	(net 277 "/DDR5 SODIMM/B.DQ26")
	(net 278 "/DDR5 SODIMM/B.DQ27")
	(net 279 "/DDR5 SODIMM/B.DQS3_N")
	(net 280 "/Supply/PG1")
	(net 281 "/Supply/PG2")
	(net 282 "/Supply/PG3")
	(net 283 "/DDR5 SODIMM/B.DQS3_P")
	(net 284 "/DDR5 SODIMM/B.~{DM3}")
	(net 285 "/Supply/QDCDC2_SCL")
	(net 286 "/DDR5 SODIMM/B.DQ28")
	(net 287 "/DDR5 SODIMM/B.DQ29")
	(net 288 "/DDR5 SODIMM/B.DQ30")
	(net 289 "/DDR5 SODIMM/B.DQ31")
	(net 290 "/Debug FTDI/DBG_USB_P")
	(net 291 "/Debug FTDI/DBG_USB_N")
	(net 292 "/HDMI + SD Card/HDMI_CONN_D2_P")
	(net 293 "/HDMI + SD Card/HDMI_CONN_D2_N")
	(net 294 "/HDMI + SD Card/HDMI_CONN_D1_P")
	(net 295 "/HDMI + SD Card/HDMI_CONN_D1_N")
	(net 296 "/HDMI + SD Card/HDMI_CONN_D0_P")
	(net 297 "/Supply/PWR_SCL_2")
	(net 298 "/Supply/PWR_SDA_2")
	(net 299 "Net-(U15-XI)")
	(net 300 "Net-(U15-XO)")
	(net 301 "Net-(D9-C_{R})")
	(net 302 "Net-(D9-C_{G})")
	(net 303 "Net-(C221-Pad1)")
	(net 304 "Net-(D1-Pad2)")
	(net 305 "Net-(D2-Pad2)")
	(net 306 "Net-(D3-Pad2)")
	(net 307 "Net-(D4-Pad2)")
	(net 308 "Net-(D5-Pad2)")
	(net 309 "Net-(D6-Pad2)")
	(net 310 "Net-(D7-Pad2)")
	(net 311 "/HDMI + SD Card/HDMI_CONN_D0_N")
	(net 312 "Net-(D9-C_{Y})")
	(net 313 "Net-(J2C-PWR_GOOD)")
	(net 314 "Net-(J2C-PWR_EN)")
	(net 315 "Net-(D10-Pad1)")
	(net 316 "Net-(D11-Pad1)")
	(net 317 "Net-(D12-Pad1)")
	(net 318 "Net-(D13-Pad1)")
	(net 319 "unconnected-(J1-Pad12)")
	(net 320 "unconnected-(J1-Pad14)")
	(net 321 "Net-(J3-CC_{1})")
	(net 322 "unconnected-(J3-SBU_{1}-PadA8)")
	(net 323 "Net-(J3-CC_{2})")
	(net 324 "unconnected-(J3-SBU_{2}-PadB8)")
	(net 325 "Net-(J4-CEC)")
	(net 326 "unconnected-(J4-UTILITY{slash}HEAC+-Pad14)")
	(net 327 "Net-(J4-SCL)")
	(net 328 "Net-(J4-SDA)")
	(net 329 "Net-(J4-HPD{slash}HEAC-)")
	(net 330 "Net-(J5-CD_SW1)")
	(net 331 "unconnected-(J8-Pin_3-Pad3)")
	(net 332 "Net-(J8-Pin_4)")
	(net 333 "unconnected-(J9-TCK-PadA5)")
	(net 334 "unconnected-(J9-TDI-PadA6)")
	(net 335 "unconnected-(J9-TDO-PadA7)")
	(net 336 "unconnected-(J9-TMS-PadA8)")
	(net 337 "unconnected-(J9-3V3-PadA10)")
	(net 338 "unconnected-(J9-NC-PadA19)")
	(net 339 "unconnected-(J9-NC-PadA32)")
	(net 340 "unconnected-(J9-SMCLK-PadB5)")
	(net 341 "unconnected-(J9-SMDAT-PadB6)")
	(net 342 "unconnected-(J9-~{TRST}-PadB9)")
	(net 343 "unconnected-(J9-3V3AUX-PadB10)")
	(net 344 "unconnected-(J9-~{WAKE}-PadB11)")
	(net 345 "unconnected-(J9-~{CLKREQ}-PadB12)")
	(net 346 "unconnected-(J9-~{PWRBRK}-PadB30)")
	(net 347 "Net-(Q1-D)")
	(net 348 "/HDMI + SD Card/HDMI_CONN_CLK_P")
	(net 349 "/HDMI + SD Card/HDMI_CONN_CLK_N")
	(net 350 "/FPGA bank 16/SD.DAT2")
	(net 351 "Net-(Q2-D)")
	(net 352 "Net-(Q3-D)")
	(net 353 "Net-(Q4-D)")
	(net 354 "Net-(Q5-D)")
	(net 355 "Net-(Q6-D)")
	(net 356 "Net-(Q7-D)")
	(net 357 "Net-(Q8-D)")
	(net 358 "Net-(Q9-D)")
	(net 359 "Net-(Q10-D)")
	(net 360 "/HyperRAM + QSPI Flash/IO3")
	(net 361 "/HyperRAM + QSPI Flash/IO2")
	(net 362 "/HyperRAM + QSPI Flash/IO0")
	(net 363 "/HyperRAM + QSPI Flash/IO1")
	(net 364 "Net-(Q11-D)")
	(net 365 "Net-(Q12-G)")
	(net 366 "Net-(Q13-G)")
	(net 367 "Net-(Q16-D)")
	(net 368 "Net-(Q17-G)")
	(net 369 "Net-(U4J-MGTRREF_115)")
	(net 370 "Net-(U6-~{RESET})")
	(net 371 "/FPGA bank 16/SD.DAT3")
	(net 372 "/FPGA bank 16/SD.CMD")
	(net 373 "/FPGA bank 16/SD.CLK")
	(net 374 "/FPGA bank 16/SD.DAT0")
	(net 375 "Net-(U6-REF)")
	(net 376 "Net-(R96-Pad2)")
	(net 377 "Net-(R97-Pad2)")
	(net 378 "Net-(U7-B1Y)")
	(net 379 "Net-(R129-Pad1)")
	(net 380 "Net-(U7-B2Y)")
	(net 381 "Net-(U7-B3Y)")
	(net 382 "Net-(U7-B4)")
	(net 383 "Net-(U13-OE)")
	(net 384 "Net-(U15-ISET)")
	(net 385 "Net-(U25-~{PWRDN})")
	(net 386 "Net-(U30-~{PWRDN})")
	(net 387 "Net-(U16-EN)")
	(net 388 "unconnected-(U1-NC-PadA2)")
	(net 389 "unconnected-(U1-NC-PadA5)")
	(net 390 "unconnected-(U1-NC-PadB5)")
	(net 391 "unconnected-(U1-NC-PadC2)")
	(net 392 "unconnected-(U1-NC-PadC5)")
	(net 393 "unconnected-(U3-EP-Pad9)")
	(net 394 "unconnected-(U4E-IO_L9P_T1_DQS_16-PadA9)")
	(net 395 "unconnected-(U4D-IO_L3N_T0_DQS_AD1N_15-PadA17)")
	(net 396 "unconnected-(U4D-IO_L2P_T0_AD8P_15-PadA18)")
	(net 397 "unconnected-(U4D-IO_L2N_T0_AD8N_15-PadA19)")
	(net 398 "unconnected-(U4A-IO_L11N_T1_SRCC_12-PadAB24)")
	(net 399 "unconnected-(U4A-IO_L7N_T1_12-PadAB25)")
	(net 400 "unconnected-(U4A-IO_L14P_T2_SRCC_12-PadAC23)")
	(net 401 "unconnected-(U4E-IO_L10N_T1_16-PadB9)")
	(net 402 "unconnected-(U4E-IO_L20N_T3_16-PadB11)")
	(net 403 "unconnected-(U4E-IO_L20P_T3_16-PadB12)")
	(net 404 "unconnected-(U4D-IO_L1N_T0_AD0N_15-PadB16)")
	(net 405 "unconnected-(U4D-IO_L3P_T0_DQS_AD1P_15-PadB17)")
	(net 406 "unconnected-(U4D-IO_L4N_T0_AD9N_15-PadB19)")
	(net 407 "unconnected-(U4E-IO_L13N_T2_MRCC_16-PadC11)")
	(net 408 "unconnected-(U4E-IO_L19N_T3_VREF_16-PadC13)")
	(net 409 "unconnected-(U4E-IO_L19P_T3_16-PadC14)")
	(net 410 "unconnected-(U4D-IO_L1P_T0_AD0P_15-PadC16)")
	(net 411 "unconnected-(U4D-IO_L5P_T0_AD2P_15-PadC17)")
	(net 412 "unconnected-(U4D-IO_L5N_T0_AD2N_15-PadC18)")
	(net 413 "unconnected-(U4D-IO_L4P_T0_AD9P_15-PadC19)")
	(net 414 "unconnected-(U4E-IO_L14N_T2_SRCC_16-PadD11)")
	(net 415 "unconnected-(U4E-IO_L17N_T2_16-PadD13)")
	(net 416 "unconnected-(U4E-IO_L17P_T2_16-PadD14)")
	(net 417 "unconnected-(U4D-IO_L6P_T0_15-PadD15)")
	(net 418 "unconnected-(U4D-IO_L6N_T0_VREF_15-PadD16)")
	(net 419 "unconnected-(U4D-IO_L13N_T2_MRCC_15-PadD18)")
	(net 420 "unconnected-(U4D-IO_L15P_T2_DQS_15-PadD19)")
	(net 421 "unconnected-(U4D-IO_L15N_T2_DQS_ADV_B_15-PadD20)")
	(net 422 "unconnected-(U4E-IO_L14P_T2_SRCC_16-PadE11)")
	(net 423 "unconnected-(U4E-IO_L18N_T2_16-PadE12)")
	(net 424 "unconnected-(U4E-IO_L18P_T2_16-PadE13)")
	(net 425 "unconnected-(U4D-IO_L10P_T1_AD4P_15-PadE15)")
	(net 426 "unconnected-(U4D-IO_L10N_T1_AD4N_15-PadE16)")
	(net 427 "unconnected-(U4D-IO_L12N_T1_MRCC_AD5N_15-PadE17)")
	(net 428 "unconnected-(U4D-IO_L13P_T2_MRCC_15-PadE18)")
	(net 429 "unconnected-(U4D-IO_L17N_T2_A25_15-PadE20)")
	(net 430 "unconnected-(U4C-IO_L12N_T1_MRCC_14-PadE23)")
	(net 431 "unconnected-(U4I-MGTREFCLK1N_116-PadF5)")
	(net 432 "unconnected-(U4I-MGTREFCLK1P_116-PadF6)")
	(net 433 "unconnected-(U4E-IO_L11N_T1_SRCC_16-PadF10)")
	(net 434 "unconnected-(U4E-IO_L16N_T2_16-PadF12)")
	(net 435 "unconnected-(U4E-IO_L15N_T2_DQS_16-PadF13)")
	(net 436 "unconnected-(U4E-IO_L15P_T2_DQS_16-PadF14)")
	(net 437 "unconnected-(U4D-IO_L8N_T1_AD3N_15-PadF15)")
	(net 438 "unconnected-(U4D-IO_L12P_T1_MRCC_AD5P_15-PadF17)")
	(net 439 "unconnected-(U4D-IO_L11N_T1_SRCC_AD12N_15-PadF18)")
	(net 440 "unconnected-(U4D-IO_L17P_T2_A26_15-PadF19)")
	(net 441 "unconnected-(U4D-IO_L16N_T2_A27_15-PadF20)")
	(net 442 "unconnected-(U4C-IO_L12P_T1_MRCC_14-PadF22)")
	(net 443 "unconnected-(U4C-IO_L14N_T2_SRCC_14-PadF24)")
	(net 444 "unconnected-(U4E-IO_L2N_T0_16-PadG9)")
	(net 445 "unconnected-(U4E-IO_L2P_T0_16-PadG10)")
	(net 446 "unconnected-(U4E-IO_L11P_T1_SRCC_16-PadG11)")
	(net 447 "unconnected-(U4E-IO_L16P_T2_16-PadG12)")
	(net 448 "unconnected-(U4E-IO_L5N_T0_16-PadG14)")
	(net 449 "unconnected-(U4D-IO_L8P_T1_AD3P_15-PadG15)")
	(net 450 "unconnected-(U4D-IO_L7N_T1_AD10N_15-PadG16)")
	(net 451 "unconnected-(U4D-IO_L11P_T1_SRCC_AD12P_15-PadG17)")
	(net 452 "unconnected-(U4D-IO_L16P_T2_A28_15-PadG19)")
	(net 453 "unconnected-(U4D-IO_L18N_T2_A23_15-PadG20)")
	(net 454 "unconnected-(U4C-IO_L19N_T3_A09_D25_VREF_14-PadG21)")
	(net 455 "unconnected-(U4C-IO_L13P_T2_MRCC_14-PadG22)")
	(net 456 "unconnected-(U4I-MGTXTXN3_115-PadH1)")
	(net 457 "unconnected-(U4I-MGTXTXP3_115-PadH2)")
	(net 458 "unconnected-(U4I-MGTREFCLK0N_115-PadH5)")
	(net 459 "unconnected-(U4I-MGTREFCLK0P_115-PadH6)")
	(net 460 "unconnected-(U4E-IO_L1N_T0_16-PadH8)")
	(net 461 "unconnected-(U4E-IO_L1P_T0_16-PadH9)")
	(net 462 "unconnected-(U4E-IO_L6N_T0_VREF_16-PadH11)")
	(net 463 "unconnected-(U4E-IO_L6P_T0_16-PadH12)")
	(net 464 "unconnected-(U4E-IO_L3N_T0_DQS_16-PadH13)")
	(net 465 "unconnected-(U4E-IO_L5P_T0_16-PadH14)")
	(net 466 "unconnected-(U4D-IO_L7P_T1_AD10P_15-PadH16)")
	(net 467 "unconnected-(U4D-IO_L14P_T2_SRCC_15-PadH17)")
	(net 468 "unconnected-(U4D-IO_L14N_T2_SRCC_15-PadH18)")
	(net 469 "unconnected-(U4D-IO_L18P_T2_A24_15-PadH19)")
	(net 470 "unconnected-(U4C-IO_L20P_T3_A08_D24_14-PadH23)")
	(net 471 "unconnected-(U4C-IO_L20N_T3_A07_D23_14-PadH24)")
	(net 472 "unconnected-(U4C-IO_L18N_T2_A11_D27_14-PadH26)")
	(net 473 "unconnected-(U4I-MGTXRXN3_115-PadJ3)")
	(net 474 "unconnected-(U4I-MGTXRXP3_115-PadJ4)")
	(net 475 "unconnected-(U4E-IO_0_16-PadJ8)")
	(net 476 "unconnected-(U4E-IO_L4N_T0_16-PadJ10)")
	(net 477 "unconnected-(U4E-IO_L4P_T0_16-PadJ11)")
	(net 478 "unconnected-(U4E-IO_L3P_T0_DQS_16-PadJ13)")
	(net 479 "unconnected-(U4E-IO_25_16-PadJ14)")
	(net 480 "unconnected-(U4D-IO_L9P_T1_DQS_AD11P_15-PadJ15)")
	(net 481 "unconnected-(U4D-IO_L9N_T1_DQS_AD11N_15-PadJ16)")
	(net 482 "unconnected-(U4D-IO_L20P_T3_A20_15-PadJ18)")
	(net 483 "unconnected-(U4D-IO_L20N_T3_A19_15-PadJ19)")
	(net 484 "unconnected-(U4D-IO_L19N_T3_A21_VREF_15-PadJ20)")
	(net 485 "unconnected-(U4C-IO_L21P_T3_DQS_14-PadJ21)")
	(net 486 "unconnected-(U4C-IO_L24N_T3_A00_D16_14-PadJ23)")
	(net 487 "unconnected-(U4C-IO_L22P_T3_A05_D21_14-PadJ24)")
	(net 488 "unconnected-(U4C-IO_L22N_T3_A04_D20_14-PadJ25)")
	(net 489 "unconnected-(U4C-IO_L18P_T2_A12_D28_14-PadJ26)")
	(net 490 "unconnected-(U4I-MGTXTXN2_115-PadK1)")
	(net 491 "unconnected-(U4I-MGTXTXP2_115-PadK2)")
	(net 492 "unconnected-(U4I-MGTREFCLK1N_115-PadK5)")
	(net 493 "unconnected-(U4I-MGTREFCLK1P_115-PadK6)")
	(net 494 "unconnected-(U4D-IO_0_15-PadK15)")
	(net 495 "unconnected-(U4D-IO_L22P_T3_A17_15-PadK16)")
	(net 496 "unconnected-(U4D-IO_L22N_T3_A16_15-PadK17)")
	(net 497 "unconnected-(U4D-IO_L24N_T3_RS0_15-PadK18)")
	(net 498 "unconnected-(U4D-IO_L19P_T3_A22_15-PadK20)")
	(net 499 "unconnected-(U4C-IO_0_14-PadK21)")
	(net 500 "unconnected-(U4C-IO_L23N_T3_A02_D18_14-PadK22)")
	(net 501 "unconnected-(U4C-IO_L24P_T3_A01_D17_14-PadK23)")
	(net 502 "unconnected-(U4B-IO_L1P_T0_13-PadK25)")
	(net 503 "unconnected-(U4B-IO_L1N_T0_13-PadK26)")
	(net 504 "unconnected-(U4I-MGTXRXN2_115-PadL3)")
	(net 505 "unconnected-(U4I-MGTXRXP2_115-PadL4)")
	(net 506 "unconnected-(U4D-IO_L24P_T3_RS1_15-PadL17)")
	(net 507 "unconnected-(U4D-IO_L23N_T3_FWE_B_15-PadL18)")
	(net 508 "unconnected-(U4D-IO_L21P_T3_DQS_15-PadL19)")
	(net 509 "unconnected-(U4D-IO_L21N_T3_DQS_A18_15-PadL20)")
	(net 510 "unconnected-(U4C-IO_L23P_T3_A03_D19_14-PadL22)")
	(net 511 "unconnected-(U4C-IO_25_14-PadL23)")
	(net 512 "unconnected-(U4B-IO_L8N_T1_13-PadL24)")
	(net 513 "unconnected-(U4B-IO_L3N_T0_DQS_13-PadL25)")
	(net 514 "unconnected-(U4I-MGTXTXN1_115-PadM1)")
	(net 515 "unconnected-(U4I-MGTXTXP1_115-PadM2)")
	(net 516 "unconnected-(U4D-IO_25_15-PadM16)")
	(net 517 "unconnected-(U4D-IO_L23P_T3_FOE_B_15-PadM17)")
	(net 518 "unconnected-(U4B-IO_L22N_T3_13-PadM19)")
	(net 519 "unconnected-(U4B-IO_L7N_T1_13-PadM20)")
	(net 520 "unconnected-(U4B-IO_L10P_T1_13-PadM21)")
	(net 521 "unconnected-(U4B-IO_L10N_T1_13-PadM22)")
	(net 522 "unconnected-(U4B-IO_L8P_T1_13-PadM24)")
	(net 523 "unconnected-(U4B-IO_L3P_T0_DQS_13-PadM25)")
	(net 524 "unconnected-(U4B-IO_L5N_T0_13-PadM26)")
	(net 525 "unconnected-(U4I-MGTXRXN1_115-PadN3)")
	(net 526 "unconnected-(U4I-MGTXRXP1_115-PadN4)")
	(net 527 "unconnected-(U4B-IO_0_13-PadN16)")
	(net 528 "unconnected-(U4B-IO_L20N_T3_13-PadN17)")
	(net 529 "unconnected-(U4B-IO_L22P_T3_13-PadN18)")
	(net 530 "unconnected-(U4B-IO_L7P_T1_13-PadN19)")
	(net 531 "unconnected-(U4B-IO_L12P_T1_MRCC_13-PadN21)")
	(net 532 "unconnected-(U4B-IO_L12N_T1_MRCC_13-PadN22)")
	(net 533 "unconnected-(U4B-IO_L11N_T1_SRCC_13-PadN23)")
	(net 534 "unconnected-(U4B-IO_L4N_T0_13-PadN24)")
	(net 535 "unconnected-(U4B-IO_L5P_T0_13-PadN26)")
	(net 536 "unconnected-(U4I-MGTXTXN0_115-PadP1)")
	(net 537 "unconnected-(U4I-MGTXTXP0_115-PadP2)")
	(net 538 "unconnected-(U4B-IO_L20P_T3_13-PadP16)")
	(net 539 "unconnected-(U4B-IO_L24N_T3_13-PadP18)")
	(net 540 "unconnected-(U4B-IO_L9P_T1_DQS_13-PadP19)")
	(net 541 "unconnected-(U4B-IO_L9N_T1_DQS_13-PadP20)")
	(net 542 "unconnected-(U4B-IO_L13N_T2_MRCC_13-PadP21)")
	(net 543 "unconnected-(U4B-IO_L11P_T1_SRCC_13-PadP23)")
	(net 544 "unconnected-(U4B-IO_L4P_T0_13-PadP24)")
	(net 545 "unconnected-(U4B-IO_L6N_T0_VREF_13-PadP25)")
	(net 546 "unconnected-(U4B-IO_L2N_T0_13-PadP26)")
	(net 547 "unconnected-(U4I-MGTXRXN0_115-PadR3)")
	(net 548 "unconnected-(U4I-MGTXRXP0_115-PadR4)")
	(net 549 "unconnected-(U4B-IO_L21P_T3_DQS_13-PadR16)")
	(net 550 "unconnected-(U4B-IO_L21N_T3_DQS_13-PadR17)")
	(net 551 "unconnected-(U4B-IO_L24P_T3_13-PadR18)")
	(net 552 "unconnected-(U4B-IO_L16N_T2_13-PadR20)")
	(net 553 "unconnected-(U4B-IO_L13P_T2_MRCC_13-PadR21)")
	(net 554 "unconnected-(U4B-IO_L14P_T2_SRCC_13-PadR22)")
	(net 555 "unconnected-(U4B-IO_L14N_T2_SRCC_13-PadR23)")
	(net 556 "unconnected-(U4B-IO_L6P_T0_13-PadR25)")
	(net 557 "unconnected-(U4B-IO_L2P_T0_13-PadR26)")
	(net 558 "unconnected-(U4B-IO_L23N_T3_13-PadT17)")
	(net 559 "unconnected-(U4B-IO_L19P_T3_13-PadT18)")
	(net 560 "unconnected-(U4B-IO_L19N_T3_VREF_13-PadT19)")
	(net 561 "unconnected-(U4B-IO_L16P_T2_13-PadT20)")
	(net 562 "unconnected-(U4B-IO_L17P_T2_13-PadT22)")
	(net 563 "unconnected-(U4B-IO_L17N_T2_13-PadT23)")
	(net 564 "unconnected-(U4B-IO_L15P_T2_DQS_13-PadT24)")
	(net 565 "unconnected-(U4B-IO_L15N_T2_DQS_13-PadT25)")
	(net 566 "unconnected-(U4B-IO_25_13-PadU16)")
	(net 567 "unconnected-(U4B-IO_L23P_T3_13-PadU17)")
	(net 568 "unconnected-(U4B-IO_L18P_T2_13-PadU19)")
	(net 569 "unconnected-(U4B-IO_L18N_T2_13-PadU20)")
	(net 570 "unconnected-(U4A-IO_0_12-PadU21)")
	(net 571 "unconnected-(U8-Pad1)")
	(net 572 "unconnected-(U8-Pad5)")
	(net 573 "unconnected-(U4A-IO_L1P_T0_12-PadU22)")
	(net 574 "unconnected-(U4A-IO_L2P_T0_12-PadU24)")
	(net 575 "unconnected-(U4A-IO_L6P_T0_12-PadV21)")
	(net 576 "unconnected-(U4A-IO_L1N_T0_12-PadV22)")
	(net 577 "unconnected-(U4A-IO_L3P_T0_DQS_12-PadV23)")
	(net 578 "unconnected-(U4A-IO_L3N_T0_DQS_12-PadV24)")
	(net 579 "unconnected-(U4A-IO_L15P_T2_DQS_12-PadW20)")
	(net 580 "unconnected-(U4A-IO_L6N_T0_VREF_12-PadW21)")
	(net 581 "unconnected-(U4A-IO_L8P_T1_12-PadW23)")
	(net 582 "unconnected-(U14-Pad5)")
	(net 583 "unconnected-(U5-NC-Pad4)")
	(net 584 "unconnected-(U6-ADBUS4-Pad17)")
	(net 585 "unconnected-(U6-ADBUS6-Pad19)")
	(net 586 "unconnected-(U6-ADBUS7-Pad20)")
	(net 587 "unconnected-(U6-BDBUS4-Pad26)")
	(net 588 "unconnected-(U6-BDBUS6-Pad28)")
	(net 589 "unconnected-(U6-BDBUS7-Pad29)")
	(net 590 "unconnected-(U6-~{SUSPEND}-Pad30)")
	(net 591 "unconnected-(U6-CDBUS2-Pad34)")
	(net 592 "unconnected-(U6-CDBUS3-Pad35)")
	(net 593 "Net-(C133-Pad1)")
	(net 594 "/FPGA bank 16/SD.DAT1")
	(net 595 "/Supply/12V_aux_fused")
	(net 596 "/Supply/12V_PCIE_fused")
	(net 597 "/Supply/12V_aux")
	(net 598 "unconnected-(U6-CDBUS4-Pad37)")
	(net 599 "unconnected-(U6-CDBUS5-Pad38)")
	(net 600 "unconnected-(U6-CDBUS6-Pad39)")
	(net 601 "unconnected-(U6-CDBUS7-Pad40)")
	(net 602 "/Ethernet/LED_SPD")
	(net 603 "/Ethernet/LED_LINK")
	(net 604 "/FPGA MGT Interface/PCIE.RXD0_P")
	(net 605 "/FPGA MGT Interface/PCIE.RXD0_N")
	(net 606 "/FPGA MGT Interface/PCIE.RXD1_P")
	(net 607 "/FPGA MGT Interface/PCIE.RXD1_N")
	(net 608 "/FPGA MGT Interface/PCIE.RXD2_P")
	(net 609 "/FPGA MGT Interface/PCIE.RXD2_N")
	(net 610 "/FPGA MGT Interface/PCIE.RXD3_P")
	(net 611 "/FPGA MGT Interface/PCIE.RXD3_N")
	(net 612 "/FPGA bank 14/PUDC_B")
	(net 613 "/FPGA Config/DONE")
	(net 614 "/FPGA Config/INIT_B")
	(net 615 "/FPGA bank 14/USR_LED1")
	(net 616 "unconnected-(U6-DDBUS2-Pad47)")
	(net 617 "/FPGA bank 14/USR_LED3")
	(net 618 "unconnected-(U6-DDBUS3-Pad48)")
	(net 619 "/FPGA bank 14/USR_LED2")
	(net 620 "unconnected-(U6-DDBUS4-Pad49)")
	(net 621 "/FPGA bank 14/USR_LED4")
	(net 622 "/FPGA bank 14/USR_LED5")
	(net 623 "/FPGA bank 12/HyperRAM.~{RESET}")
	(net 624 "/FPGA bank 12/HyperRAM.~{CS}")
	(net 625 "/FPGA Config/FLASH.~{CS}")
	(net 626 "/FPGA Config/FLASH.IO0")
	(net 627 "/FPGA Config/FLASH.IO1")
	(net 628 "/FPGA Config/FLASH.IO2")
	(net 629 "/FPGA Config/FLASH.IO3")
	(net 630 "/FPGA Config/FLASH.SCK")
	(net 631 "/FPGA Config/MODE2")
	(net 632 "/FPGA Config/MODE1")
	(net 633 "/FPGA Config/MODE0")
	(net 634 "/FPGA Config/PROGRAM_B")
	(net 635 "/FPGA Config/CFGBVS")
	(net 636 "/DDR5 SODIMM/Control.PWR_GOOD")
	(net 637 "/DDR5 SODIMM/Control.PWR_EN")
	(net 638 "/Debug FTDI/FTDI_UART0_TX")
	(net 639 "/Debug FTDI/UART0.RX")
	(net 640 "/Debug FTDI/FTDI_UART0_RX")
	(net 641 "/Debug FTDI/UART0.TX")
	(net 642 "/Debug FTDI/FTDI_UART1_TX")
	(net 643 "/Debug FTDI/UART1.RX")
	(net 644 "/Debug FTDI/FTDI_UART1_RX")
	(net 645 "/Debug FTDI/UART1.TX")
	(net 646 "/Debug FTDI/BDBUS0")
	(net 647 "/Debug FTDI/AUX.TCK")
	(net 648 "/Debug FTDI/BDBUS1")
	(net 649 "/Debug FTDI/AUX.TDI")
	(net 650 "/Debug FTDI/BDBUS2")
	(net 651 "/Debug FTDI/AUX.TDO")
	(net 652 "/Debug FTDI/BDBUS3")
	(net 653 "/Debug FTDI/AUX.TMS")
	(net 654 "/Debug FTDI/I2C_EN")
	(net 655 "/Debug FTDI/AUX.RST")
	(net 656 "/Debug FTDI/LED_TX0")
	(net 657 "/Debug FTDI/LED_RX0")
	(net 658 "/Debug FTDI/LED_TX1")
	(net 659 "/Debug FTDI/LED_RX1")
	(net 660 "/FPGA bank 16/HDMI.D2_P")
	(net 661 "/FPGA bank 16/HDMI.D2_N")
	(net 662 "/FPGA bank 16/HDMI.D1_P")
	(net 663 "/FPGA bank 16/HDMI.D1_N")
	(net 664 "/FPGA bank 16/HDMI.D0_P")
	(net 665 "/FPGA bank 16/HDMI.D0_N")
	(net 666 "/FPGA bank 16/HDMI.CLK_P")
	(net 667 "/FPGA bank 16/HDMI.CLK_N")
	(net 668 "/Debug FTDI/FTDI_PWREN")
	(net 669 "/FPGA bank 16/SD.CD")
	(net 670 "/Debug FTDI/FTDI_SCL")
	(net 671 "/Debug FTDI/FTDI.SCL")
	(net 672 "/Debug FTDI/FTDI.SDA")
	(net 673 "/Ethernet/ETH.RXD0")
	(net 674 "/Ethernet/ETH.RXD1")
	(net 675 "/Ethernet/ETH.RXD2")
	(net 676 "/Ethernet/ETH.RXD3")
	(net 677 "/Ethernet/ETH.RX_CTL")
	(net 678 "/Ethernet/ETH.RXC")
	(net 679 "/Ethernet/ETH.REF_CLK")
	(net 680 "/Ethernet/ETH.MDIO")
	(net 681 "/Ethernet/ETH.~{RESET}")
	(net 682 "/FPGA bank 14/FPGA_DDR.SCL")
	(net 683 "/FPGA bank 14/FPGA_DDR.SDA")
	(net 684 "/FPGA banks HP/VRN")
	(net 685 "/FPGA banks HP/VRP")
	(net 686 "IN1")
	(net 687 "IN2")
	(net 688 "/FPGA bank 14/FPGA_PWR.SDA")
	(net 689 "/FPGA bank 14/FPGA_PWR.SCL")
	(net 690 "/I^{2}C/PWR.SDA")
	(net 691 "/I^{2}C/PWR.SCL")
	(net 692 "/Debug FTDI/FTDI_JTAG_RST")
	(net 693 "/FPGA bank 12/HyperRAM.CK_N")
	(net 694 "/FPGA bank 12/HyperRAM.CK_P")
	(net 695 "/FPGA bank 12/HyperRAM.RWDS")
	(net 696 "/FPGA bank 12/HyperRAM.DQ2")
	(net 697 "/FPGA bank 12/HyperRAM.DQ1")
	(net 698 "/FPGA bank 12/HyperRAM.DQ0")
	(net 699 "/FPGA bank 12/HyperRAM.DQ3")
	(net 700 "/FPGA bank 12/HyperRAM.DQ4")
	(net 701 "/FPGA bank 12/HyperRAM.DQ7")
	(net 702 "/FPGA bank 12/HyperRAM.DQ6")
	(net 703 "/FPGA bank 12/HyperRAM.DQ5")
	(net 704 "/Ethernet/ETH.TXC")
	(net 705 "/Ethernet/ETH.MDC")
	(net 706 "/FPGA bank 16/GCLK100")
	(net 707 "unconnected-(U6-DDBUS5-Pad51)")
	(net 708 "unconnected-(U6-DDBUS6-Pad52)")
	(net 709 "unconnected-(U6-DDBUS7-Pad53)")
	(net 710 "unconnected-(U7-NC-Pad6)")
	(net 711 "unconnected-(U7-NC-Pad9)")
	(net 712 "unconnected-(U9-QB-Pad1)")
	(net 713 "unconnected-(U9-QC-Pad2)")
	(net 714 "unconnected-(U9-QD-Pad3)")
	(net 715 "unconnected-(J9-3V3-PadA10)_1")
	(net 716 "unconnected-(U9-QA-Pad15)")
	(net 717 "unconnected-(U9-EP-Pad17)")
	(net 718 "unconnected-(U13-NC-Pad6)")
	(net 719 "unconnected-(U13-NC-Pad9)")
	(net 720 "unconnected-(U13-B2Y-Pad12)")
	(net 721 "unconnected-(U15-NC-Pad13)")
	(net 722 "unconnected-(U15-LDO_O-Pad43)")
	(net 723 "unconnected-(U15-NC-Pad47)")
	(net 724 "unconnected-(U17-STAT-Pad4)")
	(net 725 "unconnected-(U18-STAT-Pad4)")
	(net 726 "unconnected-(U19-SW2-Pad11)")
	(net 727 "unconnected-(U19-SW1-Pad12)")
	(net 728 "unconnected-(U20-SW2-Pad11)")
	(net 729 "unconnected-(U20-SW1-Pad12)")
	(net 730 "unconnected-(U21-NC-Pad4)")
	(net 731 "unconnected-(U25-EP-Pad17)")
	(net 732 "/Ethernet/ETH.TX_CTL")
	(net 733 "/Ethernet/ETH.TXD0")
	(net 734 "/Ethernet/ETH.~{INT}")
	(net 735 "/Ethernet/ETH.TXD3")
	(net 736 "/Ethernet/ETH.TXD2")
	(net 737 "/Ethernet/ETH.TXD1")
	(net 738 "/Debug FTDI/FTDI_EECS")
	(net 739 "/Debug FTDI/FTDI_JTAG_TCK")
	(net 740 "/Debug FTDI/FTDI_JTAG_TDI")
	(net 741 "/Debug FTDI/FTDI_JTAG_TDO")
	(net 742 "/Debug FTDI/FTDI_JTAG_TMS")
	(net 743 "unconnected-(U30-EP-Pad17)")
	(net 744 "/Debug FTDI/FTDI_EEDAT")
	(net 745 "/Debug FTDI/FTDI_EECLK")
	(net 746 "Net-(U32-B1)")
	(net 747 "Net-(U32-B2)")
	(net 748 "Net-(U33-B1)")
	(net 749 "Net-(U33-B2)")
	(net 750 "unconnected-(U4G-IO_L9N_T1_DQS_33-PadAD8)")
	(net 751 "unconnected-(U4G-IO_L20N_T3_33-PadAE10)")
	(net 752 "unconnected-(J9-3V3-PadA10)_2")
	(net 753 "unconnected-(U8-Pad5)_1")
	(net 754 "unconnected-(U8-Pad1)_1")
	(net 755 "unconnected-(U9-QH&apos;-Pad9)")
	(net 756 "unconnected-(U14-Pad5)_1")
	(net 757 "Net-(J6-LED_Y+)")
	(net 758 "Net-(J6-LED_G+)")
	(net 759 "Net-(D17-C)")
	(net 760 "Net-(D18-A)")
	(net 761 "Net-(U34-SDA)")
	(net 762 "Net-(U34-SCL)")
	(footprint "antmicro-footprints:C_0402_1005Metric"
		(layer "F.Cu")
		(at 90.690501 171.536 90)
		(descr "Capacitor SMD 0402")
		(tags "capacitor SMD 0402")
		(property "Reference" "C116"
			(at 0 -0.699 90)
			(layer "F.SilkS")
			(hide yes)
			(effects
				(font
					(size 0.7 0.7)
					(thickness 0.15)
				)
				(justify left bottom)
			)
		)
		(property "Value" "C_4u7_0402"
			(at -1.022927 2.155213 90)
			(layer "F.Fab")
			(effects
				(font
					(size 0.7 0.7)
					(thickness 0.15)
				)
				(justify left bottom)
			)
		)
		(property "Datasheet" "https://www.murata.com/products/productdetail?partno=GRM155R61A475MEAA%23"
			(at 0 0 90)
			(layer "F.Fab")
			(hide yes)
			(effects
				(font
					(size 1.27 1.27)
					(thickness 0.15)
				)
			)
		)
		(property "Author" "Antmicro"
			(at 262.226501 80.845499 0)
			(layer "F.Fab")
			(hide yes)
			(effects
				(font
					(size 1 1)
					(thickness 0.15)
				)
			)
		)
		(property "Dielectric" ""
			(at 262.226501 80.845499 0)
			(layer "F.Fab")
			(hide yes)
			(effects
				(font
					(size 1 1)
					(thickness 0.15)
				)
			)
		)
		(property "License" "Apache-2.0"
			(at 262.226501 80.845499 0)
			(layer "F.Fab")
			(hide yes)
			(effects
				(font
					(size 1 1)
					(thickness 0.15)
				)
			)
		)
		(property "MPN" "GRM155R61A475MEAAD"
			(at 262.226501 80.845499 0)
			(layer "F.Fab")
			(hide yes)
			(effects
				(font
					(size 1 1)
					(thickness 0.15)
				)
			)
		)
		(property "Manufacturer" "Murata"
			(at 262.226501 80.845499 0)
			(layer "F.Fab")
			(hide yes)
			(effects
				(font
					(size 1 1)
					(thickness 0.15)
				)
			)
		)
		(property "Val" "4u7"
			(at 262.226501 80.845499 0)
			(layer "F.Fab")
			(hide yes)
			(effects
				(font
					(size 1 1)
					(thickness 0.15)
				)
			)
		)
		(property "Voltage" ""
			(at 262.226501 80.845499 0)
			(layer "F.Fab")
			(hide yes)
			(effects
				(font
					(size 1 1)
					(thickness 0.15)
				)
			)
		)
		(sheetname "/Debug FTDI/")
		(sheetfile "debug-ftdi.kicad_sch")
		(attr smd)
		(fp_rect
			(start -0.9659 -0.481258)
			(end 0.9649 0.458742)
			(stroke
				(width 0.05)
				(type solid)
			)
			(fill no)
			(layer "F.CrtYd")
		)
		(fp_line
			(start 0.499 -0.25)
			(end 0.499 0.248)
			(stroke
				(width 0.15)
				(type solid)
			)
			(layer "F.Fab")
		)
		(fp_line
			(start -0.499 -0.25)
			(end 0.499 -0.25)
			(stroke
				(width 0.15)
				(type solid)
			)
			(layer "F.Fab")
		)
		(fp_line
			(start 0.499 0.248)
			(end -0.499 0.248)
			(stroke
				(width 0.15)
				(type solid)
			)
			(layer "F.Fab")
		)
		(fp_line
			(start -0.499 0.248)
			(end -0.499 -0.25)
			(stroke
				(width 0.15)
				(type solid)
			)
			(layer "F.Fab")
		)
		(pad "1" smd roundrect
			(at -0.484 0 90)
			(size 0.59 0.64)
			(layers "F.Cu" "F.Mask" "F.Paste")
			(roundrect_rratio 0.25)
			(net 5 "/Debug FTDI/FTDI_VPHY")
			(pintype "passive")
		)
		(pad "2" smd roundrect
			(at 0.484 0 90)
			(size 0.59 0.64)
			(layers "F.Cu" "F.Mask" "F.Paste")
			(roundrect_rratio 0.25)
			(net 1 "GND")
			(pintype "passive")
		)
	)
	(footprint "antmicro-footprints:C_0402_1005Metric"
		(layer "F.Cu")
		(at 95.272344 167.552328 90)
		(descr "Capacitor SMD 0402")
		(tags "capacitor SMD 0402")
		(property "Reference" "C123"
			(at 0 -0.699 90)
			(layer "F.SilkS")
			(hide yes)
			(effects
				(font
					(size 0.7 0.7)
					(thickness 0.15)
				)
				(justify left bottom)
			)
		)
		(property "Value" "C_100n_0402"
			(at -1.022927 2.155213 90)
			(layer "F.Fab")
			(effects
				(font
					(size 0.7 0.7)
					(thickness 0.15)
				)
				(justify left bottom)
			)
		)
		(property "Datasheet" "https://www.murata.com/products/productdetail?partno=GRM155R61H104KE14%23"
			(at 0 0 90)
			(layer "F.Fab")
			(hide yes)
			(effects
				(font
					(size 1.27 1.27)
					(thickness 0.15)
				)
			)
		)
		(property "Author" "Antmicro"
			(at 262.824672 72.279984 0)
			(layer "F.Fab")
			(hide yes)
			(effects
				(font
					(size 1 1)
					(thickness 0.15)
				)
			)
		)
		(property "Dielectric" "X5R"
			(at 262.824672 72.279984 0)
			(layer "F.Fab")
			(hide yes)
			(effects
				(font
					(size 1 1)
					(thickness 0.15)
				)
			)
		)
		(property "License" "Apache-2.0"
			(at 262.824672 72.279984 0)
			(layer "F.Fab")
			(hide yes)
			(effects
				(font
					(size 1 1)
					(thickness 0.15)
				)
			)
		)
		(property "MPN" "GRM155R61H104KE14D"
			(at 262.824672 72.279984 0)
			(layer "F.Fab")
			(hide yes)
			(effects
				(font
					(size 1 1)
					(thickness 0.15)
				)
			)
		)
		(property "Manufacturer" "Murata"
			(at 262.824672 72.279984 0)
			(layer "F.Fab")
			(hide yes)
			(effects
				(font
					(size 1 1)
					(thickness 0.15)
				)
			)
		)
		(property "Val" "100n"
			(at 262.824672 72.279984 0)
			(layer "F.Fab")
			(hide yes)
			(effects
				(font
					(size 1 1)
					(thickness 0.15)
				)
			)
		)
		(property "Voltage" "50V"
			(at 262.824672 72.279984 0)
			(layer "F.Fab")
			(hide yes)
			(effects
				(font
					(size 1 1)
					(thickness 0.15)
				)
			)
		)
		(sheetname "/Debug FTDI/")
		(sheetfile "debug-ftdi.kicad_sch")
		(attr smd)
		(fp_rect
			(start -0.9659 -0.481258)
			(end 0.9649 0.458742)
			(stroke
				(width 0.05)
				(type solid)
			)
			(fill no)
			(layer "F.CrtYd")
		)
		(fp_line
			(start 0.499 -0.25)
			(end 0.499 0.248)
			(stroke
				(width 0.15)
				(type solid)
			)
			(layer "F.Fab")
		)
		(fp_line
			(start -0.499 -0.25)
			(end 0.499 -0.25)
			(stroke
				(width 0.15)
				(type solid)
			)
			(layer "F.Fab")
		)
		(fp_line
			(start 0.499 0.248)
			(end -0.499 0.248)
			(stroke
				(width 0.15)
				(type solid)
			)
			(layer "F.Fab")
		)
		(fp_line
			(start -0.499 0.248)
			(end -0.499 -0.25)
			(stroke
				(width 0.15)
				(type solid)
			)
			(layer "F.Fab")
		)
		(pad "1" smd roundrect
			(at -0.484 0 90)
			(size 0.59 0.64)
			(layers "F.Cu" "F.Mask" "F.Paste")
			(roundrect_rratio 0.25)
			(net 8 "/Debug FTDI/FTDI_VCORE")
			(pintype "passive")
		)
		(pad "2" smd roundrect
			(at 0.484 0 90)
			(size 0.59 0.64)
			(layers "F.Cu" "F.Mask" "F.Paste")
			(roundrect_rratio 0.25)
			(net 1 "GND")
			(pintype "passive")
		)
	)
	(footprint "antmicro-footprints:Resonator_SMD_Abracon_ABM8G_3.2x2.5mm"
		(layer "F.Cu")
		(at 91.898501 166.925 90)
		(property "Reference" "Y1"
			(at -1.75 -1.75 270)
			(layer "F.SilkS")
			(effects
				(font
					(size 0.7 0.7)
					(thickness 0.15)
				)
				(justify left bottom)
			)
		)
		(property "Value" "Resonator_12MHz_ABM8G"
			(at -1.75 2.548 90)
			(layer "F.Fab")
			(effects
				(font
					(size 0.7 0.7)
					(thickness 0.15)
				)
				(justify left bottom)
			)
		)
		(property "Datasheet" "https://abracon.com/Resonators/ABM8G.pdf"
			(at 0 0 90)
			(layer "F.Fab")
			(hide yes)
			(effects
				(font
					(size 1.27 1.27)
					(thickness 0.15)
				)
			)
		)
		(property "Author" "Antmicro"
			(at 258.823501 75.026499 0)
			(layer "F.Fab")
			(hide yes)
			(effects
				(font
					(size 1 1)
					(thickness 0.15)
				)
			)
		)
		(property "License" "Apache-2.0"
			(at 258.823501 75.026499 0)
			(layer "F.Fab")
			(hide yes)
			(effects
				(font
					(size 1 1)
					(thickness 0.15)
				)
			)
		)
		(property "MPN" "ABM8G-12.000MHZ-18-D2Y-T"
			(at 258.823501 75.026499 0)
			(layer "F.Fab")
			(hide yes)
			(effects
				(font
					(size 1 1)
					(thickness 0.15)
				)
			)
		)
		(property "Manufacturer" "Abracon"
			(at 258.823501 75.026499 0)
			(layer "F.Fab")
			(hide yes)
			(effects
				(font
					(size 1 1)
					(thickness 0.15)
				)
			)
		)
		(property "Val" "12 MHz"
			(at 258.823501 75.026499 0)
			(layer "F.Fab")
			(hide yes)
			(effects
				(font
					(size 1 1)
					(thickness 0.15)
				)
			)
		)
		(sheetname "/Debug FTDI/")
		(sheetfile "debug-ftdi.kicad_sch")
		(attr smd)
		(fp_line
			(start -0.35 -1.25)
			(end 0.45 -1.25)
			(stroke
				(width 0.15)
				(type solid)
			)
			(layer "F.SilkS")
		)
		(fp_line
			(start 1.6 0.3)
			(end 1.6 -0.2)
			(stroke
				(width 0.15)
				(type solid)
			)
			(layer "F.SilkS")
		)
		(fp_line
			(start -1.6 0.3)
			(end -1.6 -0.2)
			(stroke
				(width 0.15)
				(type solid)
			)
			(layer "F.SilkS")
		)
		(fp_line
			(start -0.35 1.25)
			(end 0.45 1.25)
			(stroke
				(width 0.15)
				(type solid)
			)
			(layer "F.SilkS")
		)
		(fp_circle
			(center -1.75 1.5)
			(end -1.7 1.5)
			(stroke
				(width 0.15)
				(type solid)
			)
			(fill no)
			(layer "F.SilkS")
		)
		(fp_rect
			(start -1.907 -1.55)
			(end 2.006 1.649)
			(stroke
				(width 0.05)
				(type solid)
			)
			(fill no)
			(layer "F.CrtYd")
		)
		(pad "1" smd roundrect
			(at -1.101 0.949 90)
			(size 1.3 1.1)
			(layers "F.Cu" "F.Mask" "F.Paste")
			(roundrect_rratio 0)
			(chamfer_ratio 0.2)
			(chamfer bottom_left)
			(net 4 "/Debug FTDI/FTDI_XI")
			(pintype "passive")
		)
		(pad "2" smd rect
			(at 1.199 0.949 90)
			(size 1.3 1.1)
			(layers "F.Cu" "F.Mask" "F.Paste")
			(net 1 "GND")
			(pinfunction "SH")
			(pintype "passive")
		)
		(pad "3" smd rect
			(at 1.199 -0.85 90)
			(size 1.3 1.1)
			(layers "F.Cu" "F.Mask" "F.Paste")
			(net 7 "/Debug FTDI/FTDI_XO")
			(pintype "passive")
		)
		(pad "4" smd rect
			(at -1.101 -0.85 90)
			(size 1.3 1.1)
			(layers "F.Cu" "F.Mask" "F.Paste")
			(net 1 "GND")
			(pinfunction "SH")
			(pintype "passive")
		)
	)
	(footprint "antmicro-footprints:R_0402_1005Metric"
		(layer "F.Cu")
		(at 106.775 175.02)
		(descr "Resistor SMD 0402")
		(tags "resistor SMD 0402")
		(property "Reference" "R52"
			(at -1.122484 -0.772697 0)
			(layer "F.SilkS")
			(hide yes)
			(effects
				(font
					(size 0.7 0.7)
					(thickness 0.15)
				)
				(justify left bottom)
			)
		)
		(property "Value" "R_22R_0402"
			(at -1.011843 1.772047 0)
			(layer "F.Fab")
			(effects
				(font
					(size 0.7 0.7)
					(thickness 0.15)
				)
				(justify left bottom)
			)
		)
		(property "Datasheet" "https://www.bourns.com/docs/product-datasheets/cr.pdf"
			(at 0 0 0)
			(layer "F.Fab")
			(hide yes)
			(effects
				(font
					(size 1.27 1.27)
					(thickness 0.15)
				)
			)
		)
		(property "Author" "Antmicro"
			(at 0 0 0)
			(layer "F.Fab")
			(hide yes)
			(effects
				(font
					(size 1 1)
					(thickness 0.15)
				)
			)
		)
		(property "License" "Apache-2.0"
			(at 0 0 0)
			(layer "F.Fab")
			(hide yes)
			(effects
				(font
					(size 1 1)
					(thickness 0.15)
				)
			)
		)
		(property "MPN" "CR0402-FX-22R0GLF"
			(at 0 0 0)
			(layer "F.Fab")
			(hide yes)
			(effects
				(font
					(size 1 1)
					(thickness 0.15)
				)
			)
		)
		(property "Manufacturer" "Bourns"
			(at 0 0 0)
			(layer "F.Fab")
			(hide yes)
			(effects
				(font
					(size 1 1)
					(thickness 0.15)
				)
			)
		)
		(property "Tolerance" "1%"
			(at 0 0 0)
			(layer "F.Fab")
			(hide yes)
			(effects
				(font
					(size 1 1)
					(thickness 0.15)
				)
			)
		)
		(property "Val" "22R"
			(at 0 0 0)
			(layer "F.Fab")
			(hide yes)
			(effects
				(font
					(size 1 1)
					(thickness 0.15)
				)
			)
		)
		(sheetname "/Debug FTDI/")
		(sheetfile "debug-ftdi.kicad_sch")
		(attr smd)
		(fp_rect
			(start -0.93 -0.47)
			(end 0.93 0.47)
			(stroke
				(width 0.05)
				(type solid)
			)
			(fill no)
			(layer "F.CrtYd")
		)
		(fp_rect
			(start -0.5 -0.25)
			(end 0.5 0.25)
			(stroke
				(width 0.15)
				(type solid)
			)
			(fill no)
			(layer "F.Fab")
		)
		(pad "1" smd roundrect
			(at -0.485 0)
			(size 0.59 0.64)
			(layers "F.Cu" "F.Mask" "F.Paste")
			(roundrect_rratio 0.25)
			(net 746 "Net-(U32-B1)")
			(pintype "passive")
		)
		(pad "2" smd roundrect
			(at 0.485 0)
			(size 0.59 0.64)
			(layers "F.Cu" "F.Mask" "F.Paste")
			(roundrect_rratio 0.25)
			(net 641 "/Debug FTDI/UART0.TX")
			(pintype "passive")
		)
	)
	(footprint "antmicro-footprints:R_0402_1005Metric"
		(layer "F.Cu")
		(at 106.775 176.045)
		(descr "Resistor SMD 0402")
		(tags "resistor SMD 0402")
		(property "Reference" "R53"
			(at -1.122484 -0.772697 0)
			(layer "F.SilkS")
			(hide yes)
			(effects
				(font
					(size 0.7 0.7)
					(thickness 0.15)
				)
				(justify left bottom)
			)
		)
		(property "Value" "R_22R_0402"
			(at -1.011843 1.772047 0)
			(layer "F.Fab")
			(effects
				(font
					(size 0.7 0.7)
					(thickness 0.15)
				)
				(justify left bottom)
			)
		)
		(property "Datasheet" "https://www.bourns.com/docs/product-datasheets/cr.pdf"
			(at 0 0 0)
			(layer "F.Fab")
			(hide yes)
			(effects
				(font
					(size 1.27 1.27)
					(thickness 0.15)
				)
			)
		)
		(property "Author" "Antmicro"
			(at 0 0 0)
			(layer "F.Fab")
			(hide yes)
			(effects
				(font
					(size 1 1)
					(thickness 0.15)
				)
			)
		)
		(property "License" "Apache-2.0"
			(at 0 0 0)
			(layer "F.Fab")
			(hide yes)
			(effects
				(font
					(size 1 1)
					(thickness 0.15)
				)
			)
		)
		(property "MPN" "CR0402-FX-22R0GLF"
			(at 0 0 0)
			(layer "F.Fab")
			(hide yes)
			(effects
				(font
					(size 1 1)
					(thickness 0.15)
				)
			)
		)
		(property "Manufacturer" "Bourns"
			(at 0 0 0)
			(layer "F.Fab")
			(hide yes)
			(effects
				(font
					(size 1 1)
					(thickness 0.15)
				)
			)
		)
		(property "Tolerance" "1%"
			(at 0 0 0)
			(layer "F.Fab")
			(hide yes)
			(effects
				(font
					(size 1 1)
					(thickness 0.15)
				)
			)
		)
		(property "Val" "22R"
			(at 0 0 0)
			(layer "F.Fab")
			(hide yes)
			(effects
				(font
					(size 1 1)
					(thickness 0.15)
				)
			)
		)
		(sheetname "/Debug FTDI/")
		(sheetfile "debug-ftdi.kicad_sch")
		(attr smd)
		(fp_rect
			(start -0.93 -0.47)
			(end 0.93 0.47)
			(stroke
				(width 0.05)
				(type solid)
			)
			(fill no)
			(layer "F.CrtYd")
		)
		(fp_rect
			(start -0.5 -0.25)
			(end 0.5 0.25)
			(stroke
				(width 0.15)
				(type solid)
			)
			(fill no)
			(layer "F.Fab")
		)
		(pad "1" smd roundrect
			(at -0.485 0)
			(size 0.59 0.64)
			(layers "F.Cu" "F.Mask" "F.Paste")
			(roundrect_rratio 0.25)
			(net 747 "Net-(U32-B2)")
			(pintype "passive")
		)
		(pad "2" smd roundrect
			(at 0.485 0)
			(size 0.59 0.64)
			(layers "F.Cu" "F.Mask" "F.Paste")
			(roundrect_rratio 0.25)
			(net 639 "/Debug FTDI/UART0.RX")
			(pintype "passive")
		)
	)
	(footprint "antmicro-footprints:R_0402_1005Metric"
		(layer "F.Cu")
		(at 106.78 171.26)
		(descr "Resistor SMD 0402")
		(tags "resistor SMD 0402")
		(property "Reference" "R54"
			(at -1.122484 -0.772697 0)
			(layer "F.SilkS")
			(hide yes)
			(effects
				(font
					(size 0.7 0.7)
					(thickness 0.15)
				)
				(justify left bottom)
			)
		)
		(property "Value" "R_22R_0402"
			(at -1.011843 1.772047 0)
			(layer "F.Fab")
			(effects
				(font
					(size 0.7 0.7)
					(thickness 0.15)
				)
				(justify left bottom)
			)
		)
		(property "Datasheet" "https://www.bourns.com/docs/product-datasheets/cr.pdf"
			(at 0 0 0)
			(layer "F.Fab")
			(hide yes)
			(effects
				(font
					(size 1.27 1.27)
					(thickness 0.15)
				)
			)
		)
		(property "Author" "Antmicro"
			(at 0 0 0)
			(layer "F.Fab")
			(hide yes)
			(effects
				(font
					(size 1 1)
					(thickness 0.15)
				)
			)
		)
		(property "License" "Apache-2.0"
			(at 0 0 0)
			(layer "F.Fab")
			(hide yes)
			(effects
				(font
					(size 1 1)
					(thickness 0.15)
				)
			)
		)
		(property "MPN" "CR0402-FX-22R0GLF"
			(at 0 0 0)
			(layer "F.Fab")
			(hide yes)
			(effects
				(font
					(size 1 1)
					(thickness 0.15)
				)
			)
		)
		(property "Manufacturer" "Bourns"
			(at 0 0 0)
			(layer "F.Fab")
			(hide yes)
			(effects
				(font
					(size 1 1)
					(thickness 0.15)
				)
			)
		)
		(property "Tolerance" "1%"
			(at 0 0 0)
			(layer "F.Fab")
			(hide yes)
			(effects
				(font
					(size 1 1)
					(thickness 0.15)
				)
			)
		)
		(property "Val" "22R"
			(at 0 0 0)
			(layer "F.Fab")
			(hide yes)
			(effects
				(font
					(size 1 1)
					(thickness 0.15)
				)
			)
		)
		(sheetname "/Debug FTDI/")
		(sheetfile "debug-ftdi.kicad_sch")
		(attr smd)
		(fp_rect
			(start -0.93 -0.47)
			(end 0.93 0.47)
			(stroke
				(width 0.05)
				(type solid)
			)
			(fill no)
			(layer "F.CrtYd")
		)
		(fp_rect
			(start -0.5 -0.25)
			(end 0.5 0.25)
			(stroke
				(width 0.15)
				(type solid)
			)
			(fill no)
			(layer "F.Fab")
		)
		(pad "1" smd roundrect
			(at -0.485 0)
			(size 0.59 0.64)
			(layers "F.Cu" "F.Mask" "F.Paste")
			(roundrect_rratio 0.25)
			(net 748 "Net-(U33-B1)")
			(pintype "passive")
		)
		(pad "2" smd roundrect
			(at 0.485 0)
			(size 0.59 0.64)
			(layers "F.Cu" "F.Mask" "F.Paste")
			(roundrect_rratio 0.25)
			(net 645 "/Debug FTDI/UART1.TX")
			(pintype "passive")
		)
	)
	(footprint "antmicro-footprints:R_0402_1005Metric"
		(layer "F.Cu")
		(at 106.78 172.26)
		(descr "Resistor SMD 0402")
		(tags "resistor SMD 0402")
		(property "Reference" "R55"
			(at -1.122484 -0.772697 0)
			(layer "F.SilkS")
			(hide yes)
			(effects
				(font
					(size 0.7 0.7)
					(thickness 0.15)
				)
				(justify left bottom)
			)
		)
		(property "Value" "R_22R_0402"
			(at -1.011843 1.772047 0)
			(layer "F.Fab")
			(effects
				(font
					(size 0.7 0.7)
					(thickness 0.15)
				)
				(justify left bottom)
			)
		)
		(property "Datasheet" "https://www.bourns.com/docs/product-datasheets/cr.pdf"
			(at 0 0 0)
			(layer "F.Fab")
			(hide yes)
			(effects
				(font
					(size 1.27 1.27)
					(thickness 0.15)
				)
			)
		)
		(property "Author" "Antmicro"
			(at 0 0 0)
			(layer "F.Fab")
			(hide yes)
			(effects
				(font
					(size 1 1)
					(thickness 0.15)
				)
			)
		)
		(property "License" "Apache-2.0"
			(at 0 0 0)
			(layer "F.Fab")
			(hide yes)
			(effects
				(font
					(size 1 1)
					(thickness 0.15)
				)
			)
		)
		(property "MPN" "CR0402-FX-22R0GLF"
			(at 0 0 0)
			(layer "F.Fab")
			(hide yes)
			(effects
				(font
					(size 1 1)
					(thickness 0.15)
				)
			)
		)
		(property "Manufacturer" "Bourns"
			(at 0 0 0)
			(layer "F.Fab")
			(hide yes)
			(effects
				(font
					(size 1 1)
					(thickness 0.15)
				)
			)
		)
		(property "Tolerance" "1%"
			(at 0 0 0)
			(layer "F.Fab")
			(hide yes)
			(effects
				(font
					(size 1 1)
					(thickness 0.15)
				)
			)
		)
		(property "Val" "22R"
			(at 0 0 0)
			(layer "F.Fab")
			(hide yes)
			(effects
				(font
					(size 1 1)
					(thickness 0.15)
				)
			)
		)
		(sheetname "/Debug FTDI/")
		(sheetfile "debug-ftdi.kicad_sch")
		(attr smd)
		(fp_rect
			(start -0.93 -0.47)
			(end 0.93 0.47)
			(stroke
				(width 0.05)
				(type solid)
			)
			(fill no)
			(layer "F.CrtYd")
		)
		(fp_rect
			(start -0.5 -0.25)
			(end 0.5 0.25)
			(stroke
				(width 0.15)
				(type solid)
			)
			(fill no)
			(layer "F.Fab")
		)
		(pad "1" smd roundrect
			(at -0.485 0)
			(size 0.59 0.64)
			(layers "F.Cu" "F.Mask" "F.Paste")
			(roundrect_rratio 0.25)
			(net 749 "Net-(U33-B2)")
			(pintype "passive")
		)
		(pad "2" smd roundrect
			(at 0.485 0)
			(size 0.59 0.64)
			(layers "F.Cu" "F.Mask" "F.Paste")
			(roundrect_rratio 0.25)
			(net 643 "/Debug FTDI/UART1.RX")
			(pintype "passive")
		)
	)
	(footprint "antmicro-footprints:R_0402_1005Metric"
		(layer "F.Cu")
		(at 94.5 184.6 -90)
		(descr "Resistor SMD 0402")
		(tags "resistor SMD 0402")
		(property "Reference" "R48"
			(at -1.122484 -0.772697 270)
			(layer "F.SilkS")
			(hide yes)
			(effects
				(font
					(size 0.7 0.7)
					(thickness 0.15)
				)
				(justify left bottom)
			)
		)
		(property "Value" "R_22R_0402"
			(at -1.011843 1.772047 270)
			(layer "F.Fab")
			(effects
				(font
					(size 0.7 0.7)
					(thickness 0.15)
				)
				(justify left bottom)
			)
		)
		(property "Datasheet" "https://www.bourns.com/docs/product-datasheets/cr.pdf"
			(at 0 0 270)
			(layer "F.Fab")
			(hide yes)
			(effects
				(font
					(size 1.27 1.27)
					(thickness 0.15)
				)
			)
		)
		(property "Author" "Antmicro"
			(at -90.1 279.1 0)
			(layer "F.Fab")
			(hide yes)
			(effects
				(font
					(size 1 1)
					(thickness 0.15)
				)
			)
		)
		(property "License" "Apache-2.0"
			(at -90.1 279.1 0)
			(layer "F.Fab")
			(hide yes)
			(effects
				(font
					(size 1 1)
					(thickness 0.15)
				)
			)
		)
		(property "MPN" "CR0402-FX-22R0GLF"
			(at -90.1 279.1 0)
			(layer "F.Fab")
			(hide yes)
			(effects
				(font
					(size 1 1)
					(thickness 0.15)
				)
			)
		)
		(property "Manufacturer" "Bourns"
			(at -90.1 279.1 0)
			(layer "F.Fab")
			(hide yes)
			(effects
				(font
					(size 1 1)
					(thickness 0.15)
				)
			)
		)
		(property "Tolerance" "1%"
			(at -90.1 279.1 0)
			(layer "F.Fab")
			(hide yes)
			(effects
				(font
					(size 1 1)
					(thickness 0.15)
				)
			)
		)
		(property "Val" "22R"
			(at -90.1 279.1 0)
			(layer "F.Fab")
			(hide yes)
			(effects
				(font
					(size 1 1)
					(thickness 0.15)
				)
			)
		)
		(sheetname "/Debug FTDI/")
		(sheetfile "debug-ftdi.kicad_sch")
		(attr smd)
		(fp_rect
			(start -0.93 -0.47)
			(end 0.93 0.47)
			(stroke
				(width 0.05)
				(type solid)
			)
			(fill no)
			(layer "F.CrtYd")
		)
		(fp_rect
			(start -0.5 -0.25)
			(end 0.5 0.25)
			(stroke
				(width 0.15)
				(type solid)
			)
			(fill no)
			(layer "F.Fab")
		)
		(pad "1" smd roundrect
			(at -0.485 0 270)
			(size 0.59 0.64)
			(layers "F.Cu" "F.Mask" "F.Paste")
			(roundrect_rratio 0.25)
			(net 380 "Net-(U7-B2Y)")
			(pintype "passive")
		)
		(pad "2" smd roundrect
			(at 0.485 0 270)
			(size 0.59 0.64)
			(layers "F.Cu" "F.Mask" "F.Paste")
			(roundrect_rratio 0.25)
			(net 46 "/Debug FTDI/JTAG.TCK")
			(pintype "passive")
		)
	)
	(footprint "antmicro-footprints:R_0402_1005Metric"
		(layer "F.Cu")
		(at 92.3 184.6 -90)
		(descr "Resistor SMD 0402")
		(tags "resistor SMD 0402")
		(property "Reference" "R50"
			(at -1.122484 -0.772697 270)
			(layer "F.SilkS")
			(hide yes)
			(effects
				(font
					(size 0.7 0.7)
					(thickness 0.15)
				)
				(justify left bottom)
			)
		)
		(property "Value" "R_22R_0402"
			(at -1.011843 1.772047 270)
			(layer "F.Fab")
			(effects
				(font
					(size 0.7 0.7)
					(thickness 0.15)
				)
				(justify left bottom)
			)
		)
		(property "Datasheet" "https://www.bourns.com/docs/product-datasheets/cr.pdf"
			(at 0 0 270)
			(layer "F.Fab")
			(hide yes)
			(effects
				(font
					(size 1.27 1.27)
					(thickness 0.15)
				)
			)
		)
		(property "Author" "Antmicro"
			(at -92.3 276.9 0)
			(layer "F.Fab")
			(hide yes)
			(effects
				(font
					(size 1 1)
					(thickness 0.15)
				)
			)
		)
		(property "License" "Apache-2.0"
			(at -92.3 276.9 0)
			(layer "F.Fab")
			(hide yes)
			(effects
				(font
					(size 1 1)
					(thickness 0.15)
				)
			)
		)
		(property "MPN" "CR0402-FX-22R0GLF"
			(at -92.3 276.9 0)
			(layer "F.Fab")
			(hide yes)
			(effects
				(font
					(size 1 1)
					(thickness 0.15)
				)
			)
		)
		(property "Manufacturer" "Bourns"
			(at -92.3 276.9 0)
			(layer "F.Fab")
			(hide yes)
			(effects
				(font
					(size 1 1)
					(thickness 0.15)
				)
			)
		)
		(property "Tolerance" "1%"
			(at -92.3 276.9 0)
			(layer "F.Fab")
			(hide yes)
			(effects
				(font
					(size 1 1)
					(thickness 0.15)
				)
			)
		)
		(property "Val" "22R"
			(at -92.3 276.9 0)
			(layer "F.Fab")
			(hide yes)
			(effects
				(font
					(size 1 1)
					(thickness 0.15)
				)
			)
		)
		(sheetname "/Debug FTDI/")
		(sheetfile "debug-ftdi.kicad_sch")
		(attr smd)
		(fp_rect
			(start -0.93 -0.47)
			(end 0.93 0.47)
			(stroke
				(width 0.05)
				(type solid)
			)
			(fill no)
			(layer "F.CrtYd")
		)
		(fp_rect
			(start -0.5 -0.25)
			(end 0.5 0.25)
			(stroke
				(width 0.15)
				(type solid)
			)
			(fill no)
			(layer "F.Fab")
		)
		(pad "1" smd roundrect
			(at -0.485 0 270)
			(size 0.59 0.64)
			(layers "F.Cu" "F.Mask" "F.Paste")
			(roundrect_rratio 0.25)
			(net 382 "Net-(U7-B4)")
			(pintype "passive")
		)
		(pad "2" smd roundrect
			(at 0.485 0 270)
			(size 0.59 0.64)
			(layers "F.Cu" "F.Mask" "F.Paste")
			(roundrect_rratio 0.25)
			(net 47 "/Debug FTDI/JTAG.TDO")
			(pintype "passive")
		)
	)
	(footprint "antmicro-footprints:R_0402_1005Metric"
		(layer "F.Cu")
		(at 93.422843 184.598328 -90)
		(descr "Resistor SMD 0402")
		(tags "resistor SMD 0402")
		(property "Reference" "R49"
			(at -1.122484 -0.772697 270)
			(layer "F.SilkS")
			(hide yes)
			(effects
				(font
					(size 0.7 0.7)
					(thickness 0.15)
				)
				(justify left bottom)
			)
		)
		(property "Value" "R_22R_0402"
			(at -1.011843 1.772047 270)
			(layer "F.Fab")
			(effects
				(font
					(size 0.7 0.7)
					(thickness 0.15)
				)
				(justify left bottom)
			)
		)
		(property "Datasheet" "https://www.bourns.com/docs/product-datasheets/cr.pdf"
			(at 0 0 270)
			(layer "F.Fab")
			(hide yes)
			(effects
				(font
					(size 1.27 1.27)
					(thickness 0.15)
				)
			)
		)
		(property "Author" "Antmicro"
			(at -91.175485 278.021171 0)
			(layer "F.Fab")
			(hide yes)
			(effects
				(font
					(size 1 1)
					(thickness 0.15)
				)
			)
		)
		(property "License" "Apache-2.0"
			(at -91.175485 278.021171 0)
			(layer "F.Fab")
			(hide yes)
			(effects
				(font
					(size 1 1)
					(thickness 0.15)
				)
			)
		)
		(property "MPN" "CR0402-FX-22R0GLF"
			(at -91.175485 278.021171 0)
			(layer "F.Fab")
			(hide yes)
			(effects
				(font
					(size 1 1)
					(thickness 0.15)
				)
			)
		)
		(property "Manufacturer" "Bourns"
			(at -91.175485 278.021171 0)
			(layer "F.Fab")
			(hide yes)
			(effects
				(font
					(size 1 1)
					(thickness 0.15)
				)
			)
		)
		(property "Tolerance" "1%"
			(at -91.175485 278.021171 0)
			(layer "F.Fab")
			(hide yes)
			(effects
				(font
					(size 1 1)
					(thickness 0.15)
				)
			)
		)
		(property "Val" "22R"
			(at -91.175485 278.021171 0)
			(layer "F.Fab")
			(hide yes)
			(effects
				(font
					(size 1 1)
					(thickness 0.15)
				)
			)
		)
		(sheetname "/Debug FTDI/")
		(sheetfile "debug-ftdi.kicad_sch")
		(attr smd)
		(fp_rect
			(start -0.93 -0.47)
			(end 0.93 0.47)
			(stroke
				(width 0.05)
				(type solid)
			)
			(fill no)
			(layer "F.CrtYd")
		)
		(fp_rect
			(start -0.5 -0.25)
			(end 0.5 0.25)
			(stroke
				(width 0.15)
				(type solid)
			)
			(fill no)
			(layer "F.Fab")
		)
		(pad "1" smd roundrect
			(at -0.485 0 270)
			(size 0.59 0.64)
			(layers "F.Cu" "F.Mask" "F.Paste")
			(roundrect_rratio 0.25)
			(net 381 "Net-(U7-B3Y)")
			(pintype "passive")
		)
		(pad "2" smd roundrect
			(at 0.485 0 270)
			(size 0.59 0.64)
			(layers "F.Cu" "F.Mask" "F.Paste")
			(roundrect_rratio 0.25)
			(net 48 "/Debug FTDI/JTAG.TDI")
			(pintype "passive")
		)
	)
	(footprint "antmicro-footprints:R_0402_1005Metric"
		(layer "F.Cu")
		(at 95.6 184.6 -90)
		(descr "Resistor SMD 0402")
		(tags "resistor SMD 0402")
		(property "Reference" "R47"
			(at -1.122484 -0.772697 270)
			(layer "F.SilkS")
			(hide yes)
			(effects
				(font
					(size 0.7 0.7)
					(thickness 0.15)
				)
				(justify left bottom)
			)
		)
		(property "Value" "R_22R_0402"
			(at -1.011843 1.772047 270)
			(layer "F.Fab")
			(effects
				(font
					(size 0.7 0.7)
					(thickness 0.15)
				)
				(justify left bottom)
			)
		)
		(property "Datasheet" "https://www.bourns.com/docs/product-datasheets/cr.pdf"
			(at 0 0 270)
			(layer "F.Fab")
			(hide yes)
			(effects
				(font
					(size 1.27 1.27)
					(thickness 0.15)
				)
			)
		)
		(property "Author" "Antmicro"
			(at -89 280.2 0)
			(layer "F.Fab")
			(hide yes)
			(effects
				(font
					(size 1 1)
					(thickness 0.15)
				)
			)
		)
		(property "License" "Apache-2.0"
			(at -89 280.2 0)
			(layer "F.Fab")
			(hide yes)
			(effects
				(font
					(size 1 1)
					(thickness 0.15)
				)
			)
		)
		(property "MPN" "CR0402-FX-22R0GLF"
			(at -89 280.2 0)
			(layer "F.Fab")
			(hide yes)
			(effects
				(font
					(size 1 1)
					(thickness 0.15)
				)
			)
		)
		(property "Manufacturer" "Bourns"
			(at -89 280.2 0)
			(layer "F.Fab")
			(hide yes)
			(effects
				(font
					(size 1 1)
					(thickness 0.15)
				)
			)
		)
		(property "Tolerance" "1%"
			(at -89 280.2 0)
			(layer "F.Fab")
			(hide yes)
			(effects
				(font
					(size 1 1)
					(thickness 0.15)
				)
			)
		)
		(property "Val" "22R"
			(at -89 280.2 0)
			(layer "F.Fab")
			(hide yes)
			(effects
				(font
					(size 1 1)
					(thickness 0.15)
				)
			)
		)
		(sheetname "/Debug FTDI/")
		(sheetfile "debug-ftdi.kicad_sch")
		(attr smd)
		(fp_rect
			(start -0.93 -0.47)
			(end 0.93 0.47)
			(stroke
				(width 0.05)
				(type solid)
			)
			(fill no)
			(layer "F.CrtYd")
		)
		(fp_rect
			(start -0.5 -0.25)
			(end 0.5 0.25)
			(stroke
				(width 0.15)
				(type solid)
			)
			(fill no)
			(layer "F.Fab")
		)
		(pad "1" smd roundrect
			(at -0.485 0 270)
			(size 0.59 0.64)
			(layers "F.Cu" "F.Mask" "F.Paste")
			(roundrect_rratio 0.25)
			(net 378 "Net-(U7-B1Y)")
			(pintype "passive")
		)
		(pad "2" smd roundrect
			(at 0.485 0 270)
			(size 0.59 0.64)
			(layers "F.Cu" "F.Mask" "F.Paste")
			(roundrect_rratio 0.25)
			(net 45 "/Debug FTDI/JTAG.TMS")
			(pintype "passive")
		)
	)
	(footprint "antmicro-footprints:C_0402_1005Metric"
		(layer "F.Cu")
		(at 97.272344 167.552328 90)
		(descr "Capacitor SMD 0402")
		(tags "capacitor SMD 0402")
		(property "Reference" "C115"
			(at 0 -0.699 90)
			(layer "F.SilkS")
			(hide yes)
			(effects
				(font
					(size 0.7 0.7)
					(thickness 0.15)
				)
				(justify left bottom)
			)
		)
		(property "Value" "C_100n_0402"
			(at -1.022927 2.155213 90)
			(layer "F.Fab")
			(effects
				(font
					(size 0.7 0.7)
					(thickness 0.15)
				)
				(justify left bottom)
			)
		)
		(property "Datasheet" "https://www.murata.com/products/productdetail?partno=GRM155R61H104KE14%23"
			(at 0 0 90)
			(layer "F.Fab")
			(hide yes)
			(effects
				(font
					(size 1.27 1.27)
					(thickness 0.15)
				)
			)
		)
		(property "Author" "Antmicro"
			(at 264.824672 70.279984 0)
			(layer "F.Fab")
			(hide yes)
			(effects
				(font
					(size 1 1)
					(thickness 0.15)
				)
			)
		)
		(property "Dielectric" "X5R"
			(at 264.824672 70.279984 0)
			(layer "F.Fab")
			(hide yes)
			(effects
				(font
					(size 1 1)
					(thickness 0.15)
				)
			)
		)
		(property "License" "Apache-2.0"
			(at 264.824672 70.279984 0)
			(layer "F.Fab")
			(hide yes)
			(effects
				(font
					(size 1 1)
					(thickness 0.15)
				)
			)
		)
		(property "MPN" "GRM155R61H104KE14D"
			(at 264.824672 70.279984 0)
			(layer "F.Fab")
			(hide yes)
			(effects
				(font
					(size 1 1)
					(thickness 0.15)
				)
			)
		)
		(property "Manufacturer" "Murata"
			(at 264.824672 70.279984 0)
			(layer "F.Fab")
			(hide yes)
			(effects
				(font
					(size 1 1)
					(thickness 0.15)
				)
			)
		)
		(property "Val" "100n"
			(at 264.824672 70.279984 0)
			(layer "F.Fab")
			(hide yes)
			(effects
				(font
					(size 1 1)
					(thickness 0.15)
				)
			)
		)
		(property "Voltage" "50V"
			(at 264.824672 70.279984 0)
			(layer "F.Fab")
			(hide yes)
			(effects
				(font
					(size 1 1)
					(thickness 0.15)
				)
			)
		)
		(sheetname "/Debug FTDI/")
		(sheetfile "debug-ftdi.kicad_sch")
		(attr smd)
		(fp_rect
			(start -0.9659 -0.481258)
			(end 0.9649 0.458742)
			(stroke
				(width 0.05)
				(type solid)
			)
			(fill no)
			(layer "F.CrtYd")
		)
		(fp_line
			(start 0.499 -0.25)
			(end 0.499 0.248)
			(stroke
				(width 0.15)
				(type solid)
			)
			(layer "F.Fab")
		)
		(fp_line
			(start -0.499 -0.25)
			(end 0.499 -0.25)
			(stroke
				(width 0.15)
				(type solid)
			)
			(layer "F.Fab")
		)
		(fp_line
			(start 0.499 0.248)
			(end -0.499 0.248)
			(stroke
				(width 0.15)
				(type solid)
			)
			(layer "F.Fab")
		)
		(fp_line
			(start -0.499 0.248)
			(end -0.499 -0.25)
			(stroke
				(width 0.15)
				(type solid)
			)
			(layer "F.Fab")
		)
		(pad "1" smd roundrect
			(at -0.484 0 90)
			(size 0.59 0.64)
			(layers "F.Cu" "F.Mask" "F.Paste")
			(roundrect_rratio 0.25)
			(net 6 "/Debug FTDI/FTDI_3V3")
			(pintype "passive")
		)
		(pad "2" smd roundrect
			(at 0.484 0 90)
			(size 0.59 0.64)
			(layers "F.Cu" "F.Mask" "F.Paste")
			(roundrect_rratio 0.25)
			(net 1 "GND")
			(pintype "passive")
		)
	)
	(footprint "antmicro-footprints:C_0402_1005Metric"
		(layer "F.Cu")
		(at 94.059829 167.547157 90)
		(descr "Capacitor SMD 0402")
		(tags "capacitor SMD 0402")
		(property "Reference" "C111"
			(at 0 -0.699 90)
			(layer "F.SilkS")
			(hide yes)
			(effects
				(font
					(size 0.7 0.7)
					(thickness 0.15)
				)
				(justify left bottom)
			)
		)
		(property "Value" "C_18p_0402"
			(at -1.022927 2.155213 90)
			(layer "F.Fab")
			(effects
				(font
					(size 0.7 0.7)
					(thickness 0.15)
				)
				(justify left bottom)
			)
		)
		(property "Datasheet" "https://product.samsungsem.com/mlcc/CL05C180JB51PN.do"
			(at 0 0 90)
			(layer "F.Fab")
			(hide yes)
			(effects
				(font
					(size 1.27 1.27)
					(thickness 0.15)
				)
			)
		)
		(property "Author" "Antmicro"
			(at 261.606986 73.487328 0)
			(layer "F.Fab")
			(hide yes)
			(effects
				(font
					(size 1 1)
					(thickness 0.15)
				)
			)
		)
		(property "Dielectric" ""
			(at 261.606986 73.487328 0)
			(layer "F.Fab")
			(hide yes)
			(effects
				(font
					(size 1 1)
					(thickness 0.15)
				)
			)
		)
		(property "License" "Apache-2.0"
			(at 261.606986 73.487328 0)
			(layer "F.Fab")
			(hide yes)
			(effects
				(font
					(size 1 1)
					(thickness 0.15)
				)
			)
		)
		(property "MPN" "CL05C180JB51PNC"
			(at 261.606986 73.487328 0)
			(layer "F.Fab")
			(hide yes)
			(effects
				(font
					(size 1 1)
					(thickness 0.15)
				)
			)
		)
		(property "Manufacturer" "Samsung Electro-Mechanics"
			(at 261.606986 73.487328 0)
			(layer "F.Fab")
			(hide yes)
			(effects
				(font
					(size 1 1)
					(thickness 0.15)
				)
			)
		)
		(property "Val" "18p"
			(at 261.606986 73.487328 0)
			(layer "F.Fab")
			(hide yes)
			(effects
				(font
					(size 1 1)
					(thickness 0.15)
				)
			)
		)
		(property "Voltage" ""
			(at 261.606986 73.487328 0)
			(layer "F.Fab")
			(hide yes)
			(effects
				(font
					(size 1 1)
					(thickness 0.15)
				)
			)
		)
		(sheetname "/Debug FTDI/")
		(sheetfile "debug-ftdi.kicad_sch")
		(attr smd)
		(fp_rect
			(start -0.9659 -0.481258)
			(end 0.9649 0.458742)
			(stroke
				(width 0.05)
				(type solid)
			)
			(fill no)
			(layer "F.CrtYd")
		)
		(fp_line
			(start 0.499 -0.25)
			(end 0.499 0.248)
			(stroke
				(width 0.15)
				(type solid)
			)
			(layer "F.Fab")
		)
		(fp_line
			(start -0.499 -0.25)
			(end 0.499 -0.25)
			(stroke
				(width 0.15)
				(type solid)
			)
			(layer "F.Fab")
		)
		(fp_line
			(start 0.499 0.248)
			(end -0.499 0.248)
			(stroke
				(width 0.15)
				(type solid)
			)
			(layer "F.Fab")
		)
		(fp_line
			(start -0.499 0.248)
			(end -0.499 -0.25)
			(stroke
				(width 0.15)
				(type solid)
			)
			(layer "F.Fab")
		)
		(pad "1" smd roundrect
			(at -0.484 0 90)
			(size 0.59 0.64)
			(layers "F.Cu" "F.Mask" "F.Paste")
			(roundrect_rratio 0.25)
			(net 4 "/Debug FTDI/FTDI_XI")
			(pintype "passive")
		)
		(pad "2" smd roundrect
			(at 0.484 0 90)
			(size 0.59 0.64)
			(layers "F.Cu" "F.Mask" "F.Paste")
			(roundrect_rratio 0.25)
			(net 1 "GND")
			(pintype "passive")
		)
	)
	(footprint "antmicro-footprints:C_0402_1005Metric"
		(layer "F.Cu")
		(at 97.9 180.6 -90)
		(descr "Capacitor SMD 0402")
		(tags "capacitor SMD 0402")
		(property "Reference" "C119"
			(at 0 -0.699 270)
			(layer "F.SilkS")
			(hide yes)
			(effects
				(font
					(size 0.7 0.7)
					(thickness 0.15)
				)
				(justify left bottom)
			)
		)
		(property "Value" "C_100n_0402"
			(at -1.022927 2.155213 270)
			(layer "F.Fab")
			(effects
				(font
					(size 0.7 0.7)
					(thickness 0.15)
				)
				(justify left bottom)
			)
		)
		(property "Datasheet" "https://www.murata.com/products/productdetail?partno=GRM155R61H104KE14%23"
			(at 0 0 270)
			(layer "F.Fab")
			(hide yes)
			(effects
				(font
					(size 1.27 1.27)
					(thickness 0.15)
				)
			)
		)
		(property "Author" "Antmicro"
			(at -82.7 278.5 0)
			(layer "F.Fab")
			(hide yes)
			(effects
				(font
					(size 1 1)
					(thickness 0.15)
				)
			)
		)
		(property "Dielectric" "X5R"
			(at -82.7 278.5 0)
			(layer "F.Fab")
			(hide yes)
			(effects
				(font
					(size 1 1)
					(thickness 0.15)
				)
			)
		)
		(property "License" "Apache-2.0"
			(at -82.7 278.5 0)
			(layer "F.Fab")
			(hide yes)
			(effects
				(font
					(size 1 1)
					(thickness 0.15)
				)
			)
		)
		(property "MPN" "GRM155R61H104KE14D"
			(at -82.7 278.5 0)
			(layer "F.Fab")
			(hide yes)
			(effects
				(font
					(size 1 1)
					(thickness 0.15)
				)
			)
		)
		(property "Manufacturer" "Murata"
			(at -82.7 278.5 0)
			(layer "F.Fab")
			(hide yes)
			(effects
				(font
					(size 1 1)
					(thickness 0.15)
				)
			)
		)
		(property "Val" "100n"
			(at -82.7 278.5 0)
			(layer "F.Fab")
			(hide yes)
			(effects
				(font
					(size 1 1)
					(thickness 0.15)
				)
			)
		)
		(property "Voltage" "50V"
			(at -82.7 278.5 0)
			(layer "F.Fab")
			(hide yes)
			(effects
				(font
					(size 1 1)
					(thickness 0.15)
				)
			)
		)
		(sheetname "/Debug FTDI/")
		(sheetfile "debug-ftdi.kicad_sch")
		(attr smd)
		(fp_rect
			(start -0.9659 -0.481258)
			(end 0.9649 0.458742)
			(stroke
				(width 0.05)
				(type solid)
			)
			(fill no)
			(layer "F.CrtYd")
		)
		(fp_line
			(start -0.499 0.248)
			(end -0.499 -0.25)
			(stroke
				(width 0.15)
				(type solid)
			)
			(layer "F.Fab")
		)
		(fp_line
			(start 0.499 0.248)
			(end -0.499 0.248)
			(stroke
				(width 0.15)
				(type solid)
			)
			(layer "F.Fab")
		)
		(fp_line
			(start -0.499 -0.25)
			(end 0.499 -0.25)
			(stroke
				(width 0.15)
				(type solid)
			)
			(layer "F.Fab")
		)
		(fp_line
			(start 0.499 -0.25)
			(end 0.499 0.248)
			(stroke
				(width 0.15)
				(type solid)
			)
			(layer "F.Fab")
		)
		(pad "1" smd roundrect
			(at -0.484 0 270)
			(size 0.59 0.64)
			(layers "F.Cu" "F.Mask" "F.Paste")
			(roundrect_rratio 0.25)
			(net 6 "/Debug FTDI/FTDI_3V3")
			(pintype "passive")
		)
		(pad "2" smd roundrect
			(at 0.484 0 270)
			(size 0.59 0.64)
			(layers "F.Cu" "F.Mask" "F.Paste")
			(roundrect_rratio 0.25)
			(net 1 "GND")
			(pintype "passive")
		)
	)
	(footprint "antmicro-footprints:C_0402_1005Metric"
		(layer "F.Cu")
		(at 105.467344 177.267328)
		(descr "Capacitor SMD 0402")
		(tags "capacitor SMD 0402")
		(property "Reference" "C122"
			(at 0 -0.699 0)
			(layer "F.SilkS")
			(hide yes)
			(effects
				(font
					(size 0.7 0.7)
					(thickness 0.15)
				)
				(justify left bottom)
			)
		)
		(property "Value" "C_4u7_0402"
			(at -1.022927 2.155213 0)
			(layer "F.Fab")
			(effects
				(font
					(size 0.7 0.7)
					(thickness 0.15)
				)
				(justify left bottom)
			)
		)
		(property "Datasheet" "https://www.murata.com/products/productdetail?partno=GRM155R61A475MEAA%23"
			(at 0 0 0)
			(layer "F.Fab")
			(hide yes)
			(effects
				(font
					(size 1.27 1.27)
					(thickness 0.15)
				)
			)
		)
		(property "Author" "Antmicro"
			(at 0 0 0)
			(layer "F.Fab")
			(hide yes)
			(effects
				(font
					(size 1 1)
					(thickness 0.15)
				)
			)
		)
		(property "Dielectric" ""
			(at 0 0 0)
			(layer "F.Fab")
			(hide yes)
			(effects
				(font
					(size 1 1)
					(thickness 0.15)
				)
			)
		)
		(property "License" "Apache-2.0"
			(at 0 0 0)
			(layer "F.Fab")
			(hide yes)
			(effects
				(font
					(size 1 1)
					(thickness 0.15)
				)
			)
		)
		(property "MPN" "GRM155R61A475MEAAD"
			(at 0 0 0)
			(layer "F.Fab")
			(hide yes)
			(effects
				(font
					(size 1 1)
					(thickness 0.15)
				)
			)
		)
		(property "Manufacturer" "Murata"
			(at 0 0 0)
			(layer "F.Fab")
			(hide yes)
			(effects
				(font
					(size 1 1)
					(thickness 0.15)
				)
			)
		)
		(property "Val" "4u7"
			(at 0 0 0)
			(layer "F.Fab")
			(hide yes)
			(effects
				(font
					(size 1 1)
					(thickness 0.15)
				)
			)
		)
		(property "Voltage" ""
			(at 0 0 0)
			(layer "F.Fab")
			(hide yes)
			(effects
				(font
					(size 1 1)
					(thickness 0.15)
				)
			)
		)
		(sheetname "/Debug FTDI/")
		(sheetfile "debug-ftdi.kicad_sch")
		(attr smd)
		(fp_rect
			(start -0.9659 -0.481258)
			(end 0.9649 0.458742)
			(stroke
				(width 0.05)
				(type solid)
			)
			(fill no)
			(layer "F.CrtYd")
		)
		(fp_line
			(start -0.499 -0.25)
			(end 0.499 -0.25)
			(stroke
				(width 0.15)
				(type solid)
			)
			(layer "F.Fab")
		)
		(fp_line
			(start -0.499 0.248)
			(end -0.499 -0.25)
			(stroke
				(width 0.15)
				(type solid)
			)
			(layer "F.Fab")
		)
		(fp_line
			(start 0.499 -0.25)
			(end 0.499 0.248)
			(stroke
				(width 0.15)
				(type solid)
			)
			(layer "F.Fab")
		)
		(fp_line
			(start 0.499 0.248)
			(end -0.499 0.248)
			(stroke
				(width 0.15)
				(type solid)
			)
			(layer "F.Fab")
		)
		(pad "1" smd roundrect
			(at -0.484 0)
			(size 0.59 0.64)
			(layers "F.Cu" "F.Mask" "F.Paste")
			(roundrect_rratio 0.25)
			(net 8 "/Debug FTDI/FTDI_VCORE")
			(pintype "passive")
		)
		(pad "2" smd roundrect
			(at 0.484 0)
			(size 0.59 0.64)
			(layers "F.Cu" "F.Mask" "F.Paste")
			(roundrect_rratio 0.25)
			(net 1 "GND")
			(pintype "passive")
		)
	)
	(footprint "antmicro-footprints:FB_0603_1608Metric"
		(layer "F.Cu")
		(at 89.310501 171.035 -90)
		(property "Reference" "FB2"
			(at 0 -0.8 270)
			(layer "F.SilkS")
			(hide yes)
			(effects
				(font
					(size 0.7 0.7)
					(thickness 0.15)
				)
				(justify left bottom)
			)
		)
		(property "Value" "FB_600Z_0.5A_Murata-BLM18AG_0603"
			(at 0 1.5 270)
			(layer "F.Fab")
			(effects
				(font
					(size 0.7 0.7)
					(thickness 0.15)
				)
				(justify left bottom)
			)
		)
		(property "Datasheet" "https://www.murata.com/en-us/products/productdata/8796738650142/ENFA0003.pdf"
			(at 0 0 270)
			(layer "F.Fab")
			(hide yes)
			(effects
				(font
					(size 1.27 1.27)
					(thickness 0.15)
				)
			)
		)
		(property "Author" "Antmicro"
			(at -81.724499 260.345501 0)
			(layer "F.Fab")
			(hide yes)
			(effects
				(font
					(size 1 1)
					(thickness 0.15)
				)
			)
		)
		(property "License" "Apache-2.0"
			(at -81.724499 260.345501 0)
			(layer "F.Fab")
			(hide yes)
			(effects
				(font
					(size 1 1)
					(thickness 0.15)
				)
			)
		)
		(property "MPN" "BLM18AG601SN1D"
			(at -81.724499 260.345501 0)
			(layer "F.Fab")
			(hide yes)
			(effects
				(font
					(size 1 1)
					(thickness 0.15)
				)
			)
		)
		(property "Manufacturer" "Murata"
			(at -81.724499 260.345501 0)
			(layer "F.Fab")
			(hide yes)
			(effects
				(font
					(size 1 1)
					(thickness 0.15)
				)
			)
		)
		(property "Val" "600Z/0.5A"
			(at -81.724499 260.345501 0)
			(layer "F.Fab")
			(hide yes)
			(effects
				(font
					(size 1 1)
					(thickness 0.15)
				)
			)
		)
		(sheetname "/Debug FTDI/")
		(sheetfile "debug-ftdi.kicad_sch")
		(attr smd)
		(fp_line
			(start -0.196 0.406)
			(end 0.193 0.406)
			(stroke
				(width 0.15)
				(type solid)
			)
			(layer "F.SilkS")
		)
		(fp_line
			(start -0.196 -0.408)
			(end 0.193 -0.408)
			(stroke
				(width 0.15)
				(type solid)
			)
			(layer "F.SilkS")
		)
		(fp_rect
			(start -1.3 -0.6)
			(end 1.3 0.6)
			(stroke
				(width 0.05)
				(type solid)
			)
			(fill no)
			(layer "F.CrtYd")
		)
		(fp_line
			(start -0.803 0.406)
			(end -0.803 -0.408)
			(stroke
				(width 0.15)
				(type solid)
			)
			(layer "F.Fab")
		)
		(fp_line
			(start 0.8 0.406)
			(end -0.803 0.406)
			(stroke
				(width 0.15)
				(type solid)
			)
			(layer "F.Fab")
		)
		(fp_line
			(start 0.8 -0.408)
			(end 0.8 0.406)
			(stroke
				(width 0.15)
				(type solid)
			)
			(layer "F.Fab")
		)
		(fp_line
			(start 0.8 -0.408)
			(end -0.803 -0.408)
			(stroke
				(width 0.15)
				(type solid)
			)
			(layer "F.Fab")
		)
		(pad "1" smd roundrect
			(at -0.891 0 270)
			(size 0.762 1.09)
			(layers "F.Cu" "F.Mask" "F.Paste")
			(roundrect_rratio 0.15)
			(net 6 "/Debug FTDI/FTDI_3V3")
			(pintype "passive")
		)
		(pad "2" smd roundrect
			(at 0.888 0 270)
			(size 0.762 1.09)
			(layers "F.Cu" "F.Mask" "F.Paste")
			(roundrect_rratio 0.15)
			(net 5 "/Debug FTDI/FTDI_VPHY")
			(pintype "passive")
		)
	)
	(footprint "antmicro-footprints:R_0402_1005Metric"
		(layer "F.Cu")
		(at 91.052344 173.382328)
		(descr "Resistor SMD 0402")
		(tags "resistor SMD 0402")
		(property "Reference" "R44"
			(at -1.122484 -0.772697 0)
			(layer "F.SilkS")
			(hide yes)
			(effects
				(font
					(size 0.7 0.7)
					(thickness 0.15)
				)
				(justify left bottom)
			)
		)
		(property "Value" "R_12k_0402"
			(at -1.011843 1.772047 0)
			(layer "F.Fab")
			(effects
				(font
					(size 0.7 0.7)
					(thickness 0.15)
				)
				(justify left bottom)
			)
		)
		(property "Datasheet" "https://www.bourns.com/docs/product-datasheets/cr.pdf"
			(at 0 0 0)
			(layer "F.Fab")
			(hide yes)
			(effects
				(font
					(size 1.27 1.27)
					(thickness 0.15)
				)
			)
		)
		(property "Author" "Antmicro"
			(at 0 0 0)
			(layer "F.Fab")
			(hide yes)
			(effects
				(font
					(size 1 1)
					(thickness 0.15)
				)
			)
		)
		(property "License" "Apache-2.0"
			(at 0 0 0)
			(layer "F.Fab")
			(hide yes)
			(effects
				(font
					(size 1 1)
					(thickness 0.15)
				)
			)
		)
		(property "MPN" "CR0402-FX-1202GLF"
			(at 0 0 0)
			(layer "F.Fab")
			(hide yes)
			(effects
				(font
					(size 1 1)
					(thickness 0.15)
				)
			)
		)
		(property "Manufacturer" "Bourns"
			(at 0 0 0)
			(layer "F.Fab")
			(hide yes)
			(effects
				(font
					(size 1 1)
					(thickness 0.15)
				)
			)
		)
		(property "Tolerance" "1%"
			(at 0 0 0)
			(layer "F.Fab")
			(hide yes)
			(effects
				(font
					(size 1 1)
					(thickness 0.15)
				)
			)
		)
		(property "Val" "12k"
			(at 0 0 0)
			(layer "F.Fab")
			(hide yes)
			(effects
				(font
					(size 1 1)
					(thickness 0.15)
				)
			)
		)
		(sheetname "/Debug FTDI/")
		(sheetfile "debug-ftdi.kicad_sch")
		(attr smd)
		(fp_rect
			(start -0.93 -0.47)
			(end 0.93 0.47)
			(stroke
				(width 0.05)
				(type solid)
			)
			(fill no)
			(layer "F.CrtYd")
		)
		(fp_rect
			(start -0.5 -0.25)
			(end 0.5 0.25)
			(stroke
				(width 0.15)
				(type solid)
			)
			(fill no)
			(layer "F.Fab")
		)
		(pad "1" smd roundrect
			(at -0.485 0)
			(size 0.59 0.64)
			(layers "F.Cu" "F.Mask" "F.Paste")
			(roundrect_rratio 0.25)
			(net 1 "GND")
			(pintype "passive")
		)
		(pad "2" smd roundrect
			(at 0.485 0)
			(size 0.59 0.64)
			(layers "F.Cu" "F.Mask" "F.Paste")
			(roundrect_rratio 0.25)
			(net 375 "Net-(U6-REF)")
			(pintype "passive")
		)
	)
	(footprint "antmicro-footprints:C_0402_1005Metric"
		(layer "F.Cu")
		(at 90.690501 176.036 -90)
		(descr "Capacitor SMD 0402")
		(tags "capacitor SMD 0402")
		(property "Reference" "C110"
			(at 0 -0.699 270)
			(layer "F.SilkS")
			(hide yes)
			(effects
				(font
					(size 0.7 0.7)
					(thickness 0.15)
				)
				(justify left bottom)
			)
		)
		(property "Value" "C_100n_0402"
			(at -1.022927 2.155213 270)
			(layer "F.Fab")
			(effects
				(font
					(size 0.7 0.7)
					(thickness 0.15)
				)
				(justify left bottom)
			)
		)
		(property "Datasheet" "https://www.murata.com/products/productdetail?partno=GRM155R61H104KE14%23"
			(at 0 0 270)
			(layer "F.Fab")
			(hide yes)
			(effects
				(font
					(size 1.27 1.27)
					(thickness 0.15)
				)
			)
		)
		(property "Author" "Antmicro"
			(at -85.345499 266.726501 0)
			(layer "F.Fab")
			(hide yes)
			(effects
				(font
					(size 1 1)
					(thickness 0.15)
				)
			)
		)
		(property "Dielectric" "X5R"
			(at -85.345499 266.726501 0)
			(layer "F.Fab")
			(hide yes)
			(effects
				(font
					(size 1 1)
					(thickness 0.15)
				)
			)
		)
		(property "License" "Apache-2.0"
			(at -85.345499 266.726501 0)
			(layer "F.Fab")
			(hide yes)
			(effects
				(font
					(size 1 1)
					(thickness 0.15)
				)
			)
		)
		(property "MPN" "GRM155R61H104KE14D"
			(at -85.345499 266.726501 0)
			(layer "F.Fab")
			(hide yes)
			(effects
				(font
					(size 1 1)
					(thickness 0.15)
				)
			)
		)
		(property "Manufacturer" "Murata"
			(at -85.345499 266.726501 0)
			(layer "F.Fab")
			(hide yes)
			(effects
				(font
					(size 1 1)
					(thickness 0.15)
				)
			)
		)
		(property "Val" "100n"
			(at -85.345499 266.726501 0)
			(layer "F.Fab")
			(hide yes)
			(effects
				(font
					(size 1 1)
					(thickness 0.15)
				)
			)
		)
		(property "Voltage" "50V"
			(at -85.345499 266.726501 0)
			(layer "F.Fab")
			(hide yes)
			(effects
				(font
					(size 1 1)
					(thickness 0.15)
				)
			)
		)
		(sheetname "/Debug FTDI/")
		(sheetfile "debug-ftdi.kicad_sch")
		(attr smd)
		(fp_rect
			(start -0.9659 -0.481258)
			(end 0.9649 0.458742)
			(stroke
				(width 0.05)
				(type solid)
			)
			(fill no)
			(layer "F.CrtYd")
		)
		(fp_line
			(start -0.499 0.248)
			(end -0.499 -0.25)
			(stroke
				(width 0.15)
				(type solid)
			)
			(layer "F.Fab")
		)
		(fp_line
			(start 0.499 0.248)
			(end -0.499 0.248)
			(stroke
				(width 0.15)
				(type solid)
			)
			(layer "F.Fab")
		)
		(fp_line
			(start -0.499 -0.25)
			(end 0.499 -0.25)
			(stroke
				(width 0.15)
				(type solid)
			)
			(layer "F.Fab")
		)
		(fp_line
			(start 0.499 -0.25)
			(end 0.499 0.248)
			(stroke
				(width 0.15)
				(type solid)
			)
			(layer "F.Fab")
		)
		(pad "1" smd roundrect
			(at -0.484 0 270)
			(size 0.59 0.64)
			(layers "F.Cu" "F.Mask" "F.Paste")
			(roundrect_rratio 0.25)
			(net 3 "/Debug FTDI/FTDI_VPLL")
			(pintype "passive")
		)
		(pad "2" smd roundrect
			(at 0.484 0 270)
			(size 0.59 0.64)
			(layers "F.Cu" "F.Mask" "F.Paste")
			(roundrect_rratio 0.25)
			(net 1 "GND")
			(pintype "passive")
		)
	)
	(footprint "antmicro-footprints:C_0402_1005Metric"
		(layer "F.Cu")
		(at 91.689001 176.035 -90)
		(descr "Capacitor SMD 0402")
		(tags "capacitor SMD 0402")
		(property "Reference" "C114"
			(at 0 -0.699 270)
			(layer "F.SilkS")
			(hide yes)
			(effects
				(font
					(size 0.7 0.7)
					(thickness 0.15)
				)
				(justify left bottom)
			)
		)
		(property "Value" "C_4u7_0402"
			(at -1.022927 2.155213 270)
			(layer "F.Fab")
			(effects
				(font
					(size 0.7 0.7)
					(thickness 0.15)
				)
				(justify left bottom)
			)
		)
		(property "Datasheet" "https://www.murata.com/products/productdetail?partno=GRM155R61A475MEAA%23"
			(at 0 0 270)
			(layer "F.Fab")
			(hide yes)
			(effects
				(font
					(size 1.27 1.27)
					(thickness 0.15)
				)
			)
		)
		(property "Author" "Antmicro"
			(at -84.345999 267.724001 0)
			(layer "F.Fab")
			(hide yes)
			(effects
				(font
					(size 1 1)
					(thickness 0.15)
				)
			)
		)
		(property "Dielectric" ""
			(at -84.345999 267.724001 0)
			(layer "F.Fab")
			(hide yes)
			(effects
				(font
					(size 1 1)
					(thickness 0.15)
				)
			)
		)
		(property "License" "Apache-2.0"
			(at -84.345999 267.724001 0)
			(layer "F.Fab")
			(hide yes)
			(effects
				(font
					(size 1 1)
					(thickness 0.15)
				)
			)
		)
		(property "MPN" "GRM155R61A475MEAAD"
			(at -84.345999 267.724001 0)
			(layer "F.Fab")
			(hide yes)
			(effects
				(font
					(size 1 1)
					(thickness 0.15)
				)
			)
		)
		(property "Manufacturer" "Murata"
			(at -84.345999 267.724001 0)
			(layer "F.Fab")
			(hide yes)
			(effects
				(font
					(size 1 1)
					(thickness 0.15)
				)
			)
		)
		(property "Val" "4u7"
			(at -84.345999 267.724001 0)
			(layer "F.Fab")
			(hide yes)
			(effects
				(font
					(size 1 1)
					(thickness 0.15)
				)
			)
		)
		(property "Voltage" ""
			(at -84.345999 267.724001 0)
			(layer "F.Fab")
			(hide yes)
			(effects
				(font
					(size 1 1)
					(thickness 0.15)
				)
			)
		)
		(sheetname "/Debug FTDI/")
		(sheetfile "debug-ftdi.kicad_sch")
		(attr smd)
		(fp_rect
			(start -0.9659 -0.481258)
			(end 0.9649 0.458742)
			(stroke
				(width 0.05)
				(type solid)
			)
			(fill no)
			(layer "F.CrtYd")
		)
		(fp_line
			(start -0.499 0.248)
			(end -0.499 -0.25)
			(stroke
				(width 0.15)
				(type solid)
			)
			(layer "F.Fab")
		)
		(fp_line
			(start 0.499 0.248)
			(end -0.499 0.248)
			(stroke
				(width 0.15)
				(type solid)
			)
			(layer "F.Fab")
		)
		(fp_line
			(start -0.499 -0.25)
			(end 0.499 -0.25)
			(stroke
				(width 0.15)
				(type solid)
			)
			(layer "F.Fab")
		)
		(fp_line
			(start 0.499 -0.25)
			(end 0.499 0.248)
			(stroke
				(width 0.15)
				(type solid)
			)
			(layer "F.Fab")
		)
		(pad "1" smd roundrect
			(at -0.484 0 270)
			(size 0.59 0.64)
			(layers "F.Cu" "F.Mask" "F.Paste")
			(roundrect_rratio 0.25)
			(net 3 "/Debug FTDI/FTDI_VPLL")
			(pintype "passive")
		)
		(pad "2" smd roundrect
			(at 0.484 0 270)
			(size 0.59 0.64)
			(layers "F.Cu" "F.Mask" "F.Paste")
			(roundrect_rratio 0.25)
			(net 1 "GND")
			(pintype "passive")
		)
	)
	(footprint "antmicro-footprints:FB_0603_1608Metric"
		(layer "F.Cu")
		(at 89.310501 176.535 90)
		(property "Reference" "FB1"
			(at 0 -0.8 90)
			(layer "F.SilkS")
			(hide yes)
			(effects
				(font
					(size 0.7 0.7)
					(thickness 0.15)
				)
				(justify left bottom)
			)
		)
		(property "Value" "FB_600Z_0.5A_Murata-BLM18AG_0603"
			(at 0 1.5 90)
			(layer "F.Fab")
			(effects
				(font
					(size 0.7 0.7)
					(thickness 0.15)
				)
				(justify left bottom)
			)
		)
		(property "Datasheet" "https://www.murata.com/en-us/products/productdata/8796738650142/ENFA0003.pdf"
			(at 0 0 90)
			(layer "F.Fab")
			(hide yes)
			(effects
				(font
					(size 1.27 1.27)
					(thickness 0.15)
				)
			)
		)
		(property "Author" "Antmicro"
			(at 265.845501 87.224499 0)
			(layer "F.Fab")
			(hide yes)
			(effects
				(font
					(size 1 1)
					(thickness 0.15)
				)
			)
		)
		(property "License" "Apache-2.0"
			(at 265.845501 87.224499 0)
			(layer "F.Fab")
			(hide yes)
			(effects
				(font
					(size 1 1)
					(thickness 0.15)
				)
			)
		)
		(property "MPN" "BLM18AG601SN1D"
			(at 265.845501 87.224499 0)
			(layer "F.Fab")
			(hide yes)
			(effects
				(font
					(size 1 1)
					(thickness 0.15)
				)
			)
		)
		(property "Manufacturer" "Murata"
			(at 265.845501 87.224499 0)
			(layer "F.Fab")
			(hide yes)
			(effects
				(font
					(size 1 1)
					(thickness 0.15)
				)
			)
		)
		(property "Val" "600Z/0.5A"
			(at 265.845501 87.224499 0)
			(layer "F.Fab")
			(hide yes)
			(effects
				(font
					(size 1 1)
					(thickness 0.15)
				)
			)
		)
		(sheetname "/Debug FTDI/")
		(sheetfile "debug-ftdi.kicad_sch")
		(attr smd)
		(fp_line
			(start -0.196 -0.408)
			(end 0.193 -0.408)
			(stroke
				(width 0.15)
				(type solid)
			)
			(layer "F.SilkS")
		)
		(fp_line
			(start -0.196 0.406)
			(end 0.193 0.406)
			(stroke
				(width 0.15)
				(type solid)
			)
			(layer "F.SilkS")
		)
		(fp_rect
			(start -1.3 -0.6)
			(end 1.3 0.6)
			(stroke
				(width 0.05)
				(type solid)
			)
			(fill no)
			(layer "F.CrtYd")
		)
		(fp_line
			(start 0.8 -0.408)
			(end -0.803 -0.408)
			(stroke
				(width 0.15)
				(type solid)
			)
			(layer "F.Fab")
		)
		(fp_line
			(start 0.8 -0.408)
			(end 0.8 0.406)
			(stroke
				(width 0.15)
				(type solid)
			)
			(layer "F.Fab")
		)
		(fp_line
			(start 0.8 0.406)
			(end -0.803 0.406)
			(stroke
				(width 0.15)
				(type solid)
			)
			(layer "F.Fab")
		)
		(fp_line
			(start -0.803 0.406)
			(end -0.803 -0.408)
			(stroke
				(width 0.15)
				(type solid)
			)
			(layer "F.Fab")
		)
		(pad "1" smd roundrect
			(at -0.891 0 90)
			(size 0.762 1.09)
			(layers "F.Cu" "F.Mask" "F.Paste")
			(roundrect_rratio 0.15)
			(net 6 "/Debug FTDI/FTDI_3V3")
			(pintype "passive")
		)
		(pad "2" smd roundrect
			(at 0.888 0 90)
			(size 0.762 1.09)
			(layers "F.Cu" "F.Mask" "F.Paste")
			(roundrect_rratio 0.15)
			(net 3 "/Debug FTDI/FTDI_VPLL")
			(pintype "passive")
		)
	)
	(footprint "antmicro-footprints:C_0402_1005Metric"
		(layer "F.Cu")
		(at 89.523501 166.175 -90)
		(descr "Capacitor SMD 0402")
		(tags "capacitor SMD 0402")
		(property "Reference" "C117"
			(at 0 -0.699 270)
			(layer "F.SilkS")
			(hide yes)
			(effects
				(font
					(size 0.7 0.7)
					(thickness 0.15)
				)
				(justify left bottom)
			)
		)
		(property "Value" "C_18p_0402"
			(at -1.022927 2.155213 270)
			(layer "F.Fab")
			(effects
				(font
					(size 0.7 0.7)
					(thickness 0.15)
				)
				(justify left bottom)
			)
		)
		(property "Datasheet" "https://product.samsungsem.com/mlcc/CL05C180JB51PN.do"
			(at 0 0 270)
			(layer "F.Fab")
			(hide yes)
			(effects
				(font
					(size 1.27 1.27)
					(thickness 0.15)
				)
			)
		)
		(property "Author" "Antmicro"
			(at -76.651499 255.698501 0)
			(layer "F.Fab")
			(hide yes)
			(effects
				(font
					(size 1 1)
					(thickness 0.15)
				)
			)
		)
		(property "Dielectric" ""
			(at -76.651499 255.698501 0)
			(layer "F.Fab")
			(hide yes)
			(effects
				(font
					(size 1 1)
					(thickness 0.15)
				)
			)
		)
		(property "License" "Apache-2.0"
			(at -76.651499 255.698501 0)
			(layer "F.Fab")
			(hide yes)
			(effects
				(font
					(size 1 1)
					(thickness 0.15)
				)
			)
		)
		(property "MPN" "CL05C180JB51PNC"
			(at -76.651499 255.698501 0)
			(layer "F.Fab")
			(hide yes)
			(effects
				(font
					(size 1 1)
					(thickness 0.15)
				)
			)
		)
		(property "Manufacturer" "Samsung Electro-Mechanics"
			(at -76.651499 255.698501 0)
			(layer "F.Fab")
			(hide yes)
			(effects
				(font
					(size 1 1)
					(thickness 0.15)
				)
			)
		)
		(property "Val" "18p"
			(at -76.651499 255.698501 0)
			(layer "F.Fab")
			(hide yes)
			(effects
				(font
					(size 1 1)
					(thickness 0.15)
				)
			)
		)
		(property "Voltage" ""
			(at -76.651499 255.698501 0)
			(layer "F.Fab")
			(hide yes)
			(effects
				(font
					(size 1 1)
					(thickness 0.15)
				)
			)
		)
		(sheetname "/Debug FTDI/")
		(sheetfile "debug-ftdi.kicad_sch")
		(attr smd)
		(fp_rect
			(start -0.9659 -0.481258)
			(end 0.9649 0.458742)
			(stroke
				(width 0.05)
				(type solid)
			)
			(fill no)
			(layer "F.CrtYd")
		)
		(fp_line
			(start -0.499 0.248)
			(end -0.499 -0.25)
			(stroke
				(width 0.15)
				(type solid)
			)
			(layer "F.Fab")
		)
		(fp_line
			(start 0.499 0.248)
			(end -0.499 0.248)
			(stroke
				(width 0.15)
				(type solid)
			)
			(layer "F.Fab")
		)
		(fp_line
			(start -0.499 -0.25)
			(end 0.499 -0.25)
			(stroke
				(width 0.15)
				(type solid)
			)
			(layer "F.Fab")
		)
		(fp_line
			(start 0.499 -0.25)
			(end 0.499 0.248)
			(stroke
				(width 0.15)
				(type solid)
			)
			(layer "F.Fab")
		)
		(pad "1" smd roundrect
			(at -0.484 0 270)
			(size 0.59 0.64)
			(layers "F.Cu" "F.Mask" "F.Paste")
			(roundrect_rratio 0.25)
			(net 7 "/Debug FTDI/FTDI_XO")
			(pintype "passive")
		)
		(pad "2" smd roundrect
			(at 0.484 0 270)
			(size 0.59 0.64)
			(layers "F.Cu" "F.Mask" "F.Paste")
			(roundrect_rratio 0.25)
			(net 1 "GND")
			(pintype "passive")
		)
	)
	(footprint "antmicro-footprints:R_0402_1005Metric"
		(layer "F.Cu")
		(at 84.620501 165.841 180)
		(descr "Resistor SMD 0402")
		(tags "resistor SMD 0402")
		(property "Reference" "R84"
			(at -1.122484 -0.772697 180)
			(layer "F.SilkS")
			(hide yes)
			(effects
				(font
					(size 0.7 0.7)
					(thickness 0.15)
				)
				(justify left bottom)
			)
		)
		(property "Value" "R_330R_0402"
			(at -1.011843 1.772047 180)
			(layer "F.Fab")
			(effects
				(font
					(size 0.7 0.7)
					(thickness 0.15)
				)
				(justify left bottom)
			)
		)
		(property "Datasheet" "https://www.bourns.com/docs/product-datasheets/cr.pdf"
			(at 0 0 180)
			(layer "F.Fab")
			(hide yes)
			(effects
				(font
					(size 1.27 1.27)
					(thickness 0.15)
				)
			)
		)
		(property "Author" "Antmicro"
			(at 169.241002 331.682 0)
			(layer "F.Fab")
			(hide yes)
			(effects
				(font
					(size 1 1)
					(thickness 0.15)
				)
			)
		)
		(property "License" "Apache-2.0"
			(at 169.241002 331.682 0)
			(layer "F.Fab")
			(hide yes)
			(effects
				(font
					(size 1 1)
					(thickness 0.15)
				)
			)
		)
		(property "MPN" "CR0402-FX-3300GLF"
			(at 169.241002 331.682 0)
			(layer "F.Fab")
			(hide yes)
			(effects
				(font
					(size 1 1)
					(thickness 0.15)
				)
			)
		)
		(property "Manufacturer" "Bourns"
			(at 169.241002 331.682 0)
			(layer "F.Fab")
			(hide yes)
			(effects
				(font
					(size 1 1)
					(thickness 0.15)
				)
			)
		)
		(property "Tolerance" "1%"
			(at 169.241002 331.682 0)
			(layer "F.Fab")
			(hide yes)
			(effects
				(font
					(size 1 1)
					(thickness 0.15)
				)
			)
		)
		(property "Val" "330R"
			(at 169.241002 331.682 0)
			(layer "F.Fab")
			(hide yes)
			(effects
				(font
					(size 1 1)
					(thickness 0.15)
				)
			)
		)
		(sheetname "/HDMI + SD Card/")
		(sheetfile "hdmi-sd-card.kicad_sch")
		(attr smd)
		(fp_rect
			(start -0.93 -0.47)
			(end 0.93 0.47)
			(stroke
				(width 0.05)
				(type solid)
			)
			(fill no)
			(layer "F.CrtYd")
		)
		(fp_rect
			(start -0.5 -0.25)
			(end 0.5 0.25)
			(stroke
				(width 0.15)
				(type solid)
			)
			(fill no)
			(layer "F.Fab")
		)
		(pad "1" smd roundrect
			(at -0.485 0 180)
			(size 0.59 0.64)
			(layers "F.Cu" "F.Mask" "F.Paste")
			(roundrect_rratio 0.25)
			(net 669 "/FPGA bank 16/SD.CD")
			(pintype "passive")
		)
		(pad "2" smd roundrect
			(at 0.485 0 180)
			(size 0.59 0.64)
			(layers "F.Cu" "F.Mask" "F.Paste")
			(roundrect_rratio 0.25)
			(net 330 "Net-(J5-CD_SW1)")
			(pintype "passive")
		)
	)
	(footprint "antmicro-footprints:C_0402_1005Metric"
		(layer "F.Cu")
		(at 91.689001 171.535 90)
		(descr "Capacitor SMD 0402")
		(tags "capacitor SMD 0402")
		(property "Reference" "C112"
			(at 0 -0.699 90)
			(layer "F.SilkS")
			(hide yes)
			(effects
				(font
					(size 0.7 0.7)
					(thickness 0.15)
				)
				(justify left bottom)
			)
		)
		(property "Value" "C_100n_0402"
			(at -1.022927 2.155213 90)
			(layer "F.Fab")
			(effects
				(font
					(size 0.7 0.7)
					(thickness 0.15)
				)
				(justify left bottom)
			)
		)
		(property "Datasheet" "https://www.murata.com/products/productdetail?partno=GRM155R61H104KE14%23"
			(at 0 0 90)
			(layer "F.Fab")
			(hide yes)
			(effects
				(font
					(size 1.27 1.27)
					(thickness 0.15)
				)
			)
		)
		(property "Author" "Antmicro"
			(at 263.224001 79.845999 0)
			(layer "F.Fab")
			(hide yes)
			(effects
				(font
					(size 1 1)
					(thickness 0.15)
				)
			)
		)
		(property "Dielectric" "X5R"
			(at 263.224001 79.845999 0)
			(layer "F.Fab")
			(hide yes)
			(effects
				(font
					(size 1 1)
					(thickness 0.15)
				)
			)
		)
		(property "License" "Apache-2.0"
			(at 263.224001 79.845999 0)
			(layer "F.Fab")
			(hide yes)
			(effects
				(font
					(size 1 1)
					(thickness 0.15)
				)
			)
		)
		(property "MPN" "GRM155R61H104KE14D"
			(at 263.224001 79.845999 0)
			(layer "F.Fab")
			(hide yes)
			(effects
				(font
					(size 1 1)
					(thickness 0.15)
				)
			)
		)
		(property "Manufacturer" "Murata"
			(at 263.224001 79.845999 0)
			(layer "F.Fab")
			(hide yes)
			(effects
				(font
					(size 1 1)
					(thickness 0.15)
				)
			)
		)
		(property "Val" "100n"
			(at 263.224001 79.845999 0)
			(layer "F.Fab")
			(hide yes)
			(effects
				(font
					(size 1 1)
					(thickness 0.15)
				)
			)
		)
		(property "Voltage" "50V"
			(at 263.224001 79.845999 0)
			(layer "F.Fab")
			(hide yes)
			(effects
				(font
					(size 1 1)
					(thickness 0.15)
				)
			)
		)
		(sheetname "/Debug FTDI/")
		(sheetfile "debug-ftdi.kicad_sch")
		(attr smd)
		(fp_rect
			(start -0.9659 -0.481258)
			(end 0.9649 0.458742)
			(stroke
				(width 0.05)
				(type solid)
			)
			(fill no)
			(layer "F.CrtYd")
		)
		(fp_line
			(start 0.499 -0.25)
			(end 0.499 0.248)
			(stroke
				(width 0.15)
				(type solid)
			)
			(layer "F.Fab")
		)
		(fp_line
			(start -0.499 -0.25)
			(end 0.499 -0.25)
			(stroke
				(width 0.15)
				(type solid)
			)
			(layer "F.Fab")
		)
		(fp_line
			(start 0.499 0.248)
			(end -0.499 0.248)
			(stroke
				(width 0.15)
				(type solid)
			)
			(layer "F.Fab")
		)
		(fp_line
			(start -0.499 0.248)
			(end -0.499 -0.25)
			(stroke
				(width 0.15)
				(type solid)
			)
			(layer "F.Fab")
		)
		(pad "1" smd roundrect
			(at -0.484 0 90)
			(size 0.59 0.64)
			(layers "F.Cu" "F.Mask" "F.Paste")
			(roundrect_rratio 0.25)
			(net 5 "/Debug FTDI/FTDI_VPHY")
			(pintype "passive")
		)
		(pad "2" smd roundrect
			(at 0.484 0 90)
			(size 0.59 0.64)
			(layers "F.Cu" "F.Mask" "F.Paste")
			(roundrect_rratio 0.25)
			(net 1 "GND")
			(pintype "passive")
		)
	)
	(footprint "antmicro-footprints:C_0402_1005Metric"
		(layer "F.Cu")
		(at 99.847344 167.542328 90)
		(descr "Capacitor SMD 0402")
		(tags "capacitor SMD 0402")
		(property "Reference" "C118"
			(at 0 -0.699 90)
			(layer "F.SilkS")
			(hide yes)
			(effects
				(font
					(size 0.7 0.7)
					(thickness 0.15)
				)
				(justify left bottom)
			)
		)
		(property "Value" "C_100n_0402"
			(at -1.022927 2.155213 90)
			(layer "F.Fab")
			(effects
				(font
					(size 0.7 0.7)
					(thickness 0.15)
				)
				(justify left bottom)
			)
		)
		(property "Datasheet" "https://www.murata.com/products/productdetail?partno=GRM155R61H104KE14%23"
			(at 0 0 90)
			(layer "F.Fab")
			(hide yes)
			(effects
				(font
					(size 1.27 1.27)
					(thickness 0.15)
				)
			)
		)
		(property "Author" "Antmicro"
			(at 267.389672 67.694984 0)
			(layer "F.Fab")
			(hide yes)
			(effects
				(font
					(size 1 1)
					(thickness 0.15)
				)
			)
		)
		(property "Dielectric" "X5R"
			(at 267.389672 67.694984 0)
			(layer "F.Fab")
			(hide yes)
			(effects
				(font
					(size 1 1)
					(thickness 0.15)
				)
			)
		)
		(property "License" "Apache-2.0"
			(at 267.389672 67.694984 0)
			(layer "F.Fab")
			(hide yes)
			(effects
				(font
					(size 1 1)
					(thickness 0.15)
				)
			)
		)
		(property "MPN" "GRM155R61H104KE14D"
			(at 267.389672 67.694984 0)
			(layer "F.Fab")
			(hide yes)
			(effects
				(font
					(size 1 1)
					(thickness 0.15)
				)
			)
		)
		(property "Manufacturer" "Murata"
			(at 267.389672 67.694984 0)
			(layer "F.Fab")
			(hide yes)
			(effects
				(font
					(size 1 1)
					(thickness 0.15)
				)
			)
		)
		(property "Val" "100n"
			(at 267.389672 67.694984 0)
			(layer "F.Fab")
			(hide yes)
			(effects
				(font
					(size 1 1)
					(thickness 0.15)
				)
			)
		)
		(property "Voltage" "50V"
			(at 267.389672 67.694984 0)
			(layer "F.Fab")
			(hide yes)
			(effects
				(font
					(size 1 1)
					(thickness 0.15)
				)
			)
		)
		(sheetname "/Debug FTDI/")
		(sheetfile "debug-ftdi.kicad_sch")
		(attr smd)
		(fp_rect
			(start -0.9659 -0.481258)
			(end 0.9649 0.458742)
			(stroke
				(width 0.05)
				(type solid)
			)
			(fill no)
			(layer "F.CrtYd")
		)
		(fp_line
			(start 0.499 -0.25)
			(end 0.499 0.248)
			(stroke
				(width 0.15)
				(type solid)
			)
			(layer "F.Fab")
		)
		(fp_line
			(start -0.499 -0.25)
			(end 0.499 -0.25)
			(stroke
				(width 0.15)
				(type solid)
			)
			(layer "F.Fab")
		)
		(fp_line
			(start 0.499 0.248)
			(end -0.499 0.248)
			(stroke
				(width 0.15)
				(type solid)
			)
			(layer "F.Fab")
		)
		(fp_line
			(start -0.499 0.248)
			(end -0.499 -0.25)
			(stroke
				(width 0.15)
				(type solid)
			)
			(layer "F.Fab")
		)
		(pad "1" smd roundrect
			(at -0.484 0 90)
			(size 0.59 0.64)
			(layers "F.Cu" "F.Mask" "F.Paste")
			(roundrect_rratio 0.25)
			(net 6 "/Debug FTDI/FTDI_3V3")
			(pintype "passive")
		)
		(pad "2" smd roundrect
			(at 0.484 0 90)
			(size 0.59 0.64)
			(layers "F.Cu" "F.Mask" "F.Paste")
			(roundrect_rratio 0.25)
			(net 1 "GND")
			(pintype "passive")
		)
	)
	(footprint "antmicro-footprints:C_0402_1005Metric"
		(layer "F.Cu")
		(at 100.927344 167.542328 90)
		(descr "Capacitor SMD 0402")
		(tags "capacitor SMD 0402")
		(property "Reference" "C125"
			(at 0 -0.699 90)
			(layer "F.SilkS")
			(hide yes)
			(effects
				(font
					(size 0.7 0.7)
					(thickness 0.15)
				)
				(justify left bottom)
			)
		)
		(property "Value" "C_100n_0402"
			(at -1.022927 2.155213 90)
			(layer "F.Fab")
			(effects
				(font
					(size 0.7 0.7)
					(thickness 0.15)
				)
				(justify left bottom)
			)
		)
		(property "Datasheet" "https://www.murata.com/products/productdetail?partno=GRM155R61H104KE14%23"
			(at 0 0 90)
			(layer "F.Fab")
			(hide yes)
			(effects
				(font
					(size 1.27 1.27)
					(thickness 0.15)
				)
			)
		)
		(property "Author" "Antmicro"
			(at 268.469672 66.614984 0)
			(layer "F.Fab")
			(hide yes)
			(effects
				(font
					(size 1 1)
					(thickness 0.15)
				)
			)
		)
		(property "Dielectric" "X5R"
			(at 268.469672 66.614984 0)
			(layer "F.Fab")
			(hide yes)
			(effects
				(font
					(size 1 1)
					(thickness 0.15)
				)
			)
		)
		(property "License" "Apache-2.0"
			(at 268.469672 66.614984 0)
			(layer "F.Fab")
			(hide yes)
			(effects
				(font
					(size 1 1)
					(thickness 0.15)
				)
			)
		)
		(property "MPN" "GRM155R61H104KE14D"
			(at 268.469672 66.614984 0)
			(layer "F.Fab")
			(hide yes)
			(effects
				(font
					(size 1 1)
					(thickness 0.15)
				)
			)
		)
		(property "Manufacturer" "Murata"
			(at 268.469672 66.614984 0)
			(layer "F.Fab")
			(hide yes)
			(effects
				(font
					(size 1 1)
					(thickness 0.15)
				)
			)
		)
		(property "Val" "100n"
			(at 268.469672 66.614984 0)
			(layer "F.Fab")
			(hide yes)
			(effects
				(font
					(size 1 1)
					(thickness 0.15)
				)
			)
		)
		(property "Voltage" "50V"
			(at 268.469672 66.614984 0)
			(layer "F.Fab")
			(hide yes)
			(effects
				(font
					(size 1 1)
					(thickness 0.15)
				)
			)
		)
		(sheetname "/Debug FTDI/")
		(sheetfile "debug-ftdi.kicad_sch")
		(attr smd)
		(fp_rect
			(start -0.9659 -0.481258)
			(end 0.9649 0.458742)
			(stroke
				(width 0.05)
				(type solid)
			)
			(fill no)
			(layer "F.CrtYd")
		)
		(fp_line
			(start 0.499 -0.25)
			(end 0.499 0.248)
			(stroke
				(width 0.15)
				(type solid)
			)
			(layer "F.Fab")
		)
		(fp_line
			(start -0.499 -0.25)
			(end 0.499 -0.25)
			(stroke
				(width 0.15)
				(type solid)
			)
			(layer "F.Fab")
		)
		(fp_line
			(start 0.499 0.248)
			(end -0.499 0.248)
			(stroke
				(width 0.15)
				(type solid)
			)
			(layer "F.Fab")
		)
		(fp_line
			(start -0.499 0.248)
			(end -0.499 -0.25)
			(stroke
				(width 0.15)
				(type solid)
			)
			(layer "F.Fab")
		)
		(pad "1" smd roundrect
			(at -0.484 0 90)
			(size 0.59 0.64)
			(layers "F.Cu" "F.Mask" "F.Paste")
			(roundrect_rratio 0.25)
			(net 8 "/Debug FTDI/FTDI_VCORE")
			(pintype "passive")
		)
		(pad "2" smd roundrect
			(at 0.484 0 90)
			(size 0.59 0.64)
			(layers "F.Cu" "F.Mask" "F.Paste")
			(roundrect_rratio 0.25)
			(net 1 "GND")
			(pintype "passive")
		)
	)
	(footprint "antmicro-footprints:C_0402_1005Metric"
		(layer "F.Cu")
		(at 105.468344 173.767328)
		(descr "Capacitor SMD 0402")
		(tags "capacitor SMD 0402")
		(property "Reference" "C120"
			(at 0 -0.699 0)
			(layer "F.SilkS")
			(hide yes)
			(effects
				(font
					(size 0.7 0.7)
					(thickness 0.15)
				)
				(justify left bottom)
			)
		)
		(property "Value" "C_100n_0402"
			(at -1.022927 2.155213 0)
			(layer "F.Fab")
			(effects
				(font
					(size 0.7 0.7)
					(thickness 0.15)
				)
				(justify left bottom)
			)
		)
		(property "Datasheet" "https://www.murata.com/products/productdetail?partno=GRM155R61H104KE14%23"
			(at 0 0 0)
			(layer "F.Fab")
			(hide yes)
			(effects
				(font
					(size 1.27 1.27)
					(thickness 0.15)
				)
			)
		)
		(property "Author" "Antmicro"
			(at 0 0 0)
			(layer "F.Fab")
			(hide yes)
			(effects
				(font
					(size 1 1)
					(thickness 0.15)
				)
			)
		)
		(property "Dielectric" "X5R"
			(at 0 0 0)
			(layer "F.Fab")
			(hide yes)
			(effects
				(font
					(size 1 1)
					(thickness 0.15)
				)
			)
		)
		(property "License" "Apache-2.0"
			(at 0 0 0)
			(layer "F.Fab")
			(hide yes)
			(effects
				(font
					(size 1 1)
					(thickness 0.15)
				)
			)
		)
		(property "MPN" "GRM155R61H104KE14D"
			(at 0 0 0)
			(layer "F.Fab")
			(hide yes)
			(effects
				(font
					(size 1 1)
					(thickness 0.15)
				)
			)
		)
		(property "Manufacturer" "Murata"
			(at 0 0 0)
			(layer "F.Fab")
			(hide yes)
			(effects
				(font
					(size 1 1)
					(thickness 0.15)
				)
			)
		)
		(property "Val" "100n"
			(at 0 0 0)
			(layer "F.Fab")
			(hide yes)
			(effects
				(font
					(size 1 1)
					(thickness 0.15)
				)
			)
		)
		(property "Voltage" "50V"
			(at 0 0 0)
			(layer "F.Fab")
			(hide yes)
			(effects
				(font
					(size 1 1)
					(thickness 0.15)
				)
			)
		)
		(sheetname "/Debug FTDI/")
		(sheetfile "debug-ftdi.kicad_sch")
		(attr smd)
		(fp_rect
			(start -0.9659 -0.481258)
			(end 0.9649 0.458742)
			(stroke
				(width 0.05)
				(type solid)
			)
			(fill no)
			(layer "F.CrtYd")
		)
		(fp_line
			(start -0.499 -0.25)
			(end 0.499 -0.25)
			(stroke
				(width 0.15)
				(type solid)
			)
			(layer "F.Fab")
		)
		(fp_line
			(start -0.499 0.248)
			(end -0.499 -0.25)
			(stroke
				(width 0.15)
				(type solid)
			)
			(layer "F.Fab")
		)
		(fp_line
			(start 0.499 -0.25)
			(end 0.499 0.248)
			(stroke
				(width 0.15)
				(type solid)
			)
			(layer "F.Fab")
		)
		(fp_line
			(start 0.499 0.248)
			(end -0.499 0.248)
			(stroke
				(width 0.15)
				(type solid)
			)
			(layer "F.Fab")
		)
		(pad "1" smd roundrect
			(at -0.484 0)
			(size 0.59 0.64)
			(layers "F.Cu" "F.Mask" "F.Paste")
			(roundrect_rratio 0.25)
			(net 6 "/Debug FTDI/FTDI_3V3")
			(pintype "passive")
		)
		(pad "2" smd roundrect
			(at 0.484 0)
			(size 0.59 0.64)
			(layers "F.Cu" "F.Mask" "F.Paste")
			(roundrect_rratio 0.25)
			(net 1 "GND")
			(pintype "passive")
		)
	)
	(footprint "antmicro-footprints:C_0402_1005Metric"
		(layer "F.Cu")
		(at 100.900501 158.958851)
		(descr "Capacitor SMD 0402")
		(tags "capacitor SMD 0402")
		(property "Reference" "C139"
			(at 0 -0.699 0)
			(layer "F.SilkS")
			(hide yes)
			(effects
				(font
					(size 0.7 0.7)
					(thickness 0.15)
				)
				(justify left bottom)
			)
		)
		(property "Value" "C_4u7_0402"
			(at -1.022927 2.155213 0)
			(layer "F.Fab")
			(effects
				(font
					(size 0.7 0.7)
					(thickness 0.15)
				)
				(justify left bottom)
			)
		)
		(property "Datasheet" "https://www.murata.com/products/productdetail?partno=GRM155R61A475MEAA%23"
			(at 0 0 0)
			(layer "F.Fab")
			(hide yes)
			(effects
				(font
					(size 1.27 1.27)
					(thickness 0.15)
				)
			)
		)
		(property "Author" "Antmicro"
			(at 0 0 0)
			(layer "F.Fab")
			(hide yes)
			(effects
				(font
					(size 1 1)
					(thickness 0.15)
				)
			)
		)
		(property "Dielectric" ""
			(at 0 0 0)
			(layer "F.Fab")
			(hide yes)
			(effects
				(font
					(size 1 1)
					(thickness 0.15)
				)
			)
		)
		(property "License" "Apache-2.0"
			(at 0 0 0)
			(layer "F.Fab")
			(hide yes)
			(effects
				(font
					(size 1 1)
					(thickness 0.15)
				)
			)
		)
		(property "MPN" "GRM155R61A475MEAAD"
			(at 0 0 0)
			(layer "F.Fab")
			(hide yes)
			(effects
				(font
					(size 1 1)
					(thickness 0.15)
				)
			)
		)
		(property "Manufacturer" "Murata"
			(at 0 0 0)
			(layer "F.Fab")
			(hide yes)
			(effects
				(font
					(size 1 1)
					(thickness 0.15)
				)
			)
		)
		(property "Val" "4u7"
			(at 0 0 0)
			(layer "F.Fab")
			(hide yes)
			(effects
				(font
					(size 1 1)
					(thickness 0.15)
				)
			)
		)
		(property "Voltage" ""
			(at 0 0 0)
			(layer "F.Fab")
			(hide yes)
			(effects
				(font
					(size 1 1)
					(thickness 0.15)
				)
			)
		)
		(sheetname "/Ethernet/")
		(sheetfile "ethernet.kicad_sch")
		(attr smd)
		(fp_rect
			(start -0.9659 -0.481258)
			(end 0.9649 0.458742)
			(stroke
				(width 0.05)
				(type solid)
			)
			(fill no)
			(layer "F.CrtYd")
		)
		(fp_line
			(start -0.499 -0.25)
			(end 0.499 -0.25)
			(stroke
				(width 0.15)
				(type solid)
			)
			(layer "F.Fab")
		)
		(fp_line
			(start -0.499 0.248)
			(end -0.499 -0.25)
			(stroke
				(width 0.15)
				(type solid)
			)
			(layer "F.Fab")
		)
		(fp_line
			(start 0.499 -0.25)
			(end 0.499 0.248)
			(stroke
				(width 0.15)
				(type solid)
			)
			(layer "F.Fab")
		)
		(fp_line
			(start 0.499 0.248)
			(end -0.499 0.248)
			(stroke
				(width 0.15)
				(type solid)
			)
			(layer "F.Fab")
		)
		(pad "1" smd roundrect
			(at -0.484 0)
			(size 0.59 0.64)
			(layers "F.Cu" "F.Mask" "F.Paste")
			(roundrect_rratio 0.25)
			(net 199 "+1V2")
			(pintype "passive")
		)
		(pad "2" smd roundrect
			(at 0.484 0)
			(size 0.59 0.64)
			(layers "F.Cu" "F.Mask" "F.Paste")
			(roundrect_rratio 0.25)
			(net 1 "GND")
			(pintype "passive")
		)
	)
	(footprint "antmicro-footprints:C_0402_1005Metric"
		(layer "F.Cu")
		(at 100.900501 157.958851)
		(descr "Capacitor SMD 0402")
		(tags "capacitor SMD 0402")
		(property "Reference" "C142"
			(at 0 -0.699 0)
			(layer "F.SilkS")
			(hide yes)
			(effects
				(font
					(size 0.7 0.7)
					(thickness 0.15)
				)
				(justify left bottom)
			)
		)
		(property "Value" "C_470n_0402"
			(at -1.022927 2.155213 0)
			(layer "F.Fab")
			(effects
				(font
					(size 0.7 0.7)
					(thickness 0.15)
				)
				(justify left bottom)
			)
		)
		(property "Datasheet" "https://product.tdk.com/en/search/capacitor/ceramic/mlcc/info?part_no=C1005X5R1E474M050BB"
			(at 0 0 0)
			(layer "F.Fab")
			(hide yes)
			(effects
				(font
					(size 1.27 1.27)
					(thickness 0.15)
				)
			)
		)
		(property "Author" "Antmicro"
			(at 0 0 0)
			(layer "F.Fab")
			(hide yes)
			(effects
				(font
					(size 1 1)
					(thickness 0.15)
				)
			)
		)
		(property "Dielectric" ""
			(at 0 0 0)
			(layer "F.Fab")
			(hide yes)
			(effects
				(font
					(size 1 1)
					(thickness 0.15)
				)
			)
		)
		(property "License" "Apache-2.0"
			(at 0 0 0)
			(layer "F.Fab")
			(hide yes)
			(effects
				(font
					(size 1 1)
					(thickness 0.15)
				)
			)
		)
		(property "MPN" "C1005X5R1E474M050BB"
			(at 0 0 0)
			(layer "F.Fab")
			(hide yes)
			(effects
				(font
					(size 1 1)
					(thickness 0.15)
				)
			)
		)
		(property "Manufacturer" "TDK"
			(at 0 0 0)
			(layer "F.Fab")
			(hide yes)
			(effects
				(font
					(size 1 1)
					(thickness 0.15)
				)
			)
		)
		(property "Val" "470n"
			(at 0 0 0)
			(layer "F.Fab")
			(hide yes)
			(effects
				(font
					(size 1 1)
					(thickness 0.15)
				)
			)
		)
		(property "Voltage" ""
			(at 0 0 0)
			(layer "F.Fab")
			(hide yes)
			(effects
				(font
					(size 1 1)
					(thickness 0.15)
				)
			)
		)
		(sheetname "/Ethernet/")
		(sheetfile "ethernet.kicad_sch")
		(attr smd)
		(fp_rect
			(start -0.9659 -0.481258)
			(end 0.9649 0.458742)
			(stroke
				(width 0.05)
				(type solid)
			)
			(fill no)
			(layer "F.CrtYd")
		)
		(fp_line
			(start -0.499 -0.25)
			(end 0.499 -0.25)
			(stroke
				(width 0.15)
				(type solid)
			)
			(layer "F.Fab")
		)
		(fp_line
			(start -0.499 0.248)
			(end -0.499 -0.25)
			(stroke
				(width 0.15)
				(type solid)
			)
			(layer "F.Fab")
		)
		(fp_line
			(start 0.499 -0.25)
			(end 0.499 0.248)
			(stroke
				(width 0.15)
				(type solid)
			)
			(layer "F.Fab")
		)
		(fp_line
			(start 0.499 0.248)
			(end -0.499 0.248)
			(stroke
				(width 0.15)
				(type solid)
			)
			(layer "F.Fab")
		)
		(pad "1" smd roundrect
			(at -0.484 0)
			(size 0.59 0.64)
			(layers "F.Cu" "F.Mask" "F.Paste")
			(roundrect_rratio 0.25)
			(net 199 "+1V2")
			(pintype "passive")
		)
		(pad "2" smd roundrect
			(at 0.484 0)
			(size 0.59 0.64)
			(layers "F.Cu" "F.Mask" "F.Paste")
			(roundrect_rratio 0.25)
			(net 1 "GND")
			(pintype "passive")
		)
	)
	(footprint "antmicro-footprints:C_0402_1005Metric"
		(layer "F.Cu")
		(at 100.400501 156.458851 90)
		(descr "Capacitor SMD 0402")
		(tags "capacitor SMD 0402")
		(property "Reference" "C159"
			(at 0 -0.699 90)
			(layer "F.SilkS")
			(hide yes)
			(effects
				(font
					(size 0.7 0.7)
					(thickness 0.15)
				)
				(justify left bottom)
			)
		)
		(property "Value" "C_4u7_0402"
			(at -1.022927 2.155213 90)
			(layer "F.Fab")
			(effects
				(font
					(size 0.7 0.7)
					(thickness 0.15)
				)
				(justify left bottom)
			)
		)
		(property "Datasheet" "https://www.murata.com/products/productdetail?partno=GRM155R61A475MEAA%23"
			(at 0 0 90)
			(layer "F.Fab")
			(hide yes)
			(effects
				(font
					(size 1.27 1.27)
					(thickness 0.15)
				)
			)
		)
		(property "Author" "Antmicro"
			(at 256.859352 56.05835 0)
			(layer "F.Fab")
			(hide yes)
			(effects
				(font
					(size 1 1)
					(thickness 0.15)
				)
			)
		)
		(property "Dielectric" ""
			(at 256.859352 56.05835 0)
			(layer "F.Fab")
			(hide yes)
			(effects
				(font
					(size 1 1)
					(thickness 0.15)
				)
			)
		)
		(property "License" "Apache-2.0"
			(at 256.859352 56.05835 0)
			(layer "F.Fab")
			(hide yes)
			(effects
				(font
					(size 1 1)
					(thickness 0.15)
				)
			)
		)
		(property "MPN" "GRM155R61A475MEAAD"
			(at 256.859352 56.05835 0)
			(layer "F.Fab")
			(hide yes)
			(effects
				(font
					(size 1 1)
					(thickness 0.15)
				)
			)
		)
		(property "Manufacturer" "Murata"
			(at 256.859352 56.05835 0)
			(layer "F.Fab")
			(hide yes)
			(effects
				(font
					(size 1 1)
					(thickness 0.15)
				)
			)
		)
		(property "Val" "4u7"
			(at 256.859352 56.05835 0)
			(layer "F.Fab")
			(hide yes)
			(effects
				(font
					(size 1 1)
					(thickness 0.15)
				)
			)
		)
		(property "Voltage" ""
			(at 256.859352 56.05835 0)
			(layer "F.Fab")
			(hide yes)
			(effects
				(font
					(size 1 1)
					(thickness 0.15)
				)
			)
		)
		(sheetname "/Ethernet/")
		(sheetfile "ethernet.kicad_sch")
		(attr smd)
		(fp_rect
			(start -0.9659 -0.481258)
			(end 0.9649 0.458742)
			(stroke
				(width 0.05)
				(type solid)
			)
			(fill no)
			(layer "F.CrtYd")
		)
		(fp_line
			(start 0.499 -0.25)
			(end 0.499 0.248)
			(stroke
				(width 0.15)
				(type solid)
			)
			(layer "F.Fab")
		)
		(fp_line
			(start -0.499 -0.25)
			(end 0.499 -0.25)
			(stroke
				(width 0.15)
				(type solid)
			)
			(layer "F.Fab")
		)
		(fp_line
			(start 0.499 0.248)
			(end -0.499 0.248)
			(stroke
				(width 0.15)
				(type solid)
			)
			(layer "F.Fab")
		)
		(fp_line
			(start -0.499 0.248)
			(end -0.499 -0.25)
			(stroke
				(width 0.15)
				(type solid)
			)
			(layer "F.Fab")
		)
		(pad "1" smd roundrect
			(at -0.484 0 90)
			(size 0.59 0.64)
			(layers "F.Cu" "F.Mask" "F.Paste")
			(roundrect_rratio 0.25)
			(net 1 "GND")
			(pintype "passive")
		)
		(pad "2" smd roundrect
			(at 0.484 0 90)
			(size 0.59 0.64)
			(layers "F.Cu" "F.Mask" "F.Paste")
			(roundrect_rratio 0.25)
			(net 133 "/Ethernet/AVDDL_PLL")
			(pintype "passive")
		)
	)
	(footprint "antmicro-footprints:C_0402_1005Metric"
		(layer "F.Cu")
		(at 88.500501 154.058851 -90)
		(descr "Capacitor SMD 0402")
		(tags "capacitor SMD 0402")
		(property "Reference" "C138"
			(at 0 -0.699 270)
			(layer "F.SilkS")
			(hide yes)
			(effects
				(font
					(size 0.7 0.7)
					(thickness 0.15)
				)
				(justify left bottom)
			)
		)
		(property "Value" "C_470n_0402"
			(at -1.022927 2.155213 270)
			(layer "F.Fab")
			(effects
				(font
					(size 0.7 0.7)
					(thickness 0.15)
				)
				(justify left bottom)
			)
		)
		(property "Datasheet" "https://product.tdk.com/en/search/capacitor/ceramic/mlcc/info?part_no=C1005X5R1E474M050BB"
			(at 0 0 270)
			(layer "F.Fab")
			(hide yes)
			(effects
				(font
					(size 1.27 1.27)
					(thickness 0.15)
				)
			)
		)
		(property "Author" "Antmicro"
			(at -65.55835 242.559352 0)
			(layer "F.Fab")
			(hide yes)
			(effects
				(font
					(size 1 1)
					(thickness 0.15)
				)
			)
		)
		(property "Dielectric" ""
			(at -65.55835 242.559352 0)
			(layer "F.Fab")
			(hide yes)
			(effects
				(font
					(size 1 1)
					(thickness 0.15)
				)
			)
		)
		(property "License" "Apache-2.0"
			(at -65.55835 242.559352 0)
			(layer "F.Fab")
			(hide yes)
			(effects
				(font
					(size 1 1)
					(thickness 0.15)
				)
			)
		)
		(property "MPN" "C1005X5R1E474M050BB"
			(at -65.55835 242.559352 0)
			(layer "F.Fab")
			(hide yes)
			(effects
				(font
					(size 1 1)
					(thickness 0.15)
				)
			)
		)
		(property "Manufacturer" "TDK"
			(at -65.55835 242.559352 0)
			(layer "F.Fab")
			(hide yes)
			(effects
				(font
					(size 1 1)
					(thickness 0.15)
				)
			)
		)
		(property "Val" "470n"
			(at -65.55835 242.559352 0)
			(layer "F.Fab")
			(hide yes)
			(effects
				(font
					(size 1 1)
					(thickness 0.15)
				)
			)
		)
		(property "Voltage" ""
			(at -65.55835 242.559352 0)
			(layer "F.Fab")
			(hide yes)
			(effects
				(font
					(size 1 1)
					(thickness 0.15)
				)
			)
		)
		(sheetname "/Ethernet/")
		(sheetfile "ethernet.kicad_sch")
		(attr smd)
		(fp_rect
			(start -0.9659 -0.481258)
			(end 0.9649 0.458742)
			(stroke
				(width 0.05)
				(type solid)
			)
			(fill no)
			(layer "F.CrtYd")
		)
		(fp_line
			(start -0.499 0.248)
			(end -0.499 -0.25)
			(stroke
				(width 0.15)
				(type solid)
			)
			(layer "F.Fab")
		)
		(fp_line
			(start 0.499 0.248)
			(end -0.499 0.248)
			(stroke
				(width 0.15)
				(type solid)
			)
			(layer "F.Fab")
		)
		(fp_line
			(start -0.499 -0.25)
			(end 0.499 -0.25)
			(stroke
				(width 0.15)
				(type solid)
			)
			(layer "F.Fab")
		)
		(fp_line
			(start 0.499 -0.25)
			(end 0.499 0.248)
			(stroke
				(width 0.15)
				(type solid)
			)
			(layer "F.Fab")
		)
		(pad "1" smd roundrect
			(at -0.484 0 270)
			(size 0.59 0.64)
			(layers "F.Cu" "F.Mask" "F.Paste")
			(roundrect_rratio 0.25)
			(net 200 "+3V3")
			(pintype "passive")
		)
		(pad "2" smd roundrect
			(at 0.484 0 270)
			(size 0.59 0.64)
			(layers "F.Cu" "F.Mask" "F.Paste")
			(roundrect_rratio 0.25)
			(net 1 "GND")
			(pintype "passive")
		)
	)
	(footprint "antmicro-footprints:C_0402_1005Metric"
		(layer "F.Cu")
		(at 101.500501 156.458851 90)
		(descr "Capacitor SMD 0402")
		(tags "capacitor SMD 0402")
		(property "Reference" "C157"
			(at 0 -0.699 90)
			(layer "F.SilkS")
			(hide yes)
			(effects
				(font
					(size 0.7 0.7)
					(thickness 0.15)
				)
				(justify left bottom)
			)
		)
		(property "Value" "C_100n_0402"
			(at -1.022927 2.155213 90)
			(layer "F.Fab")
			(effects
				(font
					(size 0.7 0.7)
					(thickness 0.15)
				)
				(justify left bottom)
			)
		)
		(property "Datasheet" "https://www.murata.com/products/productdetail?partno=GRM155R61H104KE14%23"
			(at 0 0 90)
			(layer "F.Fab")
			(hide yes)
			(effects
				(font
					(size 1.27 1.27)
					(thickness 0.15)
				)
			)
		)
		(property "Author" "Antmicro"
			(at 257.959352 54.95835 0)
			(layer "F.Fab")
			(hide yes)
			(effects
				(font
					(size 1 1)
					(thickness 0.15)
				)
			)
		)
		(property "Dielectric" "X5R"
			(at 257.959352 54.95835 0)
			(layer "F.Fab")
			(hide yes)
			(effects
				(font
					(size 1 1)
					(thickness 0.15)
				)
			)
		)
		(property "License" "Apache-2.0"
			(at 257.959352 54.95835 0)
			(layer "F.Fab")
			(hide yes)
			(effects
				(font
					(size 1 1)
					(thickness 0.15)
				)
			)
		)
		(property "MPN" "GRM155R61H104KE14D"
			(at 257.959352 54.95835 0)
			(layer "F.Fab")
			(hide yes)
			(effects
				(font
					(size 1 1)
					(thickness 0.15)
				)
			)
		)
		(property "Manufacturer" "Murata"
			(at 257.959352 54.95835 0)
			(layer "F.Fab")
			(hide yes)
			(effects
				(font
					(size 1 1)
					(thickness 0.15)
				)
			)
		)
		(property "Val" "100n"
			(at 257.959352 54.95835 0)
			(layer "F.Fab")
			(hide yes)
			(effects
				(font
					(size 1 1)
					(thickness 0.15)
				)
			)
		)
		(property "Voltage" "50V"
			(at 257.959352 54.95835 0)
			(layer "F.Fab")
			(hide yes)
			(effects
				(font
					(size 1 1)
					(thickness 0.15)
				)
			)
		)
		(sheetname "/Ethernet/")
		(sheetfile "ethernet.kicad_sch")
		(attr smd)
		(fp_rect
			(start -0.9659 -0.481258)
			(end 0.9649 0.458742)
			(stroke
				(width 0.05)
				(type solid)
			)
			(fill no)
			(layer "F.CrtYd")
		)
		(fp_line
			(start 0.499 -0.25)
			(end 0.499 0.248)
			(stroke
				(width 0.15)
				(type solid)
			)
			(layer "F.Fab")
		)
		(fp_line
			(start -0.499 -0.25)
			(end 0.499 -0.25)
			(stroke
				(width 0.15)
				(type solid)
			)
			(layer "F.Fab")
		)
		(fp_line
			(start 0.499 0.248)
			(end -0.499 0.248)
			(stroke
				(width 0.15)
				(type solid)
			)
			(layer "F.Fab")
		)
		(fp_line
			(start -0.499 0.248)
			(end -0.499 -0.25)
			(stroke
				(width 0.15)
				(type solid)
			)
			(layer "F.Fab")
		)
		(pad "1" smd roundrect
			(at -0.484 0 90)
			(size 0.59 0.64)
			(layers "F.Cu" "F.Mask" "F.Paste")
			(roundrect_rratio 0.25)
			(net 1 "GND")
			(pintype "passive")
		)
		(pad "2" smd roundrect
			(at 0.484 0 90)
			(size 0.59 0.64)
			(layers "F.Cu" "F.Mask" "F.Paste")
			(roundrect_rratio 0.25)
			(net 133 "/Ethernet/AVDDL_PLL")
			(pintype "passive")
		)
	)
	(footprint "antmicro-footprints:C_0402_1005Metric"
		(layer "F.Cu")
		(at 88.500501 151.733157 90)
		(descr "Capacitor SMD 0402")
		(tags "capacitor SMD 0402")
		(property "Reference" "C149"
			(at 0 -0.699 90)
			(layer "F.SilkS")
			(hide yes)
			(effects
				(font
					(size 0.7 0.7)
					(thickness 0.15)
				)
				(justify left bottom)
			)
		)
		(property "Value" "C_470n_0402"
			(at -1.022927 2.155213 90)
			(layer "F.Fab")
			(effects
				(font
					(size 0.7 0.7)
					(thickness 0.15)
				)
				(justify left bottom)
			)
		)
		(property "Datasheet" "https://product.tdk.com/en/search/capacitor/ceramic/mlcc/info?part_no=C1005X5R1E474M050BB"
			(at 0 0 90)
			(layer "F.Fab")
			(hide yes)
			(effects
				(font
					(size 1.27 1.27)
					(thickness 0.15)
				)
			)
		)
		(property "Author" "Antmicro"
			(at 240.233658 63.232656 0)
			(layer "F.Fab")
			(hide yes)
			(effects
				(font
					(size 1 1)
					(thickness 0.15)
				)
			)
		)
		(property "Dielectric" ""
			(at 240.233658 63.232656 0)
			(layer "F.Fab")
			(hide yes)
			(effects
				(font
					(size 1 1)
					(thickness 0.15)
				)
			)
		)
		(property "License" "Apache-2.0"
			(at 240.233658 63.232656 0)
			(layer "F.Fab")
			(hide yes)
			(effects
				(font
					(size 1 1)
					(thickness 0.15)
				)
			)
		)
		(property "MPN" "C1005X5R1E474M050BB"
			(at 240.233658 63.232656 0)
			(layer "F.Fab")
			(hide yes)
			(effects
				(font
					(size 1 1)
					(thickness 0.15)
				)
			)
		)
		(property "Manufacturer" "TDK"
			(at 240.233658 63.232656 0)
			(layer "F.Fab")
			(hide yes)
			(effects
				(font
					(size 1 1)
					(thickness 0.15)
				)
			)
		)
		(property "Val" "470n"
			(at 240.233658 63.232656 0)
			(layer "F.Fab")
			(hide yes)
			(effects
				(font
					(size 1 1)
					(thickness 0.15)
				)
			)
		)
		(property "Voltage" ""
			(at 240.233658 63.232656 0)
			(layer "F.Fab")
			(hide yes)
			(effects
				(font
					(size 1 1)
					(thickness 0.15)
				)
			)
		)
		(sheetname "/Ethernet/")
		(sheetfile "ethernet.kicad_sch")
		(attr smd)
		(fp_rect
			(start -0.9659 -0.481258)
			(end 0.9649 0.458742)
			(stroke
				(width 0.05)
				(type solid)
			)
			(fill no)
			(layer "F.CrtYd")
		)
		(fp_line
			(start 0.499 -0.25)
			(end 0.499 0.248)
			(stroke
				(width 0.15)
				(type solid)
			)
			(layer "F.Fab")
		)
		(fp_line
			(start -0.499 -0.25)
			(end 0.499 -0.25)
			(stroke
				(width 0.15)
				(type solid)
			)
			(layer "F.Fab")
		)
		(fp_line
			(start 0.499 0.248)
			(end -0.499 0.248)
			(stroke
				(width 0.15)
				(type solid)
			)
			(layer "F.Fab")
		)
		(fp_line
			(start -0.499 0.248)
			(end -0.499 -0.25)
			(stroke
				(width 0.15)
				(type solid)
			)
			(layer "F.Fab")
		)
		(pad "1" smd roundrect
			(at -0.484 0 90)
			(size 0.59 0.64)
			(layers "F.Cu" "F.Mask" "F.Paste")
			(roundrect_rratio 0.25)
			(net 199 "+1V2")
			(pintype "passive")
		)
		(pad "2" smd roundrect
			(at 0.484 0 90)
			(size 0.59 0.64)
			(layers "F.Cu" "F.Mask" "F.Paste")
			(roundrect_rratio 0.25)
			(net 1 "GND")
			(pintype "passive")
		)
	)
	(footprint "antmicro-footprints:C_0402_1005Metric"
		(layer "F.Cu")
		(at 102.600501 156.458851 90)
		(descr "Capacitor SMD 0402")
		(tags "capacitor SMD 0402")
		(property "Reference" "C154"
			(at 0 -0.699 90)
			(layer "F.SilkS")
			(hide yes)
			(effects
				(font
					(size 0.7 0.7)
					(thickness 0.15)
				)
				(justify left bottom)
			)
		)
		(property "Value" "C_10n_0402"
			(at -1.022927 2.155213 90)
			(layer "F.Fab")
			(effects
				(font
					(size 0.7 0.7)
					(thickness 0.15)
				)
				(justify left bottom)
			)
		)
		(property "Datasheet" "https://www.murata.com/products/productdetail?partno=GRM155R71H103KA88%23"
			(at 0 0 90)
			(layer "F.Fab")
			(hide yes)
			(effects
				(font
					(size 1.27 1.27)
					(thickness 0.15)
				)
			)
		)
		(property "Author" "Antmicro"
			(at 259.059352 53.85835 0)
			(layer "F.Fab")
			(hide yes)
			(effects
				(font
					(size 1 1)
					(thickness 0.15)
				)
			)
		)
		(property "Dielectric" "X7R"
			(at 259.059352 53.85835 0)
			(layer "F.Fab")
			(hide yes)
			(effects
				(font
					(size 1 1)
					(thickness 0.15)
				)
			)
		)
		(property "License" "Apache-2.0"
			(at 259.059352 53.85835 0)
			(layer "F.Fab")
			(hide yes)
			(effects
				(font
					(size 1 1)
					(thickness 0.15)
				)
			)
		)
		(property "MPN" "GRM155R71H103KA88D"
			(at 259.059352 53.85835 0)
			(layer "F.Fab")
			(hide yes)
			(effects
				(font
					(size 1 1)
					(thickness 0.15)
				)
			)
		)
		(property "Manufacturer" "Murata"
			(at 259.059352 53.85835 0)
			(layer "F.Fab")
			(hide yes)
			(effects
				(font
					(size 1 1)
					(thickness 0.15)
				)
			)
		)
		(property "Val" "10n"
			(at 259.059352 53.85835 0)
			(layer "F.Fab")
			(hide yes)
			(effects
				(font
					(size 1 1)
					(thickness 0.15)
				)
			)
		)
		(property "Voltage" "50V"
			(at 259.059352 53.85835 0)
			(layer "F.Fab")
			(hide yes)
			(effects
				(font
					(size 1 1)
					(thickness 0.15)
				)
			)
		)
		(sheetname "/Ethernet/")
		(sheetfile "ethernet.kicad_sch")
		(attr smd)
		(fp_rect
			(start -0.9659 -0.481258)
			(end 0.9649 0.458742)
			(stroke
				(width 0.05)
				(type solid)
			)
			(fill no)
			(layer "F.CrtYd")
		)
		(fp_line
			(start 0.499 -0.25)
			(end 0.499 0.248)
			(stroke
				(width 0.15)
				(type solid)
			)
			(layer "F.Fab")
		)
		(fp_line
			(start -0.499 -0.25)
			(end 0.499 -0.25)
			(stroke
				(width 0.15)
				(type solid)
			)
			(layer "F.Fab")
		)
		(fp_line
			(start 0.499 0.248)
			(end -0.499 0.248)
			(stroke
				(width 0.15)
				(type solid)
			)
			(layer "F.Fab")
		)
		(fp_line
			(start -0.499 0.248)
			(end -0.499 -0.25)
			(stroke
				(width 0.15)
				(type solid)
			)
			(layer "F.Fab")
		)
		(pad "1" smd roundrect
			(at -0.484 0 90)
			(size 0.59 0.64)
			(layers "F.Cu" "F.Mask" "F.Paste")
			(roundrect_rratio 0.25)
			(net 1 "GND")
			(pintype "passive")
		)
		(pad "2" smd roundrect
			(at 0.484 0 90)
			(size 0.59 0.64)
			(layers "F.Cu" "F.Mask" "F.Paste")
			(roundrect_rratio 0.25)
			(net 133 "/Ethernet/AVDDL_PLL")
			(pintype "passive")
		)
	)
	(footprint "antmicro-footprints:C_0402_1005Metric"
		(layer "F.Cu")
		(at 87.400501 157.458851 -90)
		(descr "Capacitor SMD 0402")
		(tags "capacitor SMD 0402")
		(property "Reference" "C150"
			(at 0 -0.699 270)
			(layer "F.SilkS")
			(hide yes)
			(effects
				(font
					(size 0.7 0.7)
					(thickness 0.15)
				)
				(justify left bottom)
			)
		)
		(property "Value" "C_10n_0402"
			(at -1.022927 2.155213 270)
			(layer "F.Fab")
			(effects
				(font
					(size 0.7 0.7)
					(thickness 0.15)
				)
				(justify left bottom)
			)
		)
		(property "Datasheet" "https://www.murata.com/products/productdetail?partno=GRM155R71H103KA88%23"
			(at 0 0 270)
			(layer "F.Fab")
			(hide yes)
			(effects
				(font
					(size 1.27 1.27)
					(thickness 0.15)
				)
			)
		)
		(property "Author" "Antmicro"
			(at -70.05835 244.859352 0)
			(layer "F.Fab")
			(hide yes)
			(effects
				(font
					(size 1 1)
					(thickness 0.15)
				)
			)
		)
		(property "Dielectric" "X7R"
			(at -70.05835 244.859352 0)
			(layer "F.Fab")
			(hide yes)
			(effects
				(font
					(size 1 1)
					(thickness 0.15)
				)
			)
		)
		(property "License" "Apache-2.0"
			(at -70.05835 244.859352 0)
			(layer "F.Fab")
			(hide yes)
			(effects
				(font
					(size 1 1)
					(thickness 0.15)
				)
			)
		)
		(property "MPN" "GRM155R71H103KA88D"
			(at -70.05835 244.859352 0)
			(layer "F.Fab")
			(hide yes)
			(effects
				(font
					(size 1 1)
					(thickness 0.15)
				)
			)
		)
		(property "Manufacturer" "Murata"
			(at -70.05835 244.859352 0)
			(layer "F.Fab")
			(hide yes)
			(effects
				(font
					(size 1 1)
					(thickness 0.15)
				)
			)
		)
		(property "Val" "10n"
			(at -70.05835 244.859352 0)
			(layer "F.Fab")
			(hide yes)
			(effects
				(font
					(size 1 1)
					(thickness 0.15)
				)
			)
		)
		(property "Voltage" "50V"
			(at -70.05835 244.859352 0)
			(layer "F.Fab")
			(hide yes)
			(effects
				(font
					(size 1 1)
					(thickness 0.15)
				)
			)
		)
		(sheetname "/Ethernet/")
		(sheetfile "ethernet.kicad_sch")
		(attr smd)
		(fp_rect
			(start -0.9659 -0.481258)
			(end 0.9649 0.458742)
			(stroke
				(width 0.05)
				(type solid)
			)
			(fill no)
			(layer "F.CrtYd")
		)
		(fp_line
			(start -0.499 0.248)
			(end -0.499 -0.25)
			(stroke
				(width 0.15)
				(type solid)
			)
			(layer "F.Fab")
		)
		(fp_line
			(start 0.499 0.248)
			(end -0.499 0.248)
			(stroke
				(width 0.15)
				(type solid)
			)
			(layer "F.Fab")
		)
		(fp_line
			(start -0.499 -0.25)
			(end 0.499 -0.25)
			(stroke
				(width 0.15)
				(type solid)
			)
			(layer "F.Fab")
		)
		(fp_line
			(start 0.499 -0.25)
			(end 0.499 0.248)
			(stroke
				(width 0.15)
				(type solid)
			)
			(layer "F.Fab")
		)
		(pad "1" smd roundrect
			(at -0.484 0 270)
			(size 0.59 0.64)
			(layers "F.Cu" "F.Mask" "F.Paste")
			(roundrect_rratio 0.25)
			(net 199 "+1V2")
			(pintype "passive")
		)
		(pad "2" smd roundrect
			(at 0.484 0 270)
			(size 0.59 0.64)
			(layers "F.Cu" "F.Mask" "F.Paste")
			(roundrect_rratio 0.25)
			(net 1 "GND")
			(pintype "passive")
		)
	)
	(footprint "antmicro-footprints:C_0402_1005Metric"
		(layer "F.Cu")
		(at 87.400501 154.058851 -90)
		(descr "Capacitor SMD 0402")
		(tags "capacitor SMD 0402")
		(property "Reference" "C147"
			(at 0 -0.699 270)
			(layer "F.SilkS")
			(hide yes)
			(effects
				(font
					(size 0.7 0.7)
					(thickness 0.15)
				)
				(justify left bottom)
			)
		)
		(property "Value" "C_10n_0402"
			(at -1.022927 2.155213 270)
			(layer "F.Fab")
			(effects
				(font
					(size 0.7 0.7)
					(thickness 0.15)
				)
				(justify left bottom)
			)
		)
		(property "Datasheet" "https://www.murata.com/products/productdetail?partno=GRM155R71H103KA88%23"
			(at 0 0 270)
			(layer "F.Fab")
			(hide yes)
			(effects
				(font
					(size 1.27 1.27)
					(thickness 0.15)
				)
			)
		)
		(property "Author" "Antmicro"
			(at -66.65835 241.459352 0)
			(layer "F.Fab")
			(hide yes)
			(effects
				(font
					(size 1 1)
					(thickness 0.15)
				)
			)
		)
		(property "Dielectric" "X7R"
			(at -66.65835 241.459352 0)
			(layer "F.Fab")
			(hide yes)
			(effects
				(font
					(size 1 1)
					(thickness 0.15)
				)
			)
		)
		(property "License" "Apache-2.0"
			(at -66.65835 241.459352 0)
			(layer "F.Fab")
			(hide yes)
			(effects
				(font
					(size 1 1)
					(thickness 0.15)
				)
			)
		)
		(property "MPN" "GRM155R71H103KA88D"
			(at -66.65835 241.459352 0)
			(layer "F.Fab")
			(hide yes)
			(effects
				(font
					(size 1 1)
					(thickness 0.15)
				)
			)
		)
		(property "Manufacturer" "Murata"
			(at -66.65835 241.459352 0)
			(layer "F.Fab")
			(hide yes)
			(effects
				(font
					(size 1 1)
					(thickness 0.15)
				)
			)
		)
		(property "Val" "10n"
			(at -66.65835 241.459352 0)
			(layer "F.Fab")
			(hide yes)
			(effects
				(font
					(size 1 1)
					(thickness 0.15)
				)
			)
		)
		(property "Voltage" "50V"
			(at -66.65835 241.459352 0)
			(layer "F.Fab")
			(hide yes)
			(effects
				(font
					(size 1 1)
					(thickness 0.15)
				)
			)
		)
		(sheetname "/Ethernet/")
		(sheetfile "ethernet.kicad_sch")
		(attr smd)
		(fp_rect
			(start -0.9659 -0.481258)
			(end 0.9649 0.458742)
			(stroke
				(width 0.05)
				(type solid)
			)
			(fill no)
			(layer "F.CrtYd")
		)
		(fp_line
			(start -0.499 0.248)
			(end -0.499 -0.25)
			(stroke
				(width 0.15)
				(type solid)
			)
			(layer "F.Fab")
		)
		(fp_line
			(start 0.499 0.248)
			(end -0.499 0.248)
			(stroke
				(width 0.15)
				(type solid)
			)
			(layer "F.Fab")
		)
		(fp_line
			(start -0.499 -0.25)
			(end 0.499 -0.25)
			(stroke
				(width 0.15)
				(type solid)
			)
			(layer "F.Fab")
		)
		(fp_line
			(start 0.499 -0.25)
			(end 0.499 0.248)
			(stroke
				(width 0.15)
				(type solid)
			)
			(layer "F.Fab")
		)
		(pad "1" smd roundrect
			(at -0.484 0 270)
			(size 0.59 0.64)
			(layers "F.Cu" "F.Mask" "F.Paste")
			(roundrect_rratio 0.25)
			(net 200 "+3V3")
			(pintype "passive")
		)
		(pad "2" smd roundrect
			(at 0.484 0 270)
			(size 0.59 0.64)
			(layers "F.Cu" "F.Mask" "F.Paste")
			(roundrect_rratio 0.25)
			(net 1 "GND")
			(pintype "passive")
		)
	)
	(footprint "antmicro-footprints:C_0402_1005Metric"
		(layer "F.Cu")
		(at 87.400501 151.733157 90)
		(descr "Capacitor SMD 0402")
		(tags "capacitor SMD 0402")
		(property "Reference" "C156"
			(at 0 -0.699 90)
			(layer "F.SilkS")
			(hide yes)
			(effects
				(font
					(size 0.7 0.7)
					(thickness 0.15)
				)
				(justify left bottom)
			)
		)
		(property "Value" "C_10n_0402"
			(at -1.022927 2.155213 90)
			(layer "F.Fab")
			(effects
				(font
					(size 0.7 0.7)
					(thickness 0.15)
				)
				(justify left bottom)
			)
		)
		(property "Datasheet" "https://www.murata.com/products/productdetail?partno=GRM155R71H103KA88%23"
			(at 0 0 90)
			(layer "F.Fab")
			(hide yes)
			(effects
				(font
					(size 1.27 1.27)
					(thickness 0.15)
				)
			)
		)
		(property "Author" "Antmicro"
			(at 239.133658 64.332656 0)
			(layer "F.Fab")
			(hide yes)
			(effects
				(font
					(size 1 1)
					(thickness 0.15)
				)
			)
		)
		(property "Dielectric" "X7R"
			(at 239.133658 64.332656 0)
			(layer "F.Fab")
			(hide yes)
			(effects
				(font
					(size 1 1)
					(thickness 0.15)
				)
			)
		)
		(property "License" "Apache-2.0"
			(at 239.133658 64.332656 0)
			(layer "F.Fab")
			(hide yes)
			(effects
				(font
					(size 1 1)
					(thickness 0.15)
				)
			)
		)
		(property "MPN" "GRM155R71H103KA88D"
			(at 239.133658 64.332656 0)
			(layer "F.Fab")
			(hide yes)
			(effects
				(font
					(size 1 1)
					(thickness 0.15)
				)
			)
		)
		(property "Manufacturer" "Murata"
			(at 239.133658 64.332656 0)
			(layer "F.Fab")
			(hide yes)
			(effects
				(font
					(size 1 1)
					(thickness 0.15)
				)
			)
		)
		(property "Val" "10n"
			(at 239.133658 64.332656 0)
			(layer "F.Fab")
			(hide yes)
			(effects
				(font
					(size 1 1)
					(thickness 0.15)
				)
			)
		)
		(property "Voltage" "50V"
			(at 239.133658 64.332656 0)
			(layer "F.Fab")
			(hide yes)
			(effects
				(font
					(size 1 1)
					(thickness 0.15)
				)
			)
		)
		(sheetname "/Ethernet/")
		(sheetfile "ethernet.kicad_sch")
		(attr smd)
		(fp_rect
			(start -0.9659 -0.481258)
			(end 0.9649 0.458742)
			(stroke
				(width 0.05)
				(type solid)
			)
			(fill no)
			(layer "F.CrtYd")
		)
		(fp_line
			(start 0.499 -0.25)
			(end 0.499 0.248)
			(stroke
				(width 0.15)
				(type solid)
			)
			(layer "F.Fab")
		)
		(fp_line
			(start -0.499 -0.25)
			(end 0.499 -0.25)
			(stroke
				(width 0.15)
				(type solid)
			)
			(layer "F.Fab")
		)
		(fp_line
			(start 0.499 0.248)
			(end -0.499 0.248)
			(stroke
				(width 0.15)
				(type solid)
			)
			(layer "F.Fab")
		)
		(fp_line
			(start -0.499 0.248)
			(end -0.499 -0.25)
			(stroke
				(width 0.15)
				(type solid)
			)
			(layer "F.Fab")
		)
		(pad "1" smd roundrect
			(at -0.484 0 90)
			(size 0.59 0.64)
			(layers "F.Cu" "F.Mask" "F.Paste")
			(roundrect_rratio 0.25)
			(net 199 "+1V2")
			(pintype "passive")
		)
		(pad "2" smd roundrect
			(at 0.484 0 90)
			(size 0.59 0.64)
			(layers "F.Cu" "F.Mask" "F.Paste")
			(roundrect_rratio 0.25)
			(net 1 "GND")
			(pintype "passive")
		)
	)
	(footprint "antmicro-footprints:C_0402_1005Metric"
		(layer "F.Cu")
		(at 102.800501 154.958851 180)
		(descr "Capacitor SMD 0402")
		(tags "capacitor SMD 0402")
		(property "Reference" "C163"
			(at 0 -0.699 180)
			(layer "F.SilkS")
			(hide yes)
			(effects
				(font
					(size 0.7 0.7)
					(thickness 0.15)
				)
				(justify left bottom)
			)
		)
		(property "Value" "C_18p_0402"
			(at -1.022927 2.155213 180)
			(layer "F.Fab")
			(effects
				(font
					(size 0.7 0.7)
					(thickness 0.15)
				)
				(justify left bottom)
			)
		)
		(property "Datasheet" "https://product.samsungsem.com/mlcc/CL05C180JB51PN.do"
			(at 0 0 180)
			(layer "F.Fab")
			(hide yes)
			(effects
				(font
					(size 1.27 1.27)
					(thickness 0.15)
				)
			)
		)
		(property "Author" "Antmicro"
			(at 205.601002 309.917702 0)
			(layer "F.Fab")
			(hide yes)
			(effects
				(font
					(size 1 1)
					(thickness 0.15)
				)
			)
		)
		(property "Dielectric" ""
			(at 205.601002 309.917702 0)
			(layer "F.Fab")
			(hide yes)
			(effects
				(font
					(size 1 1)
					(thickness 0.15)
				)
			)
		)
		(property "License" "Apache-2.0"
			(at 205.601002 309.917702 0)
			(layer "F.Fab")
			(hide yes)
			(effects
				(font
					(size 1 1)
					(thickness 0.15)
				)
			)
		)
		(property "MPN" "CL05C180JB51PNC"
			(at 205.601002 309.917702 0)
			(layer "F.Fab")
			(hide yes)
			(effects
				(font
					(size 1 1)
					(thickness 0.15)
				)
			)
		)
		(property "Manufacturer" "Samsung Electro-Mechanics"
			(at 205.601002 309.917702 0)
			(layer "F.Fab")
			(hide yes)
			(effects
				(font
					(size 1 1)
					(thickness 0.15)
				)
			)
		)
		(property "Val" "18p"
			(at 205.601002 309.917702 0)
			(layer "F.Fab")
			(hide yes)
			(effects
				(font
					(size 1 1)
					(thickness 0.15)
				)
			)
		)
		(property "Voltage" ""
			(at 205.601002 309.917702 0)
			(layer "F.Fab")
			(hide yes)
			(effects
				(font
					(size 1 1)
					(thickness 0.15)
				)
			)
		)
		(sheetname "/Ethernet/")
		(sheetfile "ethernet.kicad_sch")
		(attr smd)
		(fp_rect
			(start -0.9659 -0.481258)
			(end 0.9649 0.458742)
			(stroke
				(width 0.05)
				(type solid)
			)
			(fill no)
			(layer "F.CrtYd")
		)
		(fp_line
			(start 0.499 0.248)
			(end -0.499 0.248)
			(stroke
				(width 0.15)
				(type solid)
			)
			(layer "F.Fab")
		)
		(fp_line
			(start 0.499 -0.25)
			(end 0.499 0.248)
			(stroke
				(width 0.15)
				(type solid)
			)
			(layer "F.Fab")
		)
		(fp_line
			(start -0.499 0.248)
			(end -0.499 -0.25)
			(stroke
				(width 0.15)
				(type solid)
			)
			(layer "F.Fab")
		)
		(fp_line
			(start -0.499 -0.25)
			(end 0.499 -0.25)
			(stroke
				(width 0.15)
				(type solid)
			)
			(layer "F.Fab")
		)
		(pad "1" smd roundrect
			(at -0.484 0 180)
			(size 0.59 0.64)
			(layers "F.Cu" "F.Mask" "F.Paste")
			(roundrect_rratio 0.25)
			(net 1 "GND")
			(pintype "passive")
		)
		(pad "2" smd roundrect
			(at 0.484 0 180)
			(size 0.59 0.64)
			(layers "F.Cu" "F.Mask" "F.Paste")
			(roundrect_rratio 0.25)
			(net 300 "Net-(U15-XO)")
			(pintype "passive")
		)
	)
	(footprint "antmicro-footprints:C_0402_1005Metric"
		(layer "F.Cu")
		(at 104.000501 150.158851)
		(descr "Capacitor SMD 0402")
		(tags "capacitor SMD 0402")
		(property "Reference" "C162"
			(at 0 -0.699 0)
			(layer "F.SilkS")
			(hide yes)
			(effects
				(font
					(size 0.7 0.7)
					(thickness 0.15)
				)
				(justify left bottom)
			)
		)
		(property "Value" "C_18p_0402"
			(at -1.022927 2.155213 0)
			(layer "F.Fab")
			(effects
				(font
					(size 0.7 0.7)
					(thickness 0.15)
				)
				(justify left bottom)
			)
		)
		(property "Datasheet" "https://product.samsungsem.com/mlcc/CL05C180JB51PN.do"
			(at 0 0 0)
			(layer "F.Fab")
			(hide yes)
			(effects
				(font
					(size 1.27 1.27)
					(thickness 0.15)
				)
			)
		)
		(property "Author" "Antmicro"
			(at 0 0 0)
			(layer "F.Fab")
			(hide yes)
			(effects
				(font
					(size 1 1)
					(thickness 0.15)
				)
			)
		)
		(property "Dielectric" ""
			(at 0 0 0)
			(layer "F.Fab")
			(hide yes)
			(effects
				(font
					(size 1 1)
					(thickness 0.15)
				)
			)
		)
		(property "License" "Apache-2.0"
			(at 0 0 0)
			(layer "F.Fab")
			(hide yes)
			(effects
				(font
					(size 1 1)
					(thickness 0.15)
				)
			)
		)
		(property "MPN" "CL05C180JB51PNC"
			(at 0 0 0)
			(layer "F.Fab")
			(hide yes)
			(effects
				(font
					(size 1 1)
					(thickness 0.15)
				)
			)
		)
		(property "Manufacturer" "Samsung Electro-Mechanics"
			(at 0 0 0)
			(layer "F.Fab")
			(hide yes)
			(effects
				(font
					(size 1 1)
					(thickness 0.15)
				)
			)
		)
		(property "Val" "18p"
			(at 0 0 0)
			(layer "F.Fab")
			(hide yes)
			(effects
				(font
					(size 1 1)
					(thickness 0.15)
				)
			)
		)
		(property "Voltage" ""
			(at 0 0 0)
			(layer "F.Fab")
			(hide yes)
			(effects
				(font
					(size 1 1)
					(thickness 0.15)
				)
			)
		)
		(sheetname "/Ethernet/")
		(sheetfile "ethernet.kicad_sch")
		(attr smd)
		(fp_rect
			(start -0.9659 -0.481258)
			(end 0.9649 0.458742)
			(stroke
				(width 0.05)
				(type solid)
			)
			(fill no)
			(layer "F.CrtYd")
		)
		(fp_line
			(start -0.499 -0.25)
			(end 0.499 -0.25)
			(stroke
				(width 0.15)
				(type solid)
			)
			(layer "F.Fab")
		)
		(fp_line
			(start -0.499 0.248)
			(end -0.499 -0.25)
			(stroke
				(width 0.15)
				(type solid)
			)
			(layer "F.Fab")
		)
		(fp_line
			(start 0.499 -0.25)
			(end 0.499 0.248)
			(stroke
				(width 0.15)
				(type solid)
			)
			(layer "F.Fab")
		)
		(fp_line
			(start 0.499 0.248)
			(end -0.499 0.248)
			(stroke
				(width 0.15)
				(type solid)
			)
			(layer "F.Fab")
		)
		(pad "1" smd roundrect
			(at -0.484 0)
			(size 0.59 0.64)
			(layers "F.Cu" "F.Mask" "F.Paste")
			(roundrect_rratio 0.25)
			(net 1 "GND")
			(pintype "passive")
		)
		(pad "2" smd roundrect
			(at 0.484 0)
			(size 0.59 0.64)
			(layers "F.Cu" "F.Mask" "F.Paste")
			(roundrect_rratio 0.25)
			(net 299 "Net-(U15-XI)")
			(pintype "passive")
		)
	)
	(footprint "antmicro-footprints:FB_0603_1608Metric"
		(layer "F.Cu")
		(at 104.500501 156.223149 180)
		(property "Reference" "FB6"
			(at 0 -0.8 180)
			(layer "F.SilkS")
			(hide yes)
			(effects
				(font
					(size 0.7 0.7)
					(thickness 0.15)
				)
				(justify left bottom)
			)
		)
		(property "Value" "FB_120Z_2A_Murata-BLM18PG_0603"
			(at 0 1.5 180)
			(layer "F.Fab")
			(effects
				(font
					(size 0.7 0.7)
					(thickness 0.15)
				)
				(justify left bottom)
			)
		)
		(property "Datasheet" "https://www.murata.com/en-us/products/productdata/8796738650142/ENFA0003.pdf"
			(at 0 0 180)
			(layer "F.Fab")
			(hide yes)
			(effects
				(font
					(size 1.27 1.27)
					(thickness 0.15)
				)
			)
		)
		(property "Author" "Antmicro"
			(at 209.001002 312.446298 0)
			(layer "F.Fab")
			(hide yes)
			(effects
				(font
					(size 1 1)
					(thickness 0.15)
				)
			)
		)
		(property "License" "Apache-2.0"
			(at 209.001002 312.446298 0)
			(layer "F.Fab")
			(hide yes)
			(effects
				(font
					(size 1 1)
					(thickness 0.15)
				)
			)
		)
		(property "MPN" "BLM18PG121SN1D"
			(at 209.001002 312.446298 0)
			(layer "F.Fab")
			(hide yes)
			(effects
				(font
					(size 1 1)
					(thickness 0.15)
				)
			)
		)
		(property "Manufacturer" "Murata"
			(at 209.001002 312.446298 0)
			(layer "F.Fab")
			(hide yes)
			(effects
				(font
					(size 1 1)
					(thickness 0.15)
				)
			)
		)
		(property "Val" "120Z/2A"
			(at 209.001002 312.446298 0)
			(layer "F.Fab")
			(hide yes)
			(effects
				(font
					(size 1 1)
					(thickness 0.15)
				)
			)
		)
		(sheetname "/Ethernet/")
		(sheetfile "ethernet.kicad_sch")
		(attr smd)
		(fp_line
			(start -0.196 0.406)
			(end 0.193 0.406)
			(stroke
				(width 0.15)
				(type solid)
			)
			(layer "F.SilkS")
		)
		(fp_line
			(start -0.196 -0.408)
			(end 0.193 -0.408)
			(stroke
				(width 0.15)
				(type solid)
			)
			(layer "F.SilkS")
		)
		(fp_rect
			(start -1.3 -0.6)
			(end 1.3 0.6)
			(stroke
				(width 0.05)
				(type solid)
			)
			(fill no)
			(layer "F.CrtYd")
		)
		(fp_line
			(start 0.8 0.406)
			(end -0.803 0.406)
			(stroke
				(width 0.15)
				(type solid)
			)
			(layer "F.Fab")
		)
		(fp_line
			(start 0.8 -0.408)
			(end 0.8 0.406)
			(stroke
				(width 0.15)
				(type solid)
			)
			(layer "F.Fab")
		)
		(fp_line
			(start 0.8 -0.408)
			(end -0.803 -0.408)
			(stroke
				(width 0.15)
				(type solid)
			)
			(layer "F.Fab")
		)
		(fp_line
			(start -0.803 0.406)
			(end -0.803 -0.408)
			(stroke
				(width 0.15)
				(type solid)
			)
			(layer "F.Fab")
		)
		(pad "1" smd roundrect
			(at -0.891 0 180)
			(size 0.762 1.09)
			(layers "F.Cu" "F.Mask" "F.Paste")
			(roundrect_rratio 0.15)
			(net 199 "+1V2")
			(pintype "passive")
		)
		(pad "2" smd roundrect
			(at 0.888 0 180)
			(size 0.762 1.09)
			(layers "F.Cu" "F.Mask" "F.Paste")
			(roundrect_rratio 0.15)
			(net 133 "/Ethernet/AVDDL_PLL")
			(pintype "passive")
		)
	)
	(footprint "antmicro-footprints:R_0402_1005Metric"
		(layer "F.Cu")
		(at 100.400501 151.358851 -90)
		(descr "Resistor SMD 0402")
		(tags "resistor SMD 0402")
		(property "Reference" "R112"
			(at -1.122484 -0.772697 270)
			(layer "F.SilkS")
			(hide yes)
			(effects
				(font
					(size 0.7 0.7)
					(thickness 0.15)
				)
				(justify left bottom)
			)
		)
		(property "Value" "R_12k1_0402"
			(at -1.011843 1.772047 270)
			(layer "F.Fab")
			(effects
				(font
					(size 0.7 0.7)
					(thickness 0.15)
				)
				(justify left bottom)
			)
		)
		(property "Datasheet" "https://www.bourns.com/docs/product-datasheets/cr.pdf"
			(at 0 0 270)
			(layer "F.Fab")
			(hide yes)
			(effects
				(font
					(size 1.27 1.27)
					(thickness 0.15)
				)
			)
		)
		(property "Author" "Antmicro"
			(at -50.95835 251.759352 0)
			(layer "F.Fab")
			(hide yes)
			(effects
				(font
					(size 1 1)
					(thickness 0.15)
				)
			)
		)
		(property "License" "Apache-2.0"
			(at -50.95835 251.759352 0)
			(layer "F.Fab")
			(hide yes)
			(effects
				(font
					(size 1 1)
					(thickness 0.15)
				)
			)
		)
		(property "MPN" "CR0402-FX-1212GLF"
			(at -50.95835 251.759352 0)
			(layer "F.Fab")
			(hide yes)
			(effects
				(font
					(size 1 1)
					(thickness 0.15)
				)
			)
		)
		(property "Manufacturer" "Bourns"
			(at -50.95835 251.759352 0)
			(layer "F.Fab")
			(hide yes)
			(effects
				(font
					(size 1 1)
					(thickness 0.15)
				)
			)
		)
		(property "Tolerance" "1%"
			(at -50.95835 251.759352 0)
			(layer "F.Fab")
			(hide yes)
			(effects
				(font
					(size 1 1)
					(thickness 0.15)
				)
			)
		)
		(property "Val" "12k1"
			(at -50.95835 251.759352 0)
			(layer "F.Fab")
			(hide yes)
			(effects
				(font
					(size 1 1)
					(thickness 0.15)
				)
			)
		)
		(sheetname "/Ethernet/")
		(sheetfile "ethernet.kicad_sch")
		(attr smd)
		(fp_rect
			(start -0.93 -0.47)
			(end 0.93 0.47)
			(stroke
				(width 0.05)
				(type solid)
			)
			(fill no)
			(layer "F.CrtYd")
		)
		(fp_rect
			(start -0.5 -0.25)
			(end 0.5 0.25)
			(stroke
				(width 0.15)
				(type solid)
			)
			(fill no)
			(layer "F.Fab")
		)
		(pad "1" smd roundrect
			(at -0.485 0 270)
			(size 0.59 0.64)
			(layers "F.Cu" "F.Mask" "F.Paste")
			(roundrect_rratio 0.25)
			(net 1 "GND")
			(pintype "passive")
		)
		(pad "2" smd roundrect
			(at 0.485 0 270)
			(size 0.59 0.64)
			(layers "F.Cu" "F.Mask" "F.Paste")
			(roundrect_rratio 0.25)
			(net 384 "Net-(U15-ISET)")
			(pintype "passive")
		)
	)
	(footprint "antmicro-footprints:R_0402_1005Metric"
		(layer "F.Cu")
		(at 100.400501 153.358851 90)
		(descr "Resistor SMD 0402")
		(tags "resistor SMD 0402")
		(property "Reference" "R100"
			(at -1.122484 -0.772697 90)
			(layer "F.SilkS")
			(hide yes)
			(effects
				(font
					(size 0.7 0.7)
					(thickness 0.15)
				)
				(justify left bottom)
			)
		)
		(property "Value" "R_1M8_0402"
			(at -1.011843 1.772047 90)
			(layer "F.Fab")
			(effects
				(font
					(size 0.7 0.7)
					(thickness 0.15)
				)
				(justify left bottom)
			)
		)
		(property "Datasheet" "https://www.mouser.com/catalog/specsheets/YAGEO_PYu_RC_Group_51_RoHS_L_12.pdf"
			(at 0 0 90)
			(layer "F.Fab")
			(hide yes)
			(effects
				(font
					(size 1.27 1.27)
					(thickness 0.15)
				)
			)
		)
		(property "Description" "SMD Chip Resistor"
			(at 0 0 90)
			(layer "F.Fab")
			(hide yes)
			(effects
				(font
					(size 1.27 1.27)
					(thickness 0.15)
				)
			)
		)
		(property "Author" "Antmicro"
			(at 253.759352 52.95835 0)
			(layer "F.Fab")
			(hide yes)
			(effects
				(font
					(size 1 1)
					(thickness 0.15)
				)
			)
		)
		(property "License" "Apache-2.0"
			(at 253.759352 52.95835 0)
			(layer "F.Fab")
			(hide yes)
			(effects
				(font
					(size 1 1)
					(thickness 0.15)
				)
			)
		)
		(property "MPN" "RC0402FR-071M8L"
			(at 253.759352 52.95835 0)
			(layer "F.Fab")
			(hide yes)
			(effects
				(font
					(size 1 1)
					(thickness 0.15)
				)
			)
		)
		(property "Manufacturer" "YAGEO"
			(at 253.759352 52.95835 0)
			(layer "F.Fab")
			(hide yes)
			(effects
				(font
					(size 1 1)
					(thickness 0.15)
				)
			)
		)
		(property "Tolerance" "1%"
			(at 253.759352 52.95835 0)
			(layer "F.Fab")
			(hide yes)
			(effects
				(font
					(size 1 1)
					(thickness 0.15)
				)
			)
		)
		(property "Val" "1M8"
			(at 253.759352 52.95835 0)
			(layer "F.Fab")
			(hide yes)
			(effects
				(font
					(size 1 1)
					(thickness 0.15)
				)
			)
		)
		(sheetname "/Ethernet/")
		(sheetfile "ethernet.kicad_sch")
		(attr smd)
		(fp_rect
			(start -0.93 -0.47)
			(end 0.93 0.47)
			(stroke
				(width 0.05)
				(type solid)
			)
			(fill no)
			(layer "F.CrtYd")
		)
		(fp_rect
			(start -0.5 -0.25)
			(end 0.5 0.25)
			(stroke
				(width 0.15)
				(type solid)
			)
			(fill no)
			(layer "F.Fab")
		)
		(pad "1" smd roundrect
			(at -0.485 0 90)
			(size 0.59 0.64)
			(layers "F.Cu" "F.Mask" "F.Paste")
			(roundrect_rratio 0.25)
			(net 300 "Net-(U15-XO)")
			(pintype "passive")
		)
		(pad "2" smd roundrect
			(at 0.485 0 90)
			(size 0.59 0.64)
			(layers "F.Cu" "F.Mask" "F.Paste")
			(roundrect_rratio 0.25)
			(net 299 "Net-(U15-XI)")
			(pintype "passive")
		)
	)
	(footprint "antmicro-footprints:Resonator_SMD_Abracon_ABM8G_3.2x2.5mm"
		(layer "F.Cu")
		(at 103.300501 152.558851)
		(property "Reference" "Y2"
			(at 0.799499 2.641149 180)
			(layer "F.SilkS")
			(effects
				(font
					(size 0.7 0.7)
					(thickness 0.15)
				)
				(justify left bottom)
			)
		)
		(property "Value" "Resonator_25MHz_ABM8G"
			(at -1.75 2.548 0)
			(layer "F.Fab")
			(effects
				(font
					(size 0.7 0.7)
					(thickness 0.15)
				)
				(justify left bottom)
			)
		)
		(property "Datasheet" "https://abracon.com/Resonators/ABM8G.pdf"
			(at 0 0 0)
			(layer "F.Fab")
			(hide yes)
			(effects
				(font
					(size 1.27 1.27)
					(thickness 0.15)
				)
			)
		)
		(property "Author" "Antmicro"
			(at 0 0 0)
			(layer "F.Fab")
			(hide yes)
			(effects
				(font
					(size 1 1)
					(thickness 0.15)
				)
			)
		)
		(property "License" "Apache-2.0"
			(at 0 0 0)
			(layer "F.Fab")
			(hide yes)
			(effects
				(font
					(size 1 1)
					(thickness 0.15)
				)
			)
		)
		(property "MPN" "ABM8G-25.000MHZ-18-D2Y-T3"
			(at 0 0 0)
			(layer "F.Fab")
			(hide yes)
			(effects
				(font
					(size 1 1)
					(thickness 0.15)
				)
			)
		)
		(property "Manufacturer" "Abracon"
			(at 0 0 0)
			(layer "F.Fab")
			(hide yes)
			(effects
				(font
					(size 1 1)
					(thickness 0.15)
				)
			)
		)
		(property "Val" "25 MHz"
			(at 0 0 0)
			(layer "F.Fab")
			(hide yes)
			(effects
				(font
					(size 1 1)
					(thickness 0.15)
				)
			)
		)
		(sheetname "/Ethernet/")
		(sheetfile "ethernet.kicad_sch")
		(attr smd)
		(fp_line
			(start -1.6 0.3)
			(end -1.6 -0.2)
			(stroke
				(width 0.15)
				(type solid)
			)
			(layer "F.SilkS")
		)
		(fp_line
			(start -0.35 -1.25)
			(end 0.45 -1.25)
			(stroke
				(width 0.15)
				(type solid)
			)
			(layer "F.SilkS")
		)
		(fp_line
			(start -0.35 1.25)
			(end 0.45 1.25)
			(stroke
				(width 0.15)
				(type solid)
			)
			(layer "F.SilkS")
		)
		(fp_line
			(start 1.6 0.3)
			(end 1.6 -0.2)
			(stroke
				(width 0.15)
				(type solid)
			)
			(layer "F.SilkS")
		)
		(fp_circle
			(center -1.75 1.5)
			(end -1.7 1.5)
			(stroke
				(width 0.15)
				(type solid)
			)
			(fill no)
			(layer "F.SilkS")
		)
		(fp_rect
			(start -1.907 -1.55)
			(end 2.006 1.649)
			(stroke
				(width 0.05)
				(type solid)
			)
			(fill no)
			(layer "F.CrtYd")
		)
		(pad "1" smd roundrect
			(at -1.101 0.949)
			(size 1.3 1.1)
			(layers "F.Cu" "F.Mask" "F.Paste")
			(roundrect_rratio 0)
			(chamfer_ratio 0.2)
			(chamfer bottom_left)
			(net 300 "Net-(U15-XO)")
			(pintype "passive")
		)
		(pad "2" smd rect
			(at 1.199 0.949)
			(size 1.3 1.1)
			(layers "F.Cu" "F.Mask" "F.Paste")
			(net 1 "GND")
			(pinfunction "SH")
			(pintype "passive")
		)
		(pad "3" smd rect
			(at 1.199 -0.85)
			(size 1.3 1.1)
			(layers "F.Cu" "F.Mask" "F.Paste")
			(net 299 "Net-(U15-XI)")
			(pintype "passive")
		)
		(pad "4" smd rect
			(at -1.101 -0.85)
			(size 1.3 1.1)
			(layers "F.Cu" "F.Mask" "F.Paste")
			(net 1 "GND")
			(pinfunction "SH")
			(pintype "passive")
		)
	)
	(footprint "antmicro-footprints:QFN-48-1EP_7x7x0.9mm_P0.5mm_EP3.5x3.5mm"
		(layer "F.Cu")
		(at 93.550501 154.786 -90)
		(property "Reference" "U15"
			(at 5.114 -2.249499 0)
			(layer "F.SilkS")
			(effects
				(font
					(size 0.7 0.7)
					(thickness 0.15)
				)
				(justify left bottom)
			)
		)
		(property "Value" "KSZ9031RNXCA"
			(at 0 5.1 270)
			(layer "F.Fab")
			(hide yes)
			(effects
				(font
					(size 0.7 0.7)
					(thickness 0.15)
				)
				(justify left bottom)
			)
		)
		(property "Datasheet" "http://ww1.microchip.com/downloads/en/DeviceDoc/00002117F.pdf"
			(at 0 0 270)
			(layer "F.Fab")
			(hide yes)
			(effects
				(font
					(size 1.27 1.27)
					(thickness 0.15)
				)
			)
		)
		(property "Author" "Antmicro"
			(at -61.235499 248.336501 0)
			(layer "F.Fab")
			(hide yes)
			(effects
				(font
					(size 1 1)
					(thickness 0.15)
				)
			)
		)
		(property "License" "Apache-2.0"
			(at -61.235499 248.336501 0)
			(layer "F.Fab")
			(hide yes)
			(effects
				(font
					(size 1 1)
					(thickness 0.15)
				)
			)
		)
		(property "MPN" "KSZ9031RNXCA"
			(at -61.235499 248.336501 0)
			(layer "F.Fab")
			(hide yes)
			(effects
				(font
					(size 1 1)
					(thickness 0.15)
				)
			)
		)
		(property "Manufacturer" "Microchip Technology"
			(at -61.235499 248.336501 0)
			(layer "F.Fab")
			(hide yes)
			(effects
				(font
					(size 1 1)
					(thickness 0.15)
				)
			)
		)
		(sheetname "/Ethernet/")
		(sheetfile "ethernet.kicad_sch")
		(attr smd)
		(fp_line
			(start -3.65 3.648)
			(end -3.65 3.249)
			(stroke
				(width 0.15)
				(type solid)
			)
			(layer "F.SilkS")
		)
		(fp_line
			(start -3.25 3.648)
			(end -3.65 3.648)
			(stroke
				(width 0.15)
				(type solid)
			)
			(layer "F.SilkS")
		)
		(fp_line
			(start 3.249 3.648)
			(end 3.648 3.648)
			(stroke
				(width 0.15)
				(type solid)
			)
			(layer "F.SilkS")
		)
		(fp_line
			(start 3.648 3.648)
			(end 3.648 3.249)
			(stroke
				(width 0.15)
				(type solid)
			)
			(layer "F.SilkS")
		)
		(fp_line
			(start -3.65 -3.3)
			(end -3.65 -3.65)
			(stroke
				(width 0.15)
				(type solid)
			)
			(layer "F.SilkS")
		)
		(fp_line
			(start -3.3 -3.65)
			(end -3.65 -3.65)
			(stroke
				(width 0.15)
				(type solid)
			)
			(layer "F.SilkS")
		)
		(fp_line
			(start 3.249 -3.65)
			(end 3.648 -3.65)
			(stroke
				(width 0.15)
				(type solid)
			)
			(layer "F.SilkS")
		)
		(fp_line
			(start 3.648 -3.65)
			(end 3.648 -3.25)
			(stroke
				(width 0.15)
				(type solid)
			)
			(layer "F.SilkS")
		)
		(fp_circle
			(center -3.7 -3.05)
			(end -3.65 -3.05)
			(stroke
				(width 0.15)
				(type solid)
			)
			(fill yes)
			(layer "F.SilkS")
		)
		(fp_rect
			(start -4.15 -4.15)
			(end 4.15 4.15)
			(stroke
				(width 0.05)
				(type solid)
			)
			(fill no)
			(layer "F.CrtYd")
		)
		(fp_line
			(start -3.5 3.499)
			(end 3.499 3.499)
			(stroke
				(width 0.15)
				(type solid)
			)
			(layer "F.Fab")
		)
		(fp_line
			(start 3.499 3.499)
			(end 3.499 -3.5)
			(stroke
				(width 0.15)
				(type solid)
			)
			(layer "F.Fab")
		)
		(fp_line
			(start -3.5 -2.5)
			(end -3.5 3.499)
			(stroke
				(width 0.15)
				(type solid)
			)
			(layer "F.Fab")
		)
		(fp_line
			(start -2.5 -3.5)
			(end -3.5 -2.5)
			(stroke
				(width 0.15)
				(type solid)
			)
			(layer "F.Fab")
		)
		(fp_line
			(start 3.499 -3.5)
			(end -2.5 -3.5)
			(stroke
				(width 0.15)
				(type solid)
			)
			(layer "F.Fab")
		)
		(pad "1" smd oval
			(at -3.5 -2.75)
			(size 0.3 0.9)
			(layers "F.Cu" "F.Mask" "F.Paste")
			(net 134 "/Ethernet/AVDDH")
			(pinfunction "AVDDH")
			(pintype "power_in")
		)
		(pad "2" smd oval
			(at -3.5 -2.25)
			(size 0.3 0.9)
			(layers "F.Cu" "F.Mask" "F.Paste")
			(net 125 "/Ethernet/ETH1_P")
			(pinfunction "TXRXP_A")
			(pintype "bidirectional")
		)
		(pad "3" smd oval
			(at -3.5 -1.75)
			(size 0.3 0.9)
			(layers "F.Cu" "F.Mask" "F.Paste")
			(net 128 "/Ethernet/ETH1_N")
			(pinfunction "TXRXM_A")
			(pintype "bidirectional")
		)
		(pad "4" smd oval
			(at -3.5 -1.25)
			(size 0.3 0.9)
			(layers "F.Cu" "F.Mask" "F.Paste")
			(net 132 "/Ethernet/AVDDL")
			(pinfunction "AVDDL")
			(pintype "power_in")
		)
		(pad "5" smd oval
			(at -3.5 -0.75)
			(size 0.3 0.9)
			(layers "F.Cu" "F.Mask" "F.Paste")
			(net 124 "/Ethernet/ETH2_P")
			(pinfunction "TXRXP_B")
			(pintype "bidirectional")
		)
		(pad "6" smd oval
			(at -3.5 -0.25)
			(size 0.3 0.9)
			(layers "F.Cu" "F.Mask" "F.Paste")
			(net 127 "/Ethernet/ETH2_N")
			(pinfunction "TXRXM_B")
			(pintype "bidirectional")
		)
		(pad "7" smd oval
			(at -3.5 0.248)
			(size 0.3 0.9)
			(layers "F.Cu" "F.Mask" "F.Paste")
			(net 123 "/Ethernet/ETH3_P")
			(pinfunction "TXRXP_C")
			(pintype "bidirectional")
		)
		(pad "8" smd oval
			(at -3.5 0.748)
			(size 0.3 0.9)
			(layers "F.Cu" "F.Mask" "F.Paste")
			(net 129 "/Ethernet/ETH3_N")
			(pinfunction "TXRXM_C")
			(pintype "bidirectional")
		)
		(pad "9" smd oval
			(at -3.5 1.249)
			(size 0.3 0.9)
			(layers "F.Cu" "F.Mask" "F.Paste")
			(net 132 "/Ethernet/AVDDL")
			(pinfunction "AVDDL")
			(pintype "passive")
		)
		(pad "10" smd oval
			(at -3.5 1.749)
			(size 0.3 0.9)
			(layers "F.Cu" "F.Mask" "F.Paste")
			(net 126 "/Ethernet/ETH4_P")
			(pinfunction "TXRXP_D")
			(pintype "bidirectional")
		)
		(pad "11" smd oval
			(at -3.5 2.249)
			(size 0.3 0.9)
			(layers "F.Cu" "F.Mask" "F.Paste")
			(net 130 "/Ethernet/ETH4_N")
			(pinfunction "TXRXM_D")
			(pintype "bidirectional")
		)
		(pad "12" smd oval
			(at -3.5 2.749)
			(size 0.3 0.9)
			(layers "F.Cu" "F.Mask" "F.Paste")
			(net 134 "/Ethernet/AVDDH")
			(pinfunction "AVDDH")
			(pintype "passive")
		)
		(pad "13" smd oval
			(at -2.75 3.499 270)
			(size 0.3 0.9)
			(layers "F.Cu" "F.Mask" "F.Paste")
			(net 721 "unconnected-(U15-NC-Pad13)")
			(pinfunction "NC")
			(pintype "no_connect")
		)
		(pad "14" smd oval
			(at -2.25 3.499 270)
			(size 0.3 0.9)
			(layers "F.Cu" "F.Mask" "F.Paste")
			(net 199 "+1V2")
			(pinfunction "DVDDL")
			(pintype "power_in")
		)
		(pad "15" smd oval
			(at -1.75 3.499 270)
			(size 0.3 0.9)
			(layers "F.Cu" "F.Mask" "F.Paste")
			(net 602 "/Ethernet/LED_SPD")
			(pinfunction "LED2/PHYAD1")
			(pintype "bidirectional")
		)
		(pad "16" smd oval
			(at -1.25 3.499 270)
			(size 0.3 0.9)
			(layers "F.Cu" "F.Mask" "F.Paste")
			(net 200 "+3V3")
			(pinfunction "DVDDH")
			(pintype "power_in")
		)
		(pad "17" smd oval
			(at -0.75 3.499 270)
			(size 0.3 0.9)
			(layers "F.Cu" "F.Mask" "F.Paste")
			(net 603 "/Ethernet/LED_LINK")
			(pinfunction "LED1/PHAD0/PME_N1")
			(pintype "bidirectional")
		)
		(pad "18" smd oval
			(at -0.25 3.499 270)
			(size 0.3 0.9)
			(layers "F.Cu" "F.Mask" "F.Paste")
			(net 199 "+1V2")
			(pinfunction "DVDDL")
			(pintype "passive")
		)
		(pad "19" smd oval
			(at 0.248 3.499 270)
			(size 0.3 0.9)
			(layers "F.Cu" "F.Mask" "F.Paste")
			(net 733 "/Ethernet/ETH.TXD0")
			(pinfunction "TXD0")
			(pintype "input")
		)
		(pad "20" smd oval
			(at 0.748 3.499 270)
			(size 0.3 0.9)
			(layers "F.Cu" "F.Mask" "F.Paste")
			(net 737 "/Ethernet/ETH.TXD1")
			(pinfunction "TXD1")
			(pintype "input")
		)
		(pad "21" smd oval
			(at 1.249 3.499 270)
			(size 0.3 0.9)
			(layers "F.Cu" "F.Mask" "F.Paste")
			(net 736 "/Ethernet/ETH.TXD2")
			(pinfunction "TXD2")
			(pintype "input")
		)
		(pad "22" smd oval
			(at 1.749 3.499 270)
			(size 0.3 0.9)
			(layers "F.Cu" "F.Mask" "F.Paste")
			(net 735 "/Ethernet/ETH.TXD3")
			(pinfunction "TXD3")
			(pintype "input")
		)
		(pad "23" smd oval
			(at 2.249 3.499 270)
			(size 0.3 0.9)
			(layers "F.Cu" "F.Mask" "F.Paste")
			(net 199 "+1V2")
			(pinfunction "DVDDL")
			(pintype "passive")
		)
		(pad "24" smd oval
			(at 2.749 3.499 270)
			(size 0.3 0.9)
			(layers "F.Cu" "F.Mask" "F.Paste")
			(net 704 "/Ethernet/ETH.TXC")
			(pinfunction "GTX_CLK")
			(pintype "input")
		)
		(pad "25" smd oval
			(at 3.499 2.749)
			(size 0.3 0.9)
			(layers "F.Cu" "F.Mask" "F.Paste")
			(net 732 "/Ethernet/ETH.TX_CTL")
			(pinfunction "TX_EN")
			(pintype "input")
		)
		(pad "26" smd oval
			(at 3.499 2.249)
			(size 0.3 0.9)
			(layers "F.Cu" "F.Mask" "F.Paste")
			(net 199 "+1V2")
			(pinfunction "DVDDL")
			(pintype "passive")
		)
		(pad "27" smd oval
			(at 3.499 1.749)
			(size 0.3 0.9)
			(layers "F.Cu" "F.Mask" "F.Paste")
			(net 676 "/Ethernet/ETH.RXD3")
			(pinfunction "RXD3/MODE3")
			(pintype "input")
		)
		(pad "28" smd oval
			(at 3.499 1.249)
			(size 0.3 0.9)
			(layers "F.Cu" "F.Mask" "F.Paste")
			(net 675 "/Ethernet/ETH.RXD2")
			(pinfunction "RXD2/MODE2")
			(pintype "input")
		)
		(pad "29" smd oval
			(at 3.499 0.748)
			(size 0.3 0.9)
			(layers "F.Cu" "F.Mask" "F.Paste")
			(net 1 "GND")
			(pinfunction "VSS")
			(pintype "power_in")
		)
		(pad "30" smd oval
			(at 3.499 0.248)
			(size 0.3 0.9)
			(layers "F.Cu" "F.Mask" "F.Paste")
			(net 199 "+1V2")
			(pinfunction "DVDDL")
			(pintype "passive")
		)
		(pad "31" smd oval
			(at 3.499 -0.25)
			(size 0.3 0.9)
			(layers "F.Cu" "F.Mask" "F.Paste")
			(net 674 "/Ethernet/ETH.RXD1")
			(pinfunction "RXD1/MODE1")
			(pintype "input")
		)
		(pad "32" smd oval
			(at 3.499 -0.75)
			(size 0.3 0.9)
			(layers "F.Cu" "F.Mask" "F.Paste")
			(net 673 "/Ethernet/ETH.RXD0")
			(pinfunction "RXD0/MODE0")
			(pintype "input")
		)
		(pad "33" smd oval
			(at 3.499 -1.25)
			(size 0.3 0.9)
			(layers "F.Cu" "F.Mask" "F.Paste")
			(net 677 "/Ethernet/ETH.RX_CTL")
			(pinfunction "RX_DV/CLK125_EN")
			(pintype "input")
		)
		(pad "34" smd oval
			(at 3.499 -1.75)
			(size 0.3 0.9)
			(layers "F.Cu" "F.Mask" "F.Paste")
			(net 200 "+3V3")
			(pinfunction "DVDDH")
			(pintype "passive")
		)
		(pad "35" smd oval
			(at 3.499 -2.25)
			(size 0.3 0.9)
			(layers "F.Cu" "F.Mask" "F.Paste")
			(net 678 "/Ethernet/ETH.RXC")
			(pinfunction "RX_CLK/PHYAD2")
			(pintype "input")
		)
		(pad "36" smd oval
			(at 3.499 -2.75)
			(size 0.3 0.9)
			(layers "F.Cu" "F.Mask" "F.Paste")
			(net 705 "/Ethernet/ETH.MDC")
			(pinfunction "MDC")
			(pintype "input")
		)
		(pad "37" smd oval
			(at 2.749 -3.5 270)
			(size 0.3 0.9)
			(layers "F.Cu" "F.Mask" "F.Paste")
			(net 680 "/Ethernet/ETH.MDIO")
			(pinfunction "MDIO")
			(pintype "input")
		)
		(pad "38" smd oval
			(at 2.249 -3.5 270)
			(size 0.3 0.9)
			(layers "F.Cu" "F.Mask" "F.Paste")
			(net 734 "/Ethernet/ETH.~{INT}")
			(pinfunction "~{INT/PME}")
			(pintype "input")
		)
		(pad "39" smd oval
			(at 1.749 -3.5 270)
			(size 0.3 0.9)
			(layers "F.Cu" "F.Mask" "F.Paste")
			(net 199 "+1V2")
			(pinfunction "DVDDL")
			(pintype "passive")
		)
		(pad "40" smd oval
			(at 1.249 -3.5 270)
			(size 0.3 0.9)
			(layers "F.Cu" "F.Mask" "F.Paste")
			(net 200 "+3V3")
			(pinfunction "DVDDH")
			(pintype "passive")
		)
		(pad "41" smd oval
			(at 0.748 -3.5 270)
			(size 0.3 0.9)
			(layers "F.Cu" "F.Mask" "F.Paste")
			(net 679 "/Ethernet/ETH.REF_CLK")
			(pinfunction "CLK125_NDO/LED_MODE")
			(pintype "input")
		)
		(pad "42" smd oval
			(at 0.248 -3.5 270)
			(size 0.3 0.9)
			(layers "F.Cu" "F.Mask" "F.Paste")
			(net 681 "/Ethernet/ETH.~{RESET}")
			(pinfunction "~{RESET}")
			(pintype "input")
		)
		(pad "43" smd oval
			(at -0.25 -3.5 270)
			(size 0.3 0.9)
			(layers "F.Cu" "F.Mask" "F.Paste")
			(net 722 "unconnected-(U15-LDO_O-Pad43)")
			(pinfunction "LDO_O")
			(pintype "input+no_connect")
		)
		(pad "44" smd oval
			(at -0.75 -3.5 270)
			(size 0.3 0.9)
			(layers "F.Cu" "F.Mask" "F.Paste")
			(net 133 "/Ethernet/AVDDL_PLL")
			(pinfunction "AVDDL_PLL")
			(pintype "power_in")
		)
		(pad "45" smd oval
			(at -1.25 -3.5 270)
			(size 0.3 0.9)
			(layers "F.Cu" "F.Mask" "F.Paste")
			(net 300 "Net-(U15-XO)")
			(pinfunction "XO")
			(pintype "input")
		)
		(pad "46" smd oval
			(at -1.75 -3.5 270)
			(size 0.3 0.9)
			(layers "F.Cu" "F.Mask" "F.Paste")
			(net 299 "Net-(U15-XI)")
			(pinfunction "XI")
			(pintype "input")
		)
		(pad "47" smd oval
			(at -2.25 -3.5 270)
			(size 0.3 0.9)
			(layers "F.Cu" "F.Mask" "F.Paste")
			(net 723 "unconnected-(U15-NC-Pad47)")
			(pinfunction "NC")
			(pintype "no_connect")
		)
		(pad "48" smd oval
			(at -2.75 -3.5 270)
			(size 0.3 0.9)
			(layers "F.Cu" "F.Mask" "F.Paste")
			(net 384 "Net-(U15-ISET)")
			(pinfunction "ISET")
			(pintype "output")
		)
		(pad "49" smd rect
			(at 0 0 270)
			(size 3.5 3.5)
			(layers "F.Cu" "F.Mask" "F.Paste")
			(net 1 "GND")
			(pinfunction "PAD_GND")
			(pintype "power_in")
		)
	)
	(footprint "antmicro-footprints:R_0402_1005Metric"
		(layer "F.Cu")
		(at 86.867877 189.779001 180)
		(descr "Resistor SMD 0402")
		(tags "resistor SMD 0402")
		(property "Reference" "R77"
			(at -1.122484 -0.772697 180)
			(layer "F.SilkS")
			(hide yes)
			(effects
				(font
					(size 0.7 0.7)
					(thickness 0.15)
				)
				(justify left bottom)
			)
		)
		(property "Value" "R_0R_0402"
			(at -1.011843 1.772047 180)
			(layer "F.Fab")
			(effects
				(font
					(size 0.7 0.7)
					(thickness 0.15)
				)
				(justify left bottom)
			)
		)
		(property "Datasheet" "https://industrial.panasonic.com/cdbs/www-data/pdf/RDA0000/AOA0000C301.pdf"
			(at 0 0 180)
			(layer "F.Fab")
			(hide yes)
			(effects
				(font
					(size 1.27 1.27)
					(thickness 0.15)
				)
			)
		)
		(property "Author" "Antmicro"
			(at 173.735754 379.558002 0)
			(layer "F.Fab")
			(hide yes)
			(effects
				(font
					(size 1 1)
					(thickness 0.15)
				)
			)
		)
		(property "Current" "1A"
			(at 173.735754 379.558002 0)
			(layer "F.Fab")
			(hide yes)
			(effects
				(font
					(size 1 1)
					(thickness 0.15)
				)
			)
		)
		(property "License" "Apache-2.0"
			(at 173.735754 379.558002 0)
			(layer "F.Fab")
			(hide yes)
			(effects
				(font
					(size 1 1)
					(thickness 0.15)
				)
			)
		)
		(property "MPN" "ERJ2GE0R00X"
			(at 173.735754 379.558002 0)
			(layer "F.Fab")
			(hide yes)
			(effects
				(font
					(size 1 1)
					(thickness 0.15)
				)
			)
		)
		(property "Manufacturer" "Panasonic"
			(at 173.735754 379.558002 0)
			(layer "F.Fab")
			(hide yes)
			(effects
				(font
					(size 1 1)
					(thickness 0.15)
				)
			)
		)
		(property "Tolerance" ""
			(at 173.735754 379.558002 0)
			(layer "F.Fab")
			(hide yes)
			(effects
				(font
					(size 1 1)
					(thickness 0.15)
				)
			)
		)
		(property "Val" "0R"
			(at 173.735754 379.558002 0)
			(layer "F.Fab")
			(hide yes)
			(effects
				(font
					(size 1 1)
					(thickness 0.15)
				)
			)
		)
		(sheetname "/HDMI + SD Card/")
		(sheetfile "hdmi-sd-card.kicad_sch")
		(attr smd)
		(fp_rect
			(start -0.93 -0.47)
			(end 0.93 0.47)
			(stroke
				(width 0.05)
				(type solid)
			)
			(fill no)
			(layer "F.CrtYd")
		)
		(fp_rect
			(start -0.5 -0.25)
			(end 0.5 0.25)
			(stroke
				(width 0.15)
				(type solid)
			)
			(fill no)
			(layer "F.Fab")
		)
		(pad "1" smd roundrect
			(at -0.485 0 180)
			(size 0.59 0.64)
			(layers "F.Cu" "F.Mask" "F.Paste")
			(roundrect_rratio 0.25)
			(net 667 "/FPGA bank 16/HDMI.CLK_N")
			(pintype "passive")
		)
		(pad "2" smd roundrect
			(at 0.485 0 180)
			(size 0.59 0.64)
			(layers "F.Cu" "F.Mask" "F.Paste")
			(roundrect_rratio 0.25)
			(net 349 "/HDMI + SD Card/HDMI_CONN_CLK_N")
			(pintype "passive")
		)
	)
	(footprint "antmicro-footprints:R_0402_1005Metric"
		(layer "F.Cu")
		(at 86.867877 190.779001 180)
		(descr "Resistor SMD 0402")
		(tags "resistor SMD 0402")
		(property "Reference" "R76"
			(at -1.122484 -0.772697 180)
			(layer "F.SilkS")
			(hide yes)
			(effects
				(font
					(size 0.7 0.7)
					(thickness 0.15)
				)
				(justify left bottom)
			)
		)
		(property "Value" "R_0R_0402"
			(at -1.011843 1.772047 180)
			(layer "F.Fab")
			(effects
				(font
					(size 0.7 0.7)
					(thickness 0.15)
				)
				(justify left bottom)
			)
		)
		(property "Datasheet" "https://industrial.panasonic.com/cdbs/www-data/pdf/RDA0000/AOA0000C301.pdf"
			(at 0 0 180)
			(layer "F.Fab")
			(hide yes)
			(effects
				(font
					(size 1.27 1.27)
					(thickness 0.15)
				)
			)
		)
		(property "Author" "Antmicro"
			(at 173.735754 381.558002 0)
			(layer "F.Fab")
			(hide yes)
			(effects
				(font
					(size 1 1)
					(thickness 0.15)
				)
			)
		)
		(property "Current" "1A"
			(at 173.735754 381.558002 0)
			(layer "F.Fab")
			(hide yes)
			(effects
				(font
					(size 1 1)
					(thickness 0.15)
				)
			)
		)
		(property "License" "Apache-2.0"
			(at 173.735754 381.558002 0)
			(layer "F.Fab")
			(hide yes)
			(effects
				(font
					(size 1 1)
					(thickness 0.15)
				)
			)
		)
		(property "MPN" "ERJ2GE0R00X"
			(at 173.735754 381.558002 0)
			(layer "F.Fab")
			(hide yes)
			(effects
				(font
					(size 1 1)
					(thickness 0.15)
				)
			)
		)
		(property "Manufacturer" "Panasonic"
			(at 173.735754 381.558002 0)
			(layer "F.Fab")
			(hide yes)
			(effects
				(font
					(size 1 1)
					(thickness 0.15)
				)
			)
		)
		(property "Tolerance" ""
			(at 173.735754 381.558002 0)
			(layer "F.Fab")
			(hide yes)
			(effects
				(font
					(size 1 1)
					(thickness 0.15)
				)
			)
		)
		(property "Val" "0R"
			(at 173.735754 381.558002 0)
			(layer "F.Fab")
			(hide yes)
			(effects
				(font
					(size 1 1)
					(thickness 0.15)
				)
			)
		)
		(sheetname "/HDMI + SD Card/")
		(sheetfile "hdmi-sd-card.kicad_sch")
		(attr smd)
		(fp_rect
			(start -0.93 -0.47)
			(end 0.93 0.47)
			(stroke
				(width 0.05)
				(type solid)
			)
			(fill no)
			(layer "F.CrtYd")
		)
		(fp_rect
			(start -0.5 -0.25)
			(end 0.5 0.25)
			(stroke
				(width 0.15)
				(type solid)
			)
			(fill no)
			(layer "F.Fab")
		)
		(pad "1" smd roundrect
			(at -0.485 0 180)
			(size 0.59 0.64)
			(layers "F.Cu" "F.Mask" "F.Paste")
			(roundrect_rratio 0.25)
			(net 666 "/FPGA bank 16/HDMI.CLK_P")
			(pintype "passive")
		)
		(pad "2" smd roundrect
			(at 0.485 0 180)
			(size 0.59 0.64)
			(layers "F.Cu" "F.Mask" "F.Paste")
			(roundrect_rratio 0.25)
			(net 348 "/HDMI + SD Card/HDMI_CONN_CLK_P")
			(pintype "passive")
		)
	)
	(footprint "antmicro-footprints:R_0402_1005Metric"
		(layer "F.Cu")
		(at 84.65 191.25 180)
		(descr "Resistor SMD 0402")
		(tags "resistor SMD 0402")
		(property "Reference" "R75"
			(at -1.122484 -0.772697 180)
			(layer "F.SilkS")
			(hide yes)
			(effects
				(font
					(size 0.7 0.7)
					(thickness 0.15)
				)
				(justify left bottom)
			)
		)
		(property "Value" "R_0R_0402"
			(at -1.011843 1.772047 180)
			(layer "F.Fab")
			(effects
				(font
					(size 0.7 0.7)
					(thickness 0.15)
				)
				(justify left bottom)
			)
		)
		(property "Datasheet" "https://industrial.panasonic.com/cdbs/www-data/pdf/RDA0000/AOA0000C301.pdf"
			(at 0 0 180)
			(layer "F.Fab")
			(hide yes)
			(effects
				(font
					(size 1.27 1.27)
					(thickness 0.15)
				)
			)
		)
		(property "Author" "Antmicro"
			(at 169.3 382.5 0)
			(layer "F.Fab")
			(hide yes)
			(effects
				(font
					(size 1 1)
					(thickness 0.15)
				)
			)
		)
		(property "Current" "1A"
			(at 169.3 382.5 0)
			(layer "F.Fab")
			(hide yes)
			(effects
				(font
					(size 1 1)
					(thickness 0.15)
				)
			)
		)
		(property "License" "Apache-2.0"
			(at 169.3 382.5 0)
			(layer "F.Fab")
			(hide yes)
			(effects
				(font
					(size 1 1)
					(thickness 0.15)
				)
			)
		)
		(property "MPN" "ERJ2GE0R00X"
			(at 169.3 382.5 0)
			(layer "F.Fab")
			(hide yes)
			(effects
				(font
					(size 1 1)
					(thickness 0.15)
				)
			)
		)
		(property "Manufacturer" "Panasonic"
			(at 169.3 382.5 0)
			(layer "F.Fab")
			(hide yes)
			(effects
				(font
					(size 1 1)
					(thickness 0.15)
				)
			)
		)
		(property "Tolerance" ""
			(at 169.3 382.5 0)
			(layer "F.Fab")
			(hide yes)
			(effects
				(font
					(size 1 1)
					(thickness 0.15)
				)
			)
		)
		(property "Val" "0R"
			(at 169.3 382.5 0)
			(layer "F.Fab")
			(hide yes)
			(effects
				(font
					(size 1 1)
					(thickness 0.15)
				)
			)
		)
		(sheetname "/HDMI + SD Card/")
		(sheetfile "hdmi-sd-card.kicad_sch")
		(attr smd)
		(fp_rect
			(start -0.93 -0.47)
			(end 0.93 0.47)
			(stroke
				(width 0.05)
				(type solid)
			)
			(fill no)
			(layer "F.CrtYd")
		)
		(fp_rect
			(start -0.5 -0.25)
			(end 0.5 0.25)
			(stroke
				(width 0.15)
				(type solid)
			)
			(fill no)
			(layer "F.Fab")
		)
		(pad "1" smd roundrect
			(at -0.485 0 180)
			(size 0.59 0.64)
			(layers "F.Cu" "F.Mask" "F.Paste")
			(roundrect_rratio 0.25)
			(net 665 "/FPGA bank 16/HDMI.D0_N")
			(pintype "passive")
		)
		(pad "2" smd roundrect
			(at 0.485 0 180)
			(size 0.59 0.64)
			(layers "F.Cu" "F.Mask" "F.Paste")
			(roundrect_rratio 0.25)
			(net 311 "/HDMI + SD Card/HDMI_CONN_D0_N")
			(pintype "passive")
		)
	)
	(footprint "antmicro-footprints:R_0402_1005Metric"
		(layer "F.Cu")
		(at 84.65 192.252 180)
		(descr "Resistor SMD 0402")
		(tags "resistor SMD 0402")
		(property "Reference" "R74"
			(at -1.122484 -0.772697 180)
			(layer "F.SilkS")
			(hide yes)
			(effects
				(font
					(size 0.7 0.7)
					(thickness 0.15)
				)
				(justify left bottom)
			)
		)
		(property "Value" "R_0R_0402"
			(at -1.011843 1.772047 180)
			(layer "F.Fab")
			(effects
				(font
					(size 0.7 0.7)
					(thickness 0.15)
				)
				(justify left bottom)
			)
		)
		(property "Datasheet" "https://industrial.panasonic.com/cdbs/www-data/pdf/RDA0000/AOA0000C301.pdf"
			(at 0 0 180)
			(layer "F.Fab")
			(hide yes)
			(effects
				(font
					(size 1.27 1.27)
					(thickness 0.15)
				)
			)
		)
		(property "Author" "Antmicro"
			(at 169.3 384.504 0)
			(layer "F.Fab")
			(hide yes)
			(effects
				(font
					(size 1 1)
					(thickness 0.15)
				)
			)
		)
		(property "Current" "1A"
			(at 169.3 384.504 0)
			(layer "F.Fab")
			(hide yes)
			(effects
				(font
					(size 1 1)
					(thickness 0.15)
				)
			)
		)
		(property "License" "Apache-2.0"
			(at 169.3 384.504 0)
			(layer "F.Fab")
			(hide yes)
			(effects
				(font
					(size 1 1)
					(thickness 0.15)
				)
			)
		)
		(property "MPN" "ERJ2GE0R00X"
			(at 169.3 384.504 0)
			(layer "F.Fab")
			(hide yes)
			(effects
				(font
					(size 1 1)
					(thickness 0.15)
				)
			)
		)
		(property "Manufacturer" "Panasonic"
			(at 169.3 384.504 0)
			(layer "F.Fab")
			(hide yes)
			(effects
				(font
					(size 1 1)
					(thickness 0.15)
				)
			)
		)
		(property "Tolerance" ""
			(at 169.3 384.504 0)
			(layer "F.Fab")
			(hide yes)
			(effects
				(font
					(size 1 1)
					(thickness 0.15)
				)
			)
		)
		(property "Val" "0R"
			(at 169.3 384.504 0)
			(layer "F.Fab")
			(hide yes)
			(effects
				(font
					(size 1 1)
					(thickness 0.15)
				)
			)
		)
		(sheetname "/HDMI + SD Card/")
		(sheetfile "hdmi-sd-card.kicad_sch")
		(attr smd)
		(fp_rect
			(start -0.93 -0.47)
			(end 0.93 0.47)
			(stroke
				(width 0.05)
				(type solid)
			)
			(fill no)
			(layer "F.CrtYd")
		)
		(fp_rect
			(start -0.5 -0.25)
			(end 0.5 0.25)
			(stroke
				(width 0.15)
				(type solid)
			)
			(fill no)
			(layer "F.Fab")
		)
		(pad "1" smd roundrect
			(at -0.485 0 180)
			(size 0.59 0.64)
			(layers "F.Cu" "F.Mask" "F.Paste")
			(roundrect_rratio 0.25)
			(net 664 "/FPGA bank 16/HDMI.D0_P")
			(pintype "passive")
		)
		(pad "2" smd roundrect
			(at 0.485 0 180)
			(size 0.59 0.64)
			(layers "F.Cu" "F.Mask" "F.Paste")
			(roundrect_rratio 0.25)
			(net 296 "/HDMI + SD Card/HDMI_CONN_D0_P")
			(pintype "passive")
		)
	)
	(footprint "antmicro-footprints:R_0402_1005Metric"
		(layer "F.Cu")
		(at 86.9 192.85 180)
		(descr "Resistor SMD 0402")
		(tags "resistor SMD 0402")
		(property "Reference" "R73"
			(at -1.122484 -0.772697 180)
			(layer "F.SilkS")
			(hide yes)
			(effects
				(font
					(size 0.7 0.7)
					(thickness 0.15)
				)
				(justify left bottom)
			)
		)
		(property "Value" "R_0R_0402"
			(at -1.011843 1.772047 180)
			(layer "F.Fab")
			(effects
				(font
					(size 0.7 0.7)
					(thickness 0.15)
				)
				(justify left bottom)
			)
		)
		(property "Datasheet" "https://industrial.panasonic.com/cdbs/www-data/pdf/RDA0000/AOA0000C301.pdf"
			(at 0 0 180)
			(layer "F.Fab")
			(hide yes)
			(effects
				(font
					(size 1.27 1.27)
					(thickness 0.15)
				)
			)
		)
		(property "Author" "Antmicro"
			(at 173.8 385.7 0)
			(layer "F.Fab")
			(hide yes)
			(effects
				(font
					(size 1 1)
					(thickness 0.15)
				)
			)
		)
		(property "Current" "1A"
			(at 173.8 385.7 0)
			(layer "F.Fab")
			(hide yes)
			(effects
				(font
					(size 1 1)
					(thickness 0.15)
				)
			)
		)
		(property "License" "Apache-2.0"
			(at 173.8 385.7 0)
			(layer "F.Fab")
			(hide yes)
			(effects
				(font
					(size 1 1)
					(thickness 0.15)
				)
			)
		)
		(property "MPN" "ERJ2GE0R00X"
			(at 173.8 385.7 0)
			(layer "F.Fab")
			(hide yes)
			(effects
				(font
					(size 1 1)
					(thickness 0.15)
				)
			)
		)
		(property "Manufacturer" "Panasonic"
			(at 173.8 385.7 0)
			(layer "F.Fab")
			(hide yes)
			(effects
				(font
					(size 1 1)
					(thickness 0.15)
				)
			)
		)
		(property "Tolerance" ""
			(at 173.8 385.7 0)
			(layer "F.Fab")
			(hide yes)
			(effects
				(font
					(size 1 1)
					(thickness 0.15)
				)
			)
		)
		(property "Val" "0R"
			(at 173.8 385.7 0)
			(layer "F.Fab")
			(hide yes)
			(effects
				(font
					(size 1 1)
					(thickness 0.15)
				)
			)
		)
		(sheetname "/HDMI + SD Card/")
		(sheetfile "hdmi-sd-card.kicad_sch")
		(attr smd)
		(fp_rect
			(start -0.93 -0.47)
			(end 0.93 0.47)
			(stroke
				(width 0.05)
				(type solid)
			)
			(fill no)
			(layer "F.CrtYd")
		)
		(fp_rect
			(start -0.5 -0.25)
			(end 0.5 0.25)
			(stroke
				(width 0.15)
				(type solid)
			)
			(fill no)
			(layer "F.Fab")
		)
		(pad "1" smd roundrect
			(at -0.485 0 180)
			(size 0.59 0.64)
			(layers "F.Cu" "F.Mask" "F.Paste")
			(roundrect_rratio 0.25)
			(net 663 "/FPGA bank 16/HDMI.D1_N")
			(pintype "passive")
		)
		(pad "2" smd roundrect
			(at 0.485 0 180)
			(size 0.59 0.64)
			(layers "F.Cu" "F.Mask" "F.Paste")
			(roundrect_rratio 0.25)
			(net 295 "/HDMI + SD Card/HDMI_CONN_D1_N")
			(pintype "passive")
		)
	)
	(footprint "antmicro-footprints:R_0402_1005Metric"
		(layer "F.Cu")
		(at 86.9 193.85 180)
		(descr "Resistor SMD 0402")
		(tags "resistor SMD 0402")
		(property "Reference" "R72"
			(at -1.122484 -0.772697 180)
			(layer "F.SilkS")
			(hide yes)
			(effects
				(font
					(size 0.7 0.7)
					(thickness 0.15)
				)
				(justify left bottom)
			)
		)
		(property "Value" "R_0R_0402"
			(at -1.011843 1.772047 180)
			(layer "F.Fab")
			(effects
				(font
					(size 0.7 0.7)
					(thickness 0.15)
				)
				(justify left bottom)
			)
		)
		(property "Datasheet" "https://industrial.panasonic.com/cdbs/www-data/pdf/RDA0000/AOA0000C301.pdf"
			(at 0 0 180)
			(layer "F.Fab")
			(hide yes)
			(effects
				(font
					(size 1.27 1.27)
					(thickness 0.15)
				)
			)
		)
		(property "Author" "Antmicro"
			(at 173.8 387.7 0)
			(layer "F.Fab")
			(hide yes)
			(effects
				(font
					(size 1 1)
					(thickness 0.15)
				)
			)
		)
		(property "Current" "1A"
			(at 173.8 387.7 0)
			(layer "F.Fab")
			(hide yes)
			(effects
				(font
					(size 1 1)
					(thickness 0.15)
				)
			)
		)
		(property "License" "Apache-2.0"
			(at 173.8 387.7 0)
			(layer "F.Fab")
			(hide yes)
			(effects
				(font
					(size 1 1)
					(thickness 0.15)
				)
			)
		)
		(property "MPN" "ERJ2GE0R00X"
			(at 173.8 387.7 0)
			(layer "F.Fab")
			(hide yes)
			(effects
				(font
					(size 1 1)
					(thickness 0.15)
				)
			)
		)
		(property "Manufacturer" "Panasonic"
			(at 173.8 387.7 0)
			(layer "F.Fab")
			(hide yes)
			(effects
				(font
					(size 1 1)
					(thickness 0.15)
				)
			)
		)
		(property "Tolerance" ""
			(at 173.8 387.7 0)
			(layer "F.Fab")
			(hide yes)
			(effects
				(font
					(size 1 1)
					(thickness 0.15)
				)
			)
		)
		(property "Val" "0R"
			(at 173.8 387.7 0)
			(layer "F.Fab")
			(hide yes)
			(effects
				(font
					(size 1 1)
					(thickness 0.15)
				)
			)
		)
		(sheetname "/HDMI + SD Card/")
		(sheetfile "hdmi-sd-card.kicad_sch")
		(attr smd)
		(fp_rect
			(start -0.93 -0.47)
			(end 0.93 0.47)
			(stroke
				(width 0.05)
				(type solid)
			)
			(fill no)
			(layer "F.CrtYd")
		)
		(fp_rect
			(start -0.5 -0.25)
			(end 0.5 0.25)
			(stroke
				(width 0.15)
				(type solid)
			)
			(fill no)
			(layer "F.Fab")
		)
		(pad "1" smd roundrect
			(at -0.485 0 180)
			(size 0.59 0.64)
			(layers "F.Cu" "F.Mask" "F.Paste")
			(roundrect_rratio 0.25)
			(net 662 "/FPGA bank 16/HDMI.D1_P")
			(pintype "passive")
		)
		(pad "2" smd roundrect
			(at 0.485 0 180)
			(size 0.59 0.64)
			(layers "F.Cu" "F.Mask" "F.Paste")
			(roundrect_rratio 0.25)
			(net 294 "/HDMI + SD Card/HDMI_CONN_D1_P")
			(pintype "passive")
		)
	)
	(footprint "antmicro-footprints:R_0402_1005Metric"
		(layer "F.Cu")
		(at 84.65 194.35 180)
		(descr "Resistor SMD 0402")
		(tags "resistor SMD 0402")
		(property "Reference" "R71"
			(at -1.122484 -0.772697 180)
			(layer "F.SilkS")
			(hide yes)
			(effects
				(font
					(size 0.7 0.7)
					(thickness 0.15)
				)
				(justify left bottom)
			)
		)
		(property "Value" "R_0R_0402"
			(at -1.011843 1.772047 180)
			(layer "F.Fab")
			(effects
				(font
					(size 0.7 0.7)
					(thickness 0.15)
				)
				(justify left bottom)
			)
		)
		(property "Datasheet" "https://industrial.panasonic.com/cdbs/www-data/pdf/RDA0000/AOA0000C301.pdf"
			(at 0 0 180)
			(layer "F.Fab")
			(hide yes)
			(effects
				(font
					(size 1.27 1.27)
					(thickness 0.15)
				)
			)
		)
		(property "Author" "Antmicro"
			(at 169.3 388.7 0)
			(layer "F.Fab")
			(hide yes)
			(effects
				(font
					(size 1 1)
					(thickness 0.15)
				)
			)
		)
		(property "Current" "1A"
			(at 169.3 388.7 0)
			(layer "F.Fab")
			(hide yes)
			(effects
				(font
					(size 1 1)
					(thickness 0.15)
				)
			)
		)
		(property "License" "Apache-2.0"
			(at 169.3 388.7 0)
			(layer "F.Fab")
			(hide yes)
			(effects
				(font
					(size 1 1)
					(thickness 0.15)
				)
			)
		)
		(property "MPN" "ERJ2GE0R00X"
			(at 169.3 388.7 0)
			(layer "F.Fab")
			(hide yes)
			(effects
				(font
					(size 1 1)
					(thickness 0.15)
				)
			)
		)
		(property "Manufacturer" "Panasonic"
			(at 169.3 388.7 0)
			(layer "F.Fab")
			(hide yes)
			(effects
				(font
					(size 1 1)
					(thickness 0.15)
				)
			)
		)
		(property "Tolerance" ""
			(at 169.3 388.7 0)
			(layer "F.Fab")
			(hide yes)
			(effects
				(font
					(size 1 1)
					(thickness 0.15)
				)
			)
		)
		(property "Val" "0R"
			(at 169.3 388.7 0)
			(layer "F.Fab")
			(hide yes)
			(effects
				(font
					(size 1 1)
					(thickness 0.15)
				)
			)
		)
		(sheetname "/HDMI + SD Card/")
		(sheetfile "hdmi-sd-card.kicad_sch")
		(attr smd)
		(fp_rect
			(start -0.93 -0.47)
			(end 0.93 0.47)
			(stroke
				(width 0.05)
				(type solid)
			)
			(fill no)
			(layer "F.CrtYd")
		)
		(fp_rect
			(start -0.5 -0.25)
			(end 0.5 0.25)
			(stroke
				(width 0.15)
				(type solid)
			)
			(fill no)
			(layer "F.Fab")
		)
		(pad "1" smd roundrect
			(at -0.485 0 180)
			(size 0.59 0.64)
			(layers "F.Cu" "F.Mask" "F.Paste")
			(roundrect_rratio 0.25)
			(net 661 "/FPGA bank 16/HDMI.D2_N")
			(pintype "passive")
		)
		(pad "2" smd roundrect
			(at 0.485 0 180)
			(size 0.59 0.64)
			(layers "F.Cu" "F.Mask" "F.Paste")
			(roundrect_rratio 0.25)
			(net 293 "/HDMI + SD Card/HDMI_CONN_D2_N")
			(pintype "passive")
		)
	)
	(footprint "antmicro-footprints:R_0402_1005Metric"
		(layer "F.Cu")
		(at 84.65 195.35 180)
		(descr "Resistor SMD 0402")
		(tags "resistor SMD 0402")
		(property "Reference" "R70"
			(at -1.122484 -0.772697 180)
			(layer "F.SilkS")
			(hide yes)
			(effects
				(font
					(size 0.7 0.7)
					(thickness 0.15)
				)
				(justify left bottom)
			)
		)
		(property "Value" "R_0R_0402"
			(at -1.011843 1.772047 180)
			(layer "F.Fab")
			(effects
				(font
					(size 0.7 0.7)
					(thickness 0.15)
				)
				(justify left bottom)
			)
		)
		(property "Datasheet" "https://industrial.panasonic.com/cdbs/www-data/pdf/RDA0000/AOA0000C301.pdf"
			(at 0 0 180)
			(layer "F.Fab")
			(hide yes)
			(effects
				(font
					(size 1.27 1.27)
					(thickness 0.15)
				)
			)
		)
		(property "Author" "Antmicro"
			(at 169.3 390.7 0)
			(layer "F.Fab")
			(hide yes)
			(effects
				(font
					(size 1 1)
					(thickness 0.15)
				)
			)
		)
		(property "Current" "1A"
			(at 169.3 390.7 0)
			(layer "F.Fab")
			(hide yes)
			(effects
				(font
					(size 1 1)
					(thickness 0.15)
				)
			)
		)
		(property "License" "Apache-2.0"
			(at 169.3 390.7 0)
			(layer "F.Fab")
			(hide yes)
			(effects
				(font
					(size 1 1)
					(thickness 0.15)
				)
			)
		)
		(property "MPN" "ERJ2GE0R00X"
			(at 169.3 390.7 0)
			(layer "F.Fab")
			(hide yes)
			(effects
				(font
					(size 1 1)
					(thickness 0.15)
				)
			)
		)
		(property "Manufacturer" "Panasonic"
			(at 169.3 390.7 0)
			(layer "F.Fab")
			(hide yes)
			(effects
				(font
					(size 1 1)
					(thickness 0.15)
				)
			)
		)
		(property "Tolerance" ""
			(at 169.3 390.7 0)
			(layer "F.Fab")
			(hide yes)
			(effects
				(font
					(size 1 1)
					(thickness 0.15)
				)
			)
		)
		(property "Val" "0R"
			(at 169.3 390.7 0)
			(layer "F.Fab")
			(hide yes)
			(effects
				(font
					(size 1 1)
					(thickness 0.15)
				)
			)
		)
		(sheetname "/HDMI + SD Card/")
		(sheetfile "hdmi-sd-card.kicad_sch")
		(attr smd)
		(fp_rect
			(start -0.93 -0.47)
			(end 0.93 0.47)
			(stroke
				(width 0.05)
				(type solid)
			)
			(fill no)
			(layer "F.CrtYd")
		)
		(fp_rect
			(start -0.5 -0.25)
			(end 0.5 0.25)
			(stroke
				(width 0.15)
				(type solid)
			)
			(fill no)
			(layer "F.Fab")
		)
		(pad "1" smd roundrect
			(at -0.485 0 180)
			(size 0.59 0.64)
			(layers "F.Cu" "F.Mask" "F.Paste")
			(roundrect_rratio 0.25)
			(net 660 "/FPGA bank 16/HDMI.D2_P")
			(pintype "passive")
		)
		(pad "2" smd roundrect
			(at 0.485 0 180)
			(size 0.59 0.64)
			(layers "F.Cu" "F.Mask" "F.Paste")
			(roundrect_rratio 0.25)
			(net 292 "/HDMI + SD Card/HDMI_CONN_D2_P")
			(pintype "passive")
		)
	)
	(footprint "antmicro-footprints:TP_SMD_1mm"
		(layer "F.Cu")
		(at 84.3 188.2)
		(property "Reference" "TP5"
			(at -2.65 0.85 0)
			(layer "F.SilkS")
			(effects
				(font
					(size 0.7 0.7)
					(thickness 0.15)
				)
				(justify left bottom)
			)
		)
		(property "Value" "TP_1mm_SMD"
			(at 0 1.4 0)
			(layer "F.Fab")
			(effects
				(font
					(size 0.7 0.7)
					(thickness 0.15)
				)
				(justify left bottom)
			)
		)
		(property "Author" "Antmicro"
			(at 0 0 0)
			(layer "F.Fab")
			(hide yes)
			(effects
				(font
					(size 1 1)
					(thickness 0.15)
				)
			)
		)
		(property "License" "Apache-2.0"
			(at 0 0 0)
			(layer "F.Fab")
			(hide yes)
			(effects
				(font
					(size 1 1)
					(thickness 0.15)
				)
			)
		)
		(property "MPN" ""
			(at 0 0 0)
			(layer "F.Fab")
			(hide yes)
			(effects
				(font
					(size 1 1)
					(thickness 0.15)
				)
			)
		)
		(property "Manufacturer" ""
			(at 0 0 0)
			(layer "F.Fab")
			(hide yes)
			(effects
				(font
					(size 1 1)
					(thickness 0.15)
				)
			)
		)
		(sheetname "/HDMI + SD Card/")
		(sheetfile "hdmi-sd-card.kicad_sch")
		(attr exclude_from_pos_files)
		(pad "1" smd circle
			(at 0 0)
			(size 1 1)
			(layers "F.Cu" "F.Mask")
			(net 325 "Net-(J4-CEC)")
			(pinfunction "1")
			(pintype "passive")
		)
	)
	(footprint "antmicro-footprints:TP_SMD_1mm"
		(layer "F.Cu")
		(at 83 187.3)
		(property "Reference" "TP3"
			(at -2.65 0.65 0)
			(layer "F.SilkS")
			(effects
				(font
					(size 0.7 0.7)
					(thickness 0.15)
				)
				(justify left bottom)
			)
		)
		(property "Value" "TP_1mm_SMD"
			(at 0 1.4 0)
			(layer "F.Fab")
			(effects
				(font
					(size 0.7 0.7)
					(thickness 0.15)
				)
				(justify left bottom)
			)
		)
		(property "Author" "Antmicro"
			(at 0 0 0)
			(layer "F.Fab")
			(hide yes)
			(effects
				(font
					(size 1 1)
					(thickness 0.15)
				)
			)
		)
		(property "License" "Apache-2.0"
			(at 0 0 0)
			(layer "F.Fab")
			(hide yes)
			(effects
				(font
					(size 1 1)
					(thickness 0.15)
				)
			)
		)
		(property "MPN" ""
			(at 0 0 0)
			(layer "F.Fab")
			(hide yes)
			(effects
				(font
					(size 1 1)
					(thickness 0.15)
				)
			)
		)
		(property "Manufacturer" ""
			(at 0 0 0)
			(layer "F.Fab")
			(hide yes)
			(effects
				(font
					(size 1 1)
					(thickness 0.15)
				)
			)
		)
		(sheetname "/HDMI + SD Card/")
		(sheetfile "hdmi-sd-card.kicad_sch")
		(attr exclude_from_pos_files)
		(pad "1" smd circle
			(at 0 0)
			(size 1 1)
			(layers "F.Cu" "F.Mask")
			(net 327 "Net-(J4-SCL)")
			(pinfunction "1")
			(pintype "passive")
		)
	)
	(footprint "antmicro-footprints:TP_SMD_1mm"
		(layer "F.Cu")
		(at 84.3 184.2)
		(property "Reference" "TP6"
			(at -2.65 0.65 0)
			(layer "F.SilkS")
			(effects
				(font
					(size 0.7 0.7)
					(thickness 0.15)
				)
				(justify left bottom)
			)
		)
		(property "Value" "TP_1mm_SMD"
			(at 0 1.4 0)
			(layer "F.Fab")
			(effects
				(font
					(size 0.7 0.7)
					(thickness 0.15)
				)
				(justify left bottom)
			)
		)
		(property "Author" "Antmicro"
			(at 0 0 0)
			(layer "F.Fab")
			(hide yes)
			(effects
				(font
					(size 1 1)
					(thickness 0.15)
				)
			)
		)
		(property "License" "Apache-2.0"
			(at 0 0 0)
			(layer "F.Fab")
			(hide yes)
			(effects
				(font
					(size 1 1)
					(thickness 0.15)
				)
			)
		)
		(property "MPN" ""
			(at 0 0 0)
			(layer "F.Fab")
			(hide yes)
			(effects
				(font
					(size 1 1)
					(thickness 0.15)
				)
			)
		)
		(property "Manufacturer" ""
			(at 0 0 0)
			(layer "F.Fab")
			(hide yes)
			(effects
				(font
					(size 1 1)
					(thickness 0.15)
				)
			)
		)
		(sheetname "/HDMI + SD Card/")
		(sheetfile "hdmi-sd-card.kicad_sch")
		(attr exclude_from_pos_files)
		(pad "1" smd circle
			(at 0 0)
			(size 1 1)
			(layers "F.Cu" "F.Mask")
			(net 329 "Net-(J4-HPD{slash}HEAC-)")
			(pinfunction "1")
			(pintype "passive")
		)
	)
	(footprint "antmicro-footprints:TP_SMD_1mm"
		(layer "F.Cu")
		(at 84.3 186.1)
		(property "Reference" "TP4"
			(at -2.65 0.65 0)
			(layer "F.SilkS")
			(effects
				(font
					(size 0.7 0.7)
					(thickness 0.15)
				)
				(justify left bottom)
			)
		)
		(property "Value" "TP_1mm_SMD"
			(at 0 1.4 0)
			(layer "F.Fab")
			(effects
				(font
					(size 0.7 0.7)
					(thickness 0.15)
				)
				(justify left bottom)
			)
		)
		(property "Author" "Antmicro"
			(at 0 0 0)
			(layer "F.Fab")
			(hide yes)
			(effects
				(font
					(size 1 1)
					(thickness 0.15)
				)
			)
		)
		(property "License" "Apache-2.0"
			(at 0 0 0)
			(layer "F.Fab")
			(hide yes)
			(effects
				(font
					(size 1 1)
					(thickness 0.15)
				)
			)
		)
		(property "MPN" ""
			(at 0 0 0)
			(layer "F.Fab")
			(hide yes)
			(effects
				(font
					(size 1 1)
					(thickness 0.15)
				)
			)
		)
		(property "Manufacturer" ""
			(at 0 0 0)
			(layer "F.Fab")
			(hide yes)
			(effects
				(font
					(size 1 1)
					(thickness 0.15)
				)
			)
		)
		(sheetname "/HDMI + SD Card/")
		(sheetfile "hdmi-sd-card.kicad_sch")
		(attr exclude_from_pos_files)
		(pad "1" smd circle
			(at 0 0)
			(size 1 1)
			(layers "F.Cu" "F.Mask")
			(net 328 "Net-(J4-SDA)")
			(pinfunction "1")
			(pintype "passive")
		)
	)
	(footprint "antmicro-footprints:TP_SMD_1mm"
		(layer "F.Cu")
		(at 85.75 183.05)
		(property "Reference" "TP2"
			(at -2.65 0.65 0)
			(layer "F.SilkS")
			(hide yes)
			(effects
				(font
					(size 0.7 0.7)
					(thickness 0.15)
				)
				(justify left bottom)
			)
		)
		(property "Value" "TP_1mm_SMD"
			(at 0 1.4 0)
			(layer "F.Fab")
			(effects
				(font
					(size 0.7 0.7)
					(thickness 0.15)
				)
				(justify left bottom)
			)
		)
		(property "Author" "Antmicro"
			(at 0 0 0)
			(layer "F.Fab")
			(hide yes)
			(effects
				(font
					(size 1 1)
					(thickness 0.15)
				)
			)
		)
		(property "License" "Apache-2.0"
			(at 0 0 0)
			(layer "F.Fab")
			(hide yes)
			(effects
				(font
					(size 1 1)
					(thickness 0.15)
				)
			)
		)
		(property "MPN" ""
			(at 0 0 0)
			(layer "F.Fab")
			(hide yes)
			(effects
				(font
					(size 1 1)
					(thickness 0.15)
				)
			)
		)
		(property "Manufacturer" ""
			(at 0 0 0)
			(layer "F.Fab")
			(hide yes)
			(effects
				(font
					(size 1 1)
					(thickness 0.15)
				)
			)
		)
		(sheetname "/HDMI + SD Card/")
		(sheetfile "hdmi-sd-card.kicad_sch")
		(attr exclude_from_pos_files)
		(pad "1" smd circle
			(at 0 0)
			(size 1 1)
			(layers "F.Cu" "F.Mask")
			(net 9 "/HDMI + SD Card/HDMI_CONN_5V")
			(pinfunction "1")
			(pintype "passive")
		)
	)
	(footprint "antmicro-footprints:HDMI-A_Receptacle_WE_685119134923"
		(layer "F.Cu")
		(at 73.020501 190.766 90)
		(property "Reference" "J4"
			(at -9.134 -3.820501 180)
			(layer "F.SilkS")
			(effects
				(font
					(size 0.7 0.7)
					(thickness 0.15)
				)
				(justify left bottom)
			)
		)
		(property "Value" "HDMI-A_WE_685119134923"
			(at 0 7.8 90)
			(layer "F.Fab")
			(effects
				(font
					(size 0.7 0.7)
					(thickness 0.15)
				)
				(justify left bottom)
			)
		)
		(property "Datasheet" "https://www.we-online.com/components/products/datasheet/685119134923.pdf"
			(at 0 0 90)
			(layer "F.Fab")
			(hide yes)
			(effects
				(font
					(size 1.27 1.27)
					(thickness 0.15)
				)
			)
		)
		(property "Author" "Antmicro"
			(at 263.786501 117.745499 0)
			(layer "F.Fab")
			(hide yes)
			(effects
				(font
					(size 1 1)
					(thickness 0.15)
				)
			)
		)
		(property "License" "Apache-2.0"
			(at 263.786501 117.745499 0)
			(layer "F.Fab")
			(hide yes)
			(effects
				(font
					(size 1 1)
					(thickness 0.15)
				)
			)
		)
		(property "MPN" "685119134923"
			(at 263.786501 117.745499 0)
			(layer "F.Fab")
			(hide yes)
			(effects
				(font
					(size 1 1)
					(thickness 0.15)
				)
			)
		)
		(property "Manufacturer" "Würth Elektronik"
			(at 263.786501 117.745499 0)
			(layer "F.Fab")
			(hide yes)
			(effects
				(font
					(size 1 1)
					(thickness 0.15)
				)
			)
		)
		(property ki_fp_filters "685119134923")
		(sheetname "/HDMI + SD Card/")
		(sheetfile "hdmi-sd-card.kicad_sch")
		(attr smd)
		(fp_line
			(start -7.55 -0.125)
			(end -7.55 2.65)
			(stroke
				(width 0.12)
				(type solid)
			)
			(layer "F.SilkS")
		)
		(fp_line
			(start 7.55 2.75)
			(end 7.55 -0.15)
			(stroke
				(width 0.12)
				(type solid)
			)
			(layer "F.SilkS")
		)
		(fp_line
			(start 5.7 5.65)
			(end 4.75 5.65)
			(stroke
				(width 0.12)
				(type solid)
			)
			(layer "F.SilkS")
		)
		(fp_line
			(start -4.85 5.65)
			(end -5.8 5.65)
			(stroke
				(width 0.12)
				(type solid)
			)
			(layer "F.SilkS")
		)
		(fp_circle
			(center -4.9 5.9)
			(end -4.85 5.9)
			(stroke
				(width 0.15)
				(type solid)
			)
			(fill no)
			(layer "F.SilkS")
		)
		(fp_rect
			(start -8.05 -6.32)
			(end 7.949 6.78)
			(stroke
				(width 0.05)
				(type solid)
			)
			(fill no)
			(layer "F.CrtYd")
		)
		(fp_line
			(start -7.05 -5.616)
			(end 6.95 -5.616)
			(stroke
				(width 0.15)
				(type solid)
			)
			(layer "F.Fab")
		)
		(fp_line
			(start -7.05 5.525)
			(end -7.05 -5.616)
			(stroke
				(width 0.15)
				(type solid)
			)
			(layer "F.Fab")
		)
		(fp_line
			(start -7.05 5.525)
			(end -6.05 6.525)
			(stroke
				(width 0.15)
				(type solid)
			)
			(layer "F.Fab")
		)
		(fp_line
			(start 6.95 6.535)
			(end 6.95 -5.616)
			(stroke
				(width 0.15)
				(type solid)
			)
			(layer "F.Fab")
		)
		(fp_line
			(start 6.95 6.535)
			(end -6.05 6.535)
			(stroke
				(width 0.15)
				(type solid)
			)
			(layer "F.Fab")
		)
		(pad "1" smd rect
			(at -4.55 5.224 90)
			(size 0.28 2.6)
			(layers "F.Cu" "F.Mask" "F.Paste")
			(net 292 "/HDMI + SD Card/HDMI_CONN_D2_P")
			(pinfunction "D2+")
			(pintype "bidirectional")
		)
		(pad "2" smd rect
			(at -4.05 5.224 90)
			(size 0.28 2.6)
			(layers "F.Cu" "F.Mask" "F.Paste")
			(net 1 "GND")
			(pinfunction "D2S")
			(pintype "passive")
		)
		(pad "3" smd rect
			(at -3.551 5.224 90)
			(size 0.28 2.6)
			(layers "F.Cu" "F.Mask" "F.Paste")
			(net 293 "/HDMI + SD Card/HDMI_CONN_D2_N")
			(pinfunction "D2-")
			(pintype "bidirectional")
		)
		(pad "4" smd rect
			(at -3.051 5.224 90)
			(size 0.28 2.6)
			(layers "F.Cu" "F.Mask" "F.Paste")
			(net 294 "/HDMI + SD Card/HDMI_CONN_D1_P")
			(pinfunction "D1+")
			(pintype "bidirectional")
		)
		(pad "5" smd rect
			(at -2.551 5.224 90)
			(size 0.28 2.6)
			(layers "F.Cu" "F.Mask" "F.Paste")
			(net 1 "GND")
			(pinfunction "D1S")
			(pintype "passive")
		)
		(pad "6" smd rect
			(at -2.05 5.224 90)
			(size 0.28 2.6)
			(layers "F.Cu" "F.Mask" "F.Paste")
			(net 295 "/HDMI + SD Card/HDMI_CONN_D1_N")
			(pinfunction "D1-")
			(pintype "bidirectional")
		)
		(pad "7" smd rect
			(at -1.551 5.224 90)
			(size 0.28 2.6)
			(layers "F.Cu" "F.Mask" "F.Paste")
			(net 296 "/HDMI + SD Card/HDMI_CONN_D0_P")
			(pinfunction "D0+")
			(pintype "bidirectional")
		)
		(pad "8" smd rect
			(at -1.051 5.224 90)
			(size 0.28 2.6)
			(layers "F.Cu" "F.Mask" "F.Paste")
			(net 1 "GND")
			(pinfunction "D0S")
			(pintype "passive")
		)
		(pad "9" smd rect
			(at -0.551 5.224 90)
			(size 0.28 2.6)
			(layers "F.Cu" "F.Mask" "F.Paste")
			(net 311 "/HDMI + SD Card/HDMI_CONN_D0_N")
			(pinfunction "D0-")
			(pintype "bidirectional")
		)
		(pad "10" smd rect
			(at -0.051 5.224 90)
			(size 0.28 2.6)
			(layers "F.Cu" "F.Mask" "F.Paste")
			(net 348 "/HDMI + SD Card/HDMI_CONN_CLK_P")
			(pinfunction "CK+")
			(pintype "bidirectional")
		)
		(pad "11" smd rect
			(at 0.45 5.224 90)
			(size 0.28 2.6)
			(layers "F.Cu" "F.Mask" "F.Paste")
			(net 1 "GND")
			(pinfunction "CKS")
			(pintype "passive")
		)
		(pad "12" smd rect
			(at 0.95 5.224 90)
			(size 0.28 2.6)
			(layers "F.Cu" "F.Mask" "F.Paste")
			(net 349 "/HDMI + SD Card/HDMI_CONN_CLK_N")
			(pinfunction "CK-")
			(pintype "bidirectional")
		)
		(pad "13" smd rect
			(at 1.449 5.224 90)
			(size 0.28 2.6)
			(layers "F.Cu" "F.Mask" "F.Paste")
			(net 325 "Net-(J4-CEC)")
			(pinfunction "CEC")
			(pintype "bidirectional")
		)
		(pad "14" smd rect
			(at 1.949 5.224 90)
			(size 0.28 2.6)
			(layers "F.Cu" "F.Mask" "F.Paste")
			(net 326 "unconnected-(J4-UTILITY{slash}HEAC+-Pad14)")
			(pinfunction "UTILITY/HEAC+")
			(pintype "bidirectional+no_connect")
		)
		(pad "15" smd rect
			(at 2.45 5.224 90)
			(size 0.28 2.6)
			(layers "F.Cu" "F.Mask" "F.Paste")
			(net 327 "Net-(J4-SCL)")
			(pinfunction "SCL")
			(pintype "bidirectional")
		)
		(pad "16" smd rect
			(at 2.95 5.224 90)
			(size 0.28 2.6)
			(layers "F.Cu" "F.Mask" "F.Paste")
			(net 328 "Net-(J4-SDA)")
			(pinfunction "SDA")
			(pintype "bidirectional")
		)
		(pad "17" smd rect
			(at 3.45 5.224 90)
			(size 0.28 2.6)
			(layers "F.Cu" "F.Mask" "F.Paste")
			(net 1 "GND")
			(pinfunction "GND")
			(pintype "power_in")
		)
		(pad "18" smd rect
			(at 3.95 5.224 90)
			(size 0.28 2.6)
			(layers "F.Cu" "F.Mask" "F.Paste")
			(net 9 "/HDMI + SD Card/HDMI_CONN_5V")
			(pinfunction "+5V")
			(pintype "power_in")
		)
		(pad "19" smd rect
			(at 4.45 5.224 90)
			(size 0.28 2.6)
			(layers "F.Cu" "F.Mask" "F.Paste")
			(net 329 "Net-(J4-HPD{slash}HEAC-)")
			(pinfunction "HPD/HEAC-")
			(pintype "bidirectional")
		)
		(pad "SH" thru_hole oval
			(at -7.3 -1.577 90)
			(size 1.5 2.7)
			(drill oval 0.9 2.1)
			(layers "*.Cu" "*.Mask")
			(remove_unused_layers no)
			(net 251 "Net-(C132-Pad1)")
			(pinfunction "SH")
			(pintype "passive")
		)
		(pad "SH" thru_hole oval
			(at -7.3 4.424 90)
			(size 1.5 3.3)
			(drill oval 0.9 2.7)
			(layers "*.Cu" "*.Mask")
			(remove_unused_layers no)
			(net 251 "Net-(C132-Pad1)")
			(pinfunction "SH")
			(pintype "passive")
		)
		(pad "SH" thru_hole oval
			(at 7.2 -1.577 90)
			(size 1.5 2.7)
			(drill oval 0.9 2.1)
			(layers "*.Cu" "*.Mask")
			(remove_unused_layers no)
			(net 251 "Net-(C132-Pad1)")
			(pinfunction "SH")
			(pintype "passive")
		)
		(pad "SH" thru_hole oval
			(at 7.2 4.424 90)
			(size 1.5 3.3)
			(drill oval 0.9 2.7)
			(layers "*.Cu" "*.Mask")
			(remove_unused_layers no)
			(net 251 "Net-(C132-Pad1)")
			(pinfunction "SH")
			(pintype "passive")
		)
	)
	(footprint "antmicro-footprints:SOD-523"
		(layer "F.Cu")
		(at 86.277001 186.1005)
		(property "Reference" "D14"
			(at 0 -0.75 0)
			(layer "F.SilkS")
			(hide yes)
			(effects
				(font
					(size 0.7 0.7)
					(thickness 0.15)
				)
				(justify left bottom)
			)
		)
		(property "Value" "BAT54-02V-G3-08"
			(at 0 1.499 0)
			(layer "F.Fab")
			(effects
				(font
					(size 0.7 0.7)
					(thickness 0.15)
				)
				(justify left bottom)
			)
		)
		(property "Datasheet" "https://www.vishay.com/docs/85633/bat5402v.pdf"
			(at 0 0 0)
			(layer "F.Fab")
			(hide yes)
			(effects
				(font
					(size 1.27 1.27)
					(thickness 0.15)
				)
			)
		)
		(property "Description" "Small Signal Schottky Diode, Single, 30 V, 200 mA, 800 mV, 600 mA, 125 °C"
			(at 0 0 0)
			(layer "F.Fab")
			(hide yes)
			(effects
				(font
					(size 1.27 1.27)
					(thickness 0.15)
				)
			)
		)
		(property "Author" "Antmicro"
			(at 0 0 0)
			(layer "F.Fab")
			(hide yes)
			(effects
				(font
					(size 1 1)
					(thickness 0.15)
				)
			)
		)
		(property "License" "Apache-2.0"
			(at 0 0 0)
			(layer "F.Fab")
			(hide yes)
			(effects
				(font
					(size 1 1)
					(thickness 0.15)
				)
			)
		)
		(property "MPN" "BAT54-02V-G3-08"
			(at 0 0 0)
			(layer "F.Fab")
			(hide yes)
			(effects
				(font
					(size 1 1)
					(thickness 0.15)
				)
			)
		)
		(property "Manufacturer" "Vishay"
			(at 0 0 0)
			(layer "F.Fab")
			(hide yes)
			(effects
				(font
					(size 1 1)
					(thickness 0.15)
				)
			)
		)
		(sheetname "/HDMI + SD Card/")
		(sheetfile "hdmi-sd-card.kicad_sch")
		(attr smd)
		(fp_line
			(start -0.35 -0.5)
			(end -0.35 0.5)
			(stroke
				(width 0.15)
				(type solid)
			)
			(layer "F.SilkS")
		)
		(fp_rect
			(start -1 -0.6)
			(end 1 0.6)
			(stroke
				(width 0.05)
				(type solid)
			)
			(fill no)
			(layer "F.CrtYd")
		)
		(fp_line
			(start -0.652 -0.425)
			(end 0.65 -0.425)
			(stroke
				(width 0.15)
				(type solid)
			)
			(layer "F.Fab")
		)
		(fp_line
			(start -0.652 0.423)
			(end -0.652 -0.425)
			(stroke
				(width 0.15)
				(type solid)
			)
			(layer "F.Fab")
		)
		(fp_line
			(start -0.652 0.423)
			(end 0.65 0.423)
			(stroke
				(width 0.15)
				(type solid)
			)
			(layer "F.Fab")
		)
		(fp_line
			(start -0.35 -0.4)
			(end -0.35 0.4)
			(stroke
				(width 0.15)
				(type solid)
			)
			(layer "F.Fab")
		)
		(fp_line
			(start 0.65 -0.425)
			(end 0.65 0.423)
			(stroke
				(width 0.15)
				(type solid)
			)
			(layer "F.Fab")
		)
		(pad "1" smd roundrect
			(at -0.701 0)
			(size 0.5 0.6)
			(layers "F.Cu" "F.Mask" "F.Paste")
			(roundrect_rratio 0.25)
			(net 9 "/HDMI + SD Card/HDMI_CONN_5V")
			(pinfunction "C")
			(pintype "passive")
		)
		(pad "2" smd roundrect
			(at 0.699 0)
			(size 0.5 0.6)
			(layers "F.Cu" "F.Mask" "F.Paste")
			(roundrect_rratio 0.25)
			(net 34 "/HDMI + SD Card/HDMI_5V")
			(pinfunction "A")
			(pintype "passive")
		)
	)
	(footprint "antmicro-footprints:BGA-676_27x27mm_Layout26x26_P1x1mm_FFG676"
		(layer "F.Cu")
		(at 138.875501 174.801 180)
		(descr "FPGA XC7K160TFBG676")
		(tags "FPGA XC7K160TFBG676")
		(property "Reference" "U4"
			(at -12.224499 14.051 180)
			(layer "F.SilkS")
			(effects
				(font
					(size 0.7 0.7)
					(thickness 0.15)
				)
				(justify left bottom)
			)
		)
		(property "Value" "XC7K160T-FFG676"
			(at 0 15.5 180)
			(layer "F.Fab")
			(effects
				(font
					(size 0.7 0.7)
					(thickness 0.15)
				)
				(justify left bottom)
			)
		)
		(property "Datasheet" "https://docs.xilinx.com/v/u/en-US/ds180_7Series_Overview"
			(at 0 0 180)
			(layer "F.Fab")
			(hide yes)
			(effects
				(font
					(size 1.27 1.27)
					(thickness 0.15)
				)
			)
		)
		(property "Author" "Antmicro"
			(at 277.751002 349.602 0)
			(layer "F.Fab")
			(hide yes)
			(effects
				(font
					(size 1 1)
					(thickness 0.15)
				)
			)
		)
		(property "License" "Apache-2.0"
			(at 277.751002 349.602 0)
			(layer "F.Fab")
			(hide yes)
			(effects
				(font
					(size 1 1)
					(thickness 0.15)
				)
			)
		)
		(property "MPN" "XC7K160T-FFG676"
			(at 277.751002 349.602 0)
			(layer "F.Fab")
			(hide yes)
			(effects
				(font
					(size 1 1)
					(thickness 0.15)
				)
			)
		)
		(property "Manufacturer" "AMD-Xilinx"
			(at 277.751002 349.602 0)
			(layer "F.Fab")
			(hide yes)
			(effects
				(font
					(size 1 1)
					(thickness 0.15)
				)
			)
		)
		(sheetname "/FPGA Config/")
		(sheetfile "fpga-config.kicad_sch")
		(attr smd)
		(fp_line
			(start 13.499 13.499)
			(end 13.499 6.749)
			(stroke
				(width 0.15)
				(type solid)
			)
			(layer "F.SilkS")
		)
		(fp_line
			(start 13.499 13.499)
			(end 6.749 13.499)
			(stroke
				(width 0.15)
				(type solid)
			)
			(layer "F.SilkS")
		)
		(fp_line
			(start 13.499 -13.5)
			(end 13.499 -6.75)
			(stroke
				(width 0.15)
				(type solid)
			)
			(layer "F.SilkS")
		)
		(fp_line
			(start 13.499 -13.5)
			(end 6.749 -13.5)
			(stroke
				(width 0.15)
				(type solid)
			)
			(layer "F.SilkS")
		)
		(fp_line
			(start -13.5 13.499)
			(end -6.75 13.499)
			(stroke
				(width 0.15)
				(type solid)
			)
			(layer "F.SilkS")
		)
		(fp_line
			(start -13.5 13.499)
			(end -13.5 6.749)
			(stroke
				(width 0.15)
				(type solid)
			)
			(layer "F.SilkS")
		)
		(fp_line
			(start -13.5 -13.5)
			(end -6.75 -13.5)
			(stroke
				(width 0.15)
				(type solid)
			)
			(layer "F.SilkS")
		)
		(fp_line
			(start -13.5 -13.5)
			(end -13.5 -6.75)
			(stroke
				(width 0.15)
				(type solid)
			)
			(layer "F.SilkS")
		)
		(fp_circle
			(center -14 -14)
			(end -13.95 -13.94)
			(stroke
				(width 0.15)
				(type solid)
			)
			(fill yes)
			(layer "F.SilkS")
		)
		(fp_rect
			(start -14.5 -14.5)
			(end 14.5 14.5)
			(stroke
				(width 0.05)
				(type solid)
			)
			(fill no)
			(layer "F.CrtYd")
		)
		(fp_rect
			(start -13.5 -13.5)
			(end 13.499 13.499)
			(stroke
				(width 0.15)
				(type solid)
			)
			(fill no)
			(layer "F.Fab")
		)
		(pad "A1" smd circle
			(at -12.5 -12.5 180)
			(size 0.5 0.5)
			(layers "F.Cu" "F.Mask" "F.Paste")
			(net 1 "GND")
			(pinfunction "GND")
			(pintype "power_in")
		)
		(pad "A2" smd circle
			(at -11.5 -12.5 180)
			(size 0.5 0.5)
			(layers "F.Cu" "F.Mask" "F.Paste")
			(net 1 "GND")
			(pinfunction "GND")
			(pintype "passive")
		)
		(pad "A3" smd circle
			(at -10.5 -12.5 180)
			(size 0.5 0.5)
			(layers "F.Cu" "F.Mask" "F.Paste")
			(net 29 "/FPGA MGT Interface/GTX_TX3_N")
			(pinfunction "MGTXTXN3_116")
			(pintype "bidirectional")
			(die_length 14.476)
		)
		(pad "A4" smd circle
			(at -9.5 -12.5 180)
			(size 0.5 0.5)
			(layers "F.Cu" "F.Mask" "F.Paste")
			(net 23 "/FPGA MGT Interface/GTX_TX3_P")
			(pinfunction "MGTXTXP3_116")
			(pintype "bidirectional")
			(die_length 14.628)
		)
		(pad "A5" smd circle
			(at -8.5 -12.5 180)
			(size 0.5 0.5)
			(layers "F.Cu" "F.Mask" "F.Paste")
			(net 1 "GND")
			(pinfunction "GND")
			(pintype "passive")
		)
		(pad "A6" smd circle
			(at -7.5 -12.5 180)
			(size 0.5 0.5)
			(layers "F.Cu" "F.Mask" "F.Paste")
			(net 1 "GND")
			(pinfunction "GND")
			(pintype "passive")
		)
		(pad "A7" smd circle
			(at -6.5 -12.5 180)
			(size 0.5 0.5)
			(layers "F.Cu" "F.Mask" "F.Paste")
			(net 1 "GND")
			(pinfunction "GND")
			(pintype "passive")
		)
		(pad "A8" smd circle
			(at -5.5 -12.5 180)
			(size 0.5 0.5)
			(layers "F.Cu" "F.Mask" "F.Paste")
			(net 135 "PCIE.PWRGD")
			(pinfunction "IO_L9N_T1_DQS_16")
			(pintype "bidirectional")
			(die_length 19.908)
		)
		(pad "A9" smd circle
			(at -4.5 -12.5 180)
			(size 0.5 0.5)
			(layers "F.Cu" "F.Mask" "F.Paste")
			(net 394 "unconnected-(U4E-IO_L9P_T1_DQS_16-PadA9)")
			(pinfunction "IO_L9P_T1_DQS_16")
			(pintype "bidirectional+no_connect")
			(die_length 19.519)
		)
		(pad "A10" smd circle
			(at -3.5 -12.5 180)
			(size 0.5 0.5)
			(layers "F.Cu" "F.Mask" "F.Paste")
			(net 661 "/FPGA bank 16/HDMI.D2_N")
			(pinfunction "IO_L22N_T3_16")
			(pintype "bidirectional")
			(die_length 20.762)
		)
		(pad "A11" smd circle
			(at -2.5 -12.5 180)
			(size 0.5 0.5)
			(layers "F.Cu" "F.Mask" "F.Paste")
			(net 200 "+3V3")
			(pinfunction "VCCO_16")
			(pintype "power_in")
		)
		(pad "A12" smd circle
			(at -1.5 -12.5 180)
			(size 0.5 0.5)
			(layers "F.Cu" "F.Mask" "F.Paste")
			(net 663 "/FPGA bank 16/HDMI.D1_N")
			(pinfunction "IO_L24N_T3_16")
			(pintype "bidirectional")
			(die_length 22.422)
		)
		(pad "A13" smd circle
			(at -0.5 -12.5 180)
			(size 0.5 0.5)
			(layers "F.Cu" "F.Mask" "F.Paste")
			(net 662 "/FPGA bank 16/HDMI.D1_P")
			(pinfunction "IO_L24P_T3_16")
			(pintype "bidirectional")
			(die_length 22.76)
		)
		(pad "A14" smd circle
			(at 0.499 -12.5 180)
			(size 0.5 0.5)
			(layers "F.Cu" "F.Mask" "F.Paste")
			(net 665 "/FPGA bank 16/HDMI.D0_N")
			(pinfunction "IO_L21N_T3_DQS_16")
			(pintype "bidirectional")
			(die_length 18.115)
		)
		(pad "A15" smd circle
			(at 1.499 -12.5 180)
			(size 0.5 0.5)
			(layers "F.Cu" "F.Mask" "F.Paste")
			(net 667 "/FPGA bank 16/HDMI.CLK_N")
			(pinfunction "IO_L23N_T3_16")
			(pintype "bidirectional")
			(die_length 18.152)
		)
		(pad "A16" smd circle
			(at 2.499 -12.5 180)
			(size 0.5 0.5)
			(layers "F.Cu" "F.Mask" "F.Paste")
			(net 1 "GND")
			(pinfunction "GND")
			(pintype "passive")
		)
		(pad "A17" smd circle
			(at 3.499 -12.5 180)
			(size 0.5 0.5)
			(layers "F.Cu" "F.Mask" "F.Paste")
			(net 395 "unconnected-(U4D-IO_L3N_T0_DQS_AD1N_15-PadA17)")
			(pinfunction "IO_L3N_T0_DQS_AD1N_15")
			(pintype "bidirectional+no_connect")
			(die_length 18.146)
		)
		(pad "A18" smd circle
			(at 4.499 -12.5 180)
			(size 0.5 0.5)
			(layers "F.Cu" "F.Mask" "F.Paste")
			(net 396 "unconnected-(U4D-IO_L2P_T0_AD8P_15-PadA18)")
			(pinfunction "IO_L2P_T0_AD8P_15")
			(pintype "bidirectional+no_connect")
			(die_length 20.209)
		)
		(pad "A19" smd circle
			(at 5.499 -12.5 180)
			(size 0.5 0.5)
			(layers "F.Cu" "F.Mask" "F.Paste")
			(net 397 "unconnected-(U4D-IO_L2N_T0_AD8N_15-PadA19)")
			(pinfunction "IO_L2N_T0_AD8N_15")
			(pintype "bidirectional+no_connect")
			(die_length 19.837)
		)
		(pad "A20" smd circle
			(at 6.499 -12.5 180)
			(size 0.5 0.5)
			(layers "F.Cu" "F.Mask" "F.Paste")
			(net 234 "HOT_SWAP_YELLOW")
			(pinfunction "IO_L8N_T1_D12_14")
			(pintype "bidirectional")
			(die_length 22.195)
		)
		(pad "A21" smd circle
			(at 7.499 -12.5 180)
			(size 0.5 0.5)
			(layers "F.Cu" "F.Mask" "F.Paste")
			(net 200 "+3V3")
			(pinfunction "VCCO_14")
			(pintype "power_in")
		)
		(pad "A22" smd circle
			(at 8.499 -12.5 180)
			(size 0.5 0.5)
			(layers "F.Cu" "F.Mask" "F.Paste")
			(net 629 "/FPGA Config/FLASH.IO3")
			(pinfunction "IO_L2N_T0_D03_14")
			(pintype "bidirectional")
			(die_length 21.482)
		)
		(pad "A23" smd circle
			(at 9.499 -12.5 180)
			(size 0.5 0.5)
			(layers "F.Cu" "F.Mask" "F.Paste")
			(net 645 "/Debug FTDI/UART1.TX")
			(pinfunction "IO_L4P_T0_D04_14")
			(pintype "bidirectional")
			(die_length 21.833)
		)
		(pad "A24" smd circle
			(at 10.499 -12.5 180)
			(size 0.5 0.5)
			(layers "F.Cu" "F.Mask" "F.Paste")
			(net 643 "/Debug FTDI/UART1.RX")
			(pinfunction "IO_L4N_T0_D05_14")
			(pintype "bidirectional")
			(die_length 22.897)
		)
		(pad "A25" smd circle
			(at 11.499 -12.5 180)
			(size 0.5 0.5)
			(layers "F.Cu" "F.Mask" "F.Paste")
			(net 627 "/FPGA Config/FLASH.IO1")
			(pinfunction "IO_L1N_T0_D01_DIN_14")
			(pintype "bidirectional")
			(die_length 23.845)
		)
		(pad "A26" smd circle
			(at 12.499 -12.5 180)
			(size 0.5 0.5)
			(layers "F.Cu" "F.Mask" "F.Paste")
			(net 1 "GND")
			(pinfunction "GND")
			(pintype "passive")
		)
		(pad "AA1" smd circle
			(at -12.5 7.499 180)
			(size 0.5 0.5)
			(layers "F.Cu" "F.Mask" "F.Paste")
			(net 206 "+1V1")
			(pinfunction "VCCO_34")
			(pintype "power_in")
		)
		(pad "AA2" smd circle
			(at -11.5 7.499 180)
			(size 0.5 0.5)
			(layers "F.Cu" "F.Mask" "F.Paste")
			(net 260 "/DDR5 SODIMM/B.DQ17")
			(pinfunction "IO_L12N_T1_MRCC_34")
			(pintype "bidirectional")
			(die_length 19.51)
		)
		(pad "AA3" smd circle
			(at -10.5 7.499 180)
			(size 0.5 0.5)
			(layers "F.Cu" "F.Mask" "F.Paste")
			(net 194 "/DDR5 SODIMM/B.CB2")
			(pinfunction "IO_L12P_T1_MRCC_34")
			(pintype "bidirectional")
			(die_length 19.161)
		)
		(pad "AA4" smd circle
			(at -9.5 7.499 180)
			(size 0.5 0.5)
			(layers "F.Cu" "F.Mask" "F.Paste")
			(net 258 "/DDR5 SODIMM/B.DQ15")
			(pinfunction "IO_L13P_T2_MRCC_34")
			(pintype "bidirectional")
			(die_length 19.112)
		)
		(pad "AA5" smd circle
			(at -8.5 7.499 180)
			(size 0.5 0.5)
			(layers "F.Cu" "F.Mask" "F.Paste")
			(net 253 "/DDR5 SODIMM/B.DQS1_P")
			(pinfunction "IO_L15P_T2_DQS_34")
			(pintype "bidirectional")
			(die_length 18.268)
		)
		(pad "AA6" smd circle
			(at -7.5 7.499 180)
			(size 0.5 0.5)
			(layers "F.Cu" "F.Mask" "F.Paste")
			(net 1 "GND")
			(pinfunction "GND")
			(pintype "passive")
		)
		(pad "AA7" smd circle
			(at -6.5 7.499 180)
			(size 0.5 0.5)
			(layers "F.Cu" "F.Mask" "F.Paste")
			(net 156 "/DDR5 SODIMM/A.CA12")
			(pinfunction "IO_L8N_T1_33")
			(pintype "bidirectional")
			(die_length 16.325)
		)
		(pad "AA8" smd circle
			(at -5.5 7.499 180)
			(size 0.5 0.5)
			(layers "F.Cu" "F.Mask" "F.Paste")
			(net 153 "/DDR5 SODIMM/A.CA9")
			(pinfunction "IO_L8P_T1_33")
			(pintype "bidirectional")
			(die_length 15.251)
		)
		(pad "AA9" smd circle
			(at -4.5 7.499 180)
			(size 0.5 0.5)
			(layers "F.Cu" "F.Mask" "F.Paste")
			(net 149 "/DDR5 SODIMM/A.CA5")
			(pinfunction "IO_L11P_T1_SRCC_33")
			(pintype "bidirectional")
			(die_length 13.773)
		)
		(pad "AA10" smd circle
			(at -3.5 7.499 180)
			(size 0.5 0.5)
			(layers "F.Cu" "F.Mask" "F.Paste")
			(net 161 "/DDR5 SODIMM/B.CK0_P")
			(pinfunction "IO_L14P_T2_SRCC_33")
			(pintype "bidirectional")
			(die_length 14.881)
		)
		(pad "AA11" smd circle
			(at -2.5 7.499 180)
			(size 0.5 0.5)
			(layers "F.Cu" "F.Mask" "F.Paste")
			(net 206 "+1V1")
			(pinfunction "VCCO_33")
			(pintype "power_in")
		)
		(pad "AA12" smd circle
			(at -1.5 7.499 180)
			(size 0.5 0.5)
			(layers "F.Cu" "F.Mask" "F.Paste")
			(net 120 "/DDR5 SODIMM/A.~{CS0}")
			(pinfunction "IO_L16N_T2_33")
			(pintype "bidirectional")
			(die_length 14.923)
		)
		(pad "AA13" smd circle
			(at -0.5 7.499 180)
			(size 0.5 0.5)
			(layers "F.Cu" "F.Mask" "F.Paste")
			(net 170 "/DDR5 SODIMM/B.CA7")
			(pinfunction "IO_L16P_T2_33")
			(pintype "bidirectional")
			(die_length 16.493)
		)
		(pad "AA14" smd circle
			(at 0.499 7.499 180)
			(size 0.5 0.5)
			(layers "F.Cu" "F.Mask" "F.Paste")
			(net 114 "/DDR5 SODIMM/A.CB0")
			(pinfunction "IO_L7P_T1_32")
			(pintype "bidirectional")
			(die_length 11.726)
		)
		(pad "AA15" smd circle
			(at 1.499 7.499 180)
			(size 0.5 0.5)
			(layers "F.Cu" "F.Mask" "F.Paste")
			(net 94 "/DDR5 SODIMM/A.~{DM2}")
			(pinfunction "IO_L7N_T1_32")
			(pintype "bidirectional")
			(die_length 11.467)
		)
		(pad "AA16" smd circle
			(at 2.499 7.499 180)
			(size 0.5 0.5)
			(layers "F.Cu" "F.Mask" "F.Paste")
			(net 1 "GND")
			(pinfunction "GND")
			(pintype "passive")
		)
		(pad "AA17" smd circle
			(at 3.499 7.499 180)
			(size 0.5 0.5)
			(layers "F.Cu" "F.Mask" "F.Paste")
			(net 91 "/DDR5 SODIMM/A.DQ17")
			(pinfunction "IO_L11P_T1_SRCC_32")
			(pintype "bidirectional")
			(die_length 14.572)
		)
		(pad "AA18" smd circle
			(at 4.499 7.499 180)
			(size 0.5 0.5)
			(layers "F.Cu" "F.Mask" "F.Paste")
			(net 89 "/DDR5 SODIMM/A.DQ16")
			(pinfunction "IO_L11N_T1_SRCC_32")
			(pintype "bidirectional")
			(die_length 14.747)
		)
		(pad "AA19" smd circle
			(at 5.499 7.499 180)
			(size 0.5 0.5)
			(layers "F.Cu" "F.Mask" "F.Paste")
			(net 74 "/DDR5 SODIMM/A.DQ8")
			(pinfunction "IO_L16P_T2_32")
			(pintype "bidirectional")
			(die_length 19.389)
		)
		(pad "AA20" smd circle
			(at 6.499 7.499 180)
			(size 0.5 0.5)
			(layers "F.Cu" "F.Mask" "F.Paste")
			(net 80 "/DDR5 SODIMM/A.DQ11")
			(pinfunction "IO_L16N_T2_32")
			(pintype "bidirectional")
			(die_length 21.053)
		)
		(pad "AA21" smd circle
			(at 7.499 7.499 180)
			(size 0.5 0.5)
			(layers "F.Cu" "F.Mask" "F.Paste")
			(net 200 "+3V3")
			(pinfunction "VCCO_12")
			(pintype "power_in")
		)
		(pad "AA22" smd circle
			(at 8.499 7.499 180)
			(size 0.5 0.5)
			(layers "F.Cu" "F.Mask" "F.Paste")
			(net 681 "/Ethernet/ETH.~{RESET}")
			(pinfunction "IO_L13N_T2_MRCC_12")
			(pintype "bidirectional")
			(die_length 11.687)
		)
		(pad "AA23" smd circle
			(at 9.499 7.499 180)
			(size 0.5 0.5)
			(layers "F.Cu" "F.Mask" "F.Paste")
			(net 679 "/Ethernet/ETH.REF_CLK")
			(pinfunction "IO_L11P_T1_SRCC_12")
			(pintype "bidirectional")
			(die_length 13.863)
		)
		(pad "AA24" smd circle
			(at 10.499 7.499 180)
			(size 0.5 0.5)
			(layers "F.Cu" "F.Mask" "F.Paste")
			(net 704 "/Ethernet/ETH.TXC")
			(pinfunction "IO_L12N_T1_MRCC_12")
			(pintype "bidirectional")
			(die_length 13.119)
		)
		(pad "AA25" smd circle
			(at 11.499 7.499 180)
			(size 0.5 0.5)
			(layers "F.Cu" "F.Mask" "F.Paste")
			(net 705 "/Ethernet/ETH.MDC")
			(pinfunction "IO_L7P_T1_12")
			(pintype "bidirectional")
			(die_length 15.139)
		)
		(pad "AA26" smd circle
			(at 12.499 7.499 180)
			(size 0.5 0.5)
			(layers "F.Cu" "F.Mask" "F.Paste")
			(net 1 "GND")
			(pinfunction "GND")
			(pintype "passive")
		)
		(pad "AB1" smd circle
			(at -12.5 8.499 180)
			(size 0.5 0.5)
			(layers "F.Cu" "F.Mask" "F.Paste")
			(net 266 "/DDR5 SODIMM/B.DQS2_P")
			(pinfunction "IO_L9P_T1_DQS_34")
			(pintype "bidirectional")
			(die_length 21.468)
		)
		(pad "AB2" smd circle
			(at -11.5 8.499 180)
			(size 0.5 0.5)
			(layers "F.Cu" "F.Mask" "F.Paste")
			(net 259 "/DDR5 SODIMM/B.DQ16")
			(pinfunction "IO_L11P_T1_SRCC_34")
			(pintype "bidirectional")
			(die_length 21.477)
		)
		(pad "AB3" smd circle
			(at -10.5 8.499 180)
			(size 0.5 0.5)
			(layers "F.Cu" "F.Mask" "F.Paste")
			(net 1 "GND")
			(pinfunction "GND")
			(pintype "passive")
		)
		(pad "AB4" smd circle
			(at -9.5 8.499 180)
			(size 0.5 0.5)
			(layers "F.Cu" "F.Mask" "F.Paste")
			(net 257 "/DDR5 SODIMM/B.DQ14")
			(pinfunction "IO_L13N_T2_MRCC_34")
			(pintype "bidirectional")
			(die_length 19.11)
		)
		(pad "AB5" smd circle
			(at -8.5 8.499 180)
			(size 0.5 0.5)
			(layers "F.Cu" "F.Mask" "F.Paste")
			(net 250 "/DDR5 SODIMM/B.DQS1_N")
			(pinfunction "IO_L15N_T2_DQS_34")
			(pintype "bidirectional")
			(die_length 17.889)
		)
		(pad "AB6" smd circle
			(at -7.5 8.499 180)
			(size 0.5 0.5)
			(layers "F.Cu" "F.Mask" "F.Paste")
			(net 228 "/DDR5 SODIMM/B.DQ8")
			(pinfunction "IO_L16P_T2_34")
			(pintype "bidirectional")
			(die_length 18.462)
		)
		(pad "AB7" smd circle
			(at -6.5 8.499 180)
			(size 0.5 0.5)
			(layers "F.Cu" "F.Mask" "F.Paste")
			(net 155 "/DDR5 SODIMM/A.CA11")
			(pinfunction "IO_L10P_T1_33")
			(pintype "bidirectional")
			(die_length 14.818)
		)
		(pad "AB8" smd circle
			(at -5.5 8.499 180)
			(size 0.5 0.5)
			(layers "F.Cu" "F.Mask" "F.Paste")
			(net 206 "+1V1")
			(pinfunction "VCCO_33")
			(pintype "passive")
		)
		(pad "AB9" smd circle
			(at -4.5 8.499 180)
			(size 0.5 0.5)
			(layers "F.Cu" "F.Mask" "F.Paste")
			(net 150 "/DDR5 SODIMM/A.CA6")
			(pinfunction "IO_L11N_T1_SRCC_33")
			(pintype "bidirectional")
			(die_length 13.992)
		)
		(pad "AB10" smd circle
			(at -3.5 8.499 180)
			(size 0.5 0.5)
			(layers "F.Cu" "F.Mask" "F.Paste")
			(net 163 "/DDR5 SODIMM/B.CK0_N")
			(pinfunction "IO_L14N_T2_SRCC_33")
			(pintype "bidirectional")
			(die_length 15.337)
		)
		(pad "AB11" smd circle
			(at -2.5 8.499 180)
			(size 0.5 0.5)
			(layers "F.Cu" "F.Mask" "F.Paste")
			(net 157 "/DDR5 SODIMM/A.CK0_P")
			(pinfunction "IO_L13P_T2_MRCC_33")
			(pintype "bidirectional")
			(die_length 18.178)
		)
		(pad "AB12" smd circle
			(at -1.5 8.499 180)
			(size 0.5 0.5)
			(layers "F.Cu" "F.Mask" "F.Paste")
			(net 138 "/DDR5 SODIMM/A.~{CS1}")
			(pinfunction "IO_L15P_T2_DQS_33")
			(pintype "bidirectional")
			(die_length 19.224)
		)
		(pad "AB13" smd circle
			(at -0.5 8.499 180)
			(size 0.5 0.5)
			(layers "F.Cu" "F.Mask" "F.Paste")
			(net 1 "GND")
			(pinfunction "GND")
			(pintype "passive")
		)
		(pad "AB14" smd circle
			(at 0.499 8.499 180)
			(size 0.5 0.5)
			(layers "F.Cu" "F.Mask" "F.Paste")
			(net 99 "/DDR5 SODIMM/A.DQ22")
			(pinfunction "IO_L10P_T1_32")
			(pintype "bidirectional")
			(die_length 14.652)
		)
		(pad "AB15" smd circle
			(at 1.499 8.499 180)
			(size 0.5 0.5)
			(layers "F.Cu" "F.Mask" "F.Paste")
			(net 100 "/DDR5 SODIMM/A.DQ23")
			(pinfunction "IO_L10N_T1_32")
			(pintype "bidirectional")
			(die_length 16.86)
		)
		(pad "AB16" smd circle
			(at 2.499 8.499 180)
			(size 0.5 0.5)
			(layers "F.Cu" "F.Mask" "F.Paste")
			(net 92 "/DDR5 SODIMM/A.DQ18")
			(pinfunction "IO_L12P_T1_MRCC_32")
			(pintype "bidirectional")
			(die_length 17.498)
		)
		(pad "AB17" smd circle
			(at 3.499 8.499 180)
			(size 0.5 0.5)
			(layers "F.Cu" "F.Mask" "F.Paste")
			(net 77 "/DDR5 SODIMM/A.DQ9")
			(pinfunction "IO_L14P_T2_SRCC_32")
			(pintype "bidirectional")
			(die_length 16.709)
		)
		(pad "AB18" smd circle
			(at 4.499 8.499 180)
			(size 0.5 0.5)
			(layers "F.Cu" "F.Mask" "F.Paste")
			(net 206 "+1V1")
			(pinfunction "VCCO_32")
			(pintype "power_in")
		)
		(pad "AB19" smd circle
			(at 5.499 8.499 180)
			(size 0.5 0.5)
			(layers "F.Cu" "F.Mask" "F.Paste")
			(net 79 "/DDR5 SODIMM/A.DQ10")
			(pinfunction "IO_L18P_T2_32")
			(pintype "bidirectional")
			(die_length 21.632)
		)
		(pad "AB20" smd circle
			(at 6.499 8.499 180)
			(size 0.5 0.5)
			(layers "F.Cu" "F.Mask" "F.Paste")
			(net 115 "/DDR5 SODIMM/A.CB1")
			(pinfunction "IO_L18N_T2_32")
			(pintype "bidirectional")
			(die_length 20.965)
		)
		(pad "AB21" smd circle
			(at 7.499 8.499 180)
			(size 0.5 0.5)
			(layers "F.Cu" "F.Mask" "F.Paste")
			(net 273 "RFU_1")
			(pinfunction "IO_L18P_T2_12")
			(pintype "bidirectional")
			(die_length 11.49)
		)
		(pad "AB22" smd circle
			(at 8.499 8.499 180)
			(size 0.5 0.5)
			(layers "F.Cu" "F.Mask" "F.Paste")
			(net 274 "RFU_3")
			(pinfunction "IO_L17P_T2_12")
			(pintype "bidirectional")
			(die_length 12.162)
		)
		(pad "AB23" smd circle
			(at 9.499 8.499 180)
			(size 0.5 0.5)
			(layers "F.Cu" "F.Mask" "F.Paste")
			(net 1 "GND")
			(pinfunction "GND")
			(pintype "passive")
		)
		(pad "AB24" smd circle
			(at 10.499 8.499 180)
			(size 0.5 0.5)
			(layers "F.Cu" "F.Mask" "F.Paste")
			(net 398 "unconnected-(U4A-IO_L11N_T1_SRCC_12-PadAB24)")
			(pinfunction "IO_L11N_T1_SRCC_12")
			(pintype "bidirectional+no_connect")
			(die_length 14.571)
		)
		(pad "AB25" smd circle
			(at 11.499 8.499 180)
			(size 0.5 0.5)
			(layers "F.Cu" "F.Mask" "F.Paste")
			(net 399 "unconnected-(U4A-IO_L7N_T1_12-PadAB25)")
			(pinfunction "IO_L7N_T1_12")
			(pintype "bidirectional+no_connect")
			(die_length 16.017)
		)
		(pad "AB26" smd circle
			(at 12.499 8.499 180)
			(size 0.5 0.5)
			(layers "F.Cu" "F.Mask" "F.Paste")
			(net 680 "/Ethernet/ETH.MDIO")
			(pinfunction "IO_L9P_T1_DQS_12")
			(pintype "bidirectional")
			(die_length 16.487)
		)
		(pad "AC1" smd circle
			(at -12.5 9.499 180)
			(size 0.5 0.5)
			(layers "F.Cu" "F.Mask" "F.Paste")
			(net 265 "/DDR5 SODIMM/B.DQS2_N")
			(pinfunction "IO_L9N_T1_DQS_34")
			(pintype "bidirectional")
			(die_length 21.84)
		)
		(pad "AC2" smd circle
			(at -11.5 9.499 180)
			(size 0.5 0.5)
			(layers "F.Cu" "F.Mask" "F.Paste")
			(net 262 "/DDR5 SODIMM/B.DQ19")
			(pinfunction "IO_L11N_T1_SRCC_34")
			(pintype "bidirectional")
			(die_length 21.727)
		)
		(pad "AC3" smd circle
			(at -10.5 9.499 180)
			(size 0.5 0.5)
			(layers "F.Cu" "F.Mask" "F.Paste")
			(net 255 "/DDR5 SODIMM/B.DQ12")
			(pinfunction "IO_L14N_T2_SRCC_34")
			(pintype "bidirectional")
			(die_length 20.603)
		)
		(pad "AC4" smd circle
			(at -9.5 9.499 180)
			(size 0.5 0.5)
			(layers "F.Cu" "F.Mask" "F.Paste")
			(net 256 "/DDR5 SODIMM/B.DQ13")
			(pinfunction "IO_L14P_T2_SRCC_34")
			(pintype "bidirectional")
			(die_length 20.232)
		)
		(pad "AC5" smd circle
			(at -8.5 9.499 180)
			(size 0.5 0.5)
			(layers "F.Cu" "F.Mask" "F.Paste")
			(net 206 "+1V1")
			(pinfunction "VCCO_34")
			(pintype "passive")
		)
		(pad "AC6" smd circle
			(at -7.5 9.499 180)
			(size 0.5 0.5)
			(layers "F.Cu" "F.Mask" "F.Paste")
			(net 247 "/DDR5 SODIMM/B.DQ11")
			(pinfunction "IO_L16N_T2_34")
			(pintype "bidirectional")
			(die_length 19.298)
		)
		(pad "AC7" smd circle
			(at -6.5 9.499 180)
			(size 0.5 0.5)
			(layers "F.Cu" "F.Mask" "F.Paste")
			(net 154 "/DDR5 SODIMM/A.CA10")
			(pinfunction "IO_L10N_T1_33")
			(pintype "bidirectional")
			(die_length 16.292)
		)
		(pad "AC8" smd circle
			(at -5.5 9.499 180)
			(size 0.5 0.5)
			(layers "F.Cu" "F.Mask" "F.Paste")
			(net 152 "/DDR5 SODIMM/A.CA8")
			(pinfunction "IO_L9P_T1_DQS_33")
			(pintype "bidirectional")
			(die_length 16.788)
		)
		(pad "AC9" smd circle
			(at -4.5 9.499 180)
			(size 0.5 0.5)
			(layers "F.Cu" "F.Mask" "F.Paste")
			(net 148 "/DDR5 SODIMM/A.CA4")
			(pinfunction "IO_L12P_T1_MRCC_33")
			(pintype "bidirectional")
			(die_length 16.857)
		)
		(pad "AC10" smd circle
			(at -3.5 9.499 180)
			(size 0.5 0.5)
			(layers "F.Cu" "F.Mask" "F.Paste")
			(net 1 "GND")
			(pinfunction "GND")
			(pintype "passive")
		)
		(pad "AC11" smd circle
			(at -2.5 9.499 180)
			(size 0.5 0.5)
			(layers "F.Cu" "F.Mask" "F.Paste")
			(net 159 "/DDR5 SODIMM/A.CK0_N")
			(pinfunction "IO_L13N_T2_MRCC_33")
			(pintype "bidirectional")
			(die_length 17.813)
		)
		(pad "AC12" smd circle
			(at -1.5 9.499 180)
			(size 0.5 0.5)
			(layers "F.Cu" "F.Mask" "F.Paste")
			(net 136 "/DDR5 SODIMM/A.CA1")
			(pinfunction "IO_L15N_T2_DQS_33")
			(pintype "bidirectional")
			(die_length 18.956)
		)
		(pad "AC13" smd circle
			(at -0.5 9.499 180)
			(size 0.5 0.5)
			(layers "F.Cu" "F.Mask" "F.Paste")
			(net 147 "/DDR5 SODIMM/A.CA3")
			(pinfunction "IO_L17P_T2_33")
			(pintype "bidirectional")
			(die_length 21.425)
		)
		(pad "AC14" smd circle
			(at 0.499 9.499 180)
			(size 0.5 0.5)
			(layers "F.Cu" "F.Mask" "F.Paste")
			(net 98 "/DDR5 SODIMM/A.DQ21")
			(pinfunction "IO_L8P_T1_32")
			(pintype "bidirectional")
			(die_length 15.875)
		)
		(pad "AC15" smd circle
			(at 1.499 9.499 180)
			(size 0.5 0.5)
			(layers "F.Cu" "F.Mask" "F.Paste")
			(net 206 "+1V1")
			(pinfunction "VCCO_32")
			(pintype "passive")
		)
		(pad "AC16" smd circle
			(at 2.499 9.499 180)
			(size 0.5 0.5)
			(layers "F.Cu" "F.Mask" "F.Paste")
			(net 93 "/DDR5 SODIMM/A.DQ19")
			(pinfunction "IO_L12N_T1_MRCC_32")
			(pintype "bidirectional")
			(die_length 17.396)
		)
		(pad "AC17" smd circle
			(at 3.499 9.499 180)
			(size 0.5 0.5)
			(layers "F.Cu" "F.Mask" "F.Paste")
			(net 87 "/DDR5 SODIMM/A.DQ14")
			(pinfunction "IO_L14N_T2_SRCC_32")
			(pintype "bidirectional")
			(die_length 17.38)
		)
		(pad "AC18" smd circle
			(at 4.499 9.499 180)
			(size 0.5 0.5)
			(layers "F.Cu" "F.Mask" "F.Paste")
			(net 84 "/DDR5 SODIMM/A.DQ12")
			(pinfunction "IO_L13P_T2_MRCC_32")
			(pintype "bidirectional")
			(die_length 20.008)
		)
		(pad "AC19" smd circle
			(at 5.499 9.499 180)
			(size 0.5 0.5)
			(layers "F.Cu" "F.Mask" "F.Paste")
			(net 83 "/DDR5 SODIMM/A.~{DM1}")
			(pinfunction "IO_L17P_T2_32")
			(pintype "bidirectional")
			(die_length 22.343)
		)
		(pad "AC20" smd circle
			(at 6.499 9.499 180)
			(size 0.5 0.5)
			(layers "F.Cu" "F.Mask" "F.Paste")
			(net 1 "GND")
			(pinfunction "GND")
			(pintype "passive")
		)
		(pad "AC21" smd circle
			(at 7.499 9.499 180)
			(size 0.5 0.5)
			(layers "F.Cu" "F.Mask" "F.Paste")
			(net 637 "/DDR5 SODIMM/Control.PWR_EN")
			(pinfunction "IO_L18N_T2_12")
			(pintype "bidirectional")
			(die_length 11.327)
		)
		(pad "AC22" smd circle
			(at 8.499 9.499 180)
			(size 0.5 0.5)
			(layers "F.Cu" "F.Mask" "F.Paste")
			(net 101 "RFU_2")
			(pinfunction "IO_L17N_T2_12")
			(pintype "bidirectional")
			(die_length 12.08)
		)
		(pad "AC23" smd circle
			(at 9.499 9.499 180)
			(size 0.5 0.5)
			(layers "F.Cu" "F.Mask" "F.Paste")
			(net 400 "unconnected-(U4A-IO_L14P_T2_SRCC_12-PadAC23)")
			(pinfunction "IO_L14P_T2_SRCC_12")
			(pintype "bidirectional+no_connect")
			(die_length 13.919)
		)
		(pad "AC24" smd circle
			(at 10.499 9.499 180)
			(size 0.5 0.5)
			(layers "F.Cu" "F.Mask" "F.Paste")
			(net 623 "/FPGA bank 12/HyperRAM.~{RESET}")
			(pinfunction "IO_L14N_T2_SRCC_12")
			(pintype "bidirectional")
			(die_length 13.859)
		)
		(pad "AC25" smd circle
			(at 11.499 9.499 180)
			(size 0.5 0.5)
			(layers "F.Cu" "F.Mask" "F.Paste")
			(net 200 "+3V3")
			(pinfunction "VCCO_12")
			(pintype "passive")
		)
		(pad "AC26" smd circle
			(at 12.499 9.499 180)
			(size 0.5 0.5)
			(layers "F.Cu" "F.Mask" "F.Paste")
			(net 624 "/FPGA bank 12/HyperRAM.~{CS}")
			(pinfunction "IO_L9N_T1_DQS_12")
			(pintype "bidirectional")
			(die_length 17.028)
		)
		(pad "AD1" smd circle
			(at -12.5 10.499 180)
			(size 0.5 0.5)
			(layers "F.Cu" "F.Mask" "F.Paste")
			(net 219 "/DDR5 SODIMM/B.DQ7")
			(pinfunction "IO_L20P_T3_34")
			(pintype "bidirectional")
			(die_length 23.961)
		)
		(pad "AD2" smd circle
			(at -11.5 10.499 180)
			(size 0.5 0.5)
			(layers "F.Cu" "F.Mask" "F.Paste")
			(net 206 "+1V1")
			(pinfunction "VCCO_34")
			(pintype "passive")
		)
		(pad "AD3" smd circle
			(at -10.5 10.499 180)
			(size 0.5 0.5)
			(layers "F.Cu" "F.Mask" "F.Paste")
			(net 10 "/FPGA banks HP/VREF")
			(pinfunction "IO_L19N_T3_VREF_34")
			(pintype "bidirectional")
			(die_length 21.156)
		)
		(pad "AD4" smd circle
			(at -9.5 10.499 180)
			(size 0.5 0.5)
			(layers "F.Cu" "F.Mask" "F.Paste")
			(net 196 "/DDR5 SODIMM/B.DQ1")
			(pinfunction "IO_L19P_T3_34")
			(pintype "bidirectional")
			(die_length 21.197)
		)
		(pad "AD5" smd circle
			(at -8.5 10.499 180)
			(size 0.5 0.5)
			(layers "F.Cu" "F.Mask" "F.Paste")
			(net 254 "/DDR5 SODIMM/B.~{DM1}")
			(pinfunction "IO_L18N_T2_34")
			(pintype "bidirectional")
			(die_length 19.989)
		)
		(pad "AD6" smd circle
			(at -7.5 10.499 180)
			(size 0.5 0.5)
			(layers "F.Cu" "F.Mask" "F.Paste")
			(net 189 "/DDR5 SODIMM/B.CB0")
			(pinfunction "IO_L18P_T2_34")
			(pintype "bidirectional")
			(die_length 20.498)
		)
		(pad "AD7" smd circle
			(at -6.5 10.499 180)
			(size 0.5 0.5)
			(layers "F.Cu" "F.Mask" "F.Paste")
			(net 1 "GND")
			(pinfunction "GND")
			(pintype "passive")
		)
		(pad "AD8" smd circle
			(at -5.5 10.499 180)
			(size 0.5 0.5)
			(layers "F.Cu" "F.Mask" "F.Paste")
			(net 750 "unconnected-(U4G-IO_L9N_T1_DQS_33-PadAD8)")
			(pinfunction "IO_L9N_T1_DQS_33")
			(pintype "bidirectional+no_connect")
			(die_length 16.577)
		)
		(pad "AD9" smd circle
			(at -4.5 10.499 180)
			(size 0.5 0.5)
			(layers "F.Cu" "F.Mask" "F.Paste")
			(net 151 "/DDR5 SODIMM/A.CA7")
			(pinfunction "IO_L12N_T1_MRCC_33")
			(pintype "bidirectional")
			(die_length 17.579)
		)
		(pad "AD10" smd circle
			(at -3.5 10.499 180)
			(size 0.5 0.5)
			(layers "F.Cu" "F.Mask" "F.Paste")
			(net 139 "/DDR5 SODIMM/A.CA2")
			(pinfunction "IO_L20P_T3_33")
			(pintype "bidirectional")
			(die_length 16.019)
		)
		(pad "AD11" smd circle
			(at -2.5 10.499 180)
			(size 0.5 0.5)
			(layers "F.Cu" "F.Mask" "F.Paste")
			(net 121 "/DDR5 SODIMM/A.CA0")
			(pinfunction "IO_L19P_T3_33")
			(pintype "bidirectional")
			(die_length 18.739)
		)
		(pad "AD12" smd circle
			(at -1.5 10.499 180)
			(size 0.5 0.5)
			(layers "F.Cu" "F.Mask" "F.Paste")
			(net 206 "+1V1")
			(pinfunction "VCCO_33")
			(pintype "passive")
		)
		(pad "AD13" smd circle
			(at -0.5 10.499 180)
			(size 0.5 0.5)
			(layers "F.Cu" "F.Mask" "F.Paste")
			(net 122 "/DDR5 SODIMM/Control.~{ALERT}")
			(pinfunction "IO_L17N_T2_33")
			(pintype "bidirectional")
			(die_length 19.307)
		)
		(pad "AD14" smd circle
			(at 0.499 10.499 180)
			(size 0.5 0.5)
			(layers "F.Cu" "F.Mask" "F.Paste")
			(net 97 "/DDR5 SODIMM/A.DQ20")
			(pinfunction "IO_L8N_T1_32")
			(pintype "bidirectional")
			(die_length 17.8)
		)
		(pad "AD15" smd circle
			(at 1.499 10.499 180)
			(size 0.5 0.5)
			(layers "F.Cu" "F.Mask" "F.Paste")
			(net 110 "/DDR5 SODIMM/A.DQ28")
			(pinfunction "IO_L4P_T0_32")
			(pintype "bidirectional")
			(die_length 19.249)
		)
		(pad "AD16" smd circle
			(at 2.499 10.499 180)
			(size 0.5 0.5)
			(layers "F.Cu" "F.Mask" "F.Paste")
			(net 103 "/DDR5 SODIMM/A.DQ25")
			(pinfunction "IO_L6P_T0_32")
			(pintype "bidirectional")
			(die_length 19.246)
		)
		(pad "AD17" smd circle
			(at 3.499 10.499 180)
			(size 0.5 0.5)
			(layers "F.Cu" "F.Mask" "F.Paste")
			(net 1 "GND")
			(pinfunction "GND")
			(pintype "passive")
		)
		(pad "AD18" smd circle
			(at 4.499 10.499 180)
			(size 0.5 0.5)
			(layers "F.Cu" "F.Mask" "F.Paste")
			(net 88 "/DDR5 SODIMM/A.DQ15")
			(pinfunction "IO_L13N_T2_MRCC_32")
			(pintype "bidirectional")
			(die_length 20.423)
		)
		(pad "AD19" smd circle
			(at 5.499 10.499 180)
			(size 0.5 0.5)
			(layers "F.Cu" "F.Mask" "F.Paste")
			(net 85 "/DDR5 SODIMM/A.DQ13")
			(pinfunction "IO_L17N_T2_32")
			(pintype "bidirectional")
			(die_length 20.752)
		)
		(pad "AD20" smd circle
			(at 6.499 10.499 180)
			(size 0.5 0.5)
			(layers "F.Cu" "F.Mask" "F.Paste")
			(net 82 "/DDR5 SODIMM/A.DQS1_P")
			(pinfunction "IO_L15P_T2_DQS_32")
			(pintype "bidirectional")
			(die_length 22.214)
		)
		(pad "AD21" smd circle
			(at 7.499 10.499 180)
			(size 0.5 0.5)
			(layers "F.Cu" "F.Mask" "F.Paste")
			(net 636 "/DDR5 SODIMM/Control.PWR_GOOD")
			(pinfunction "IO_L19P_T3_12")
			(pintype "bidirectional")
			(die_length 13.92)
		)
		(pad "AD22" smd circle
			(at 8.499 10.499 180)
			(size 0.5 0.5)
			(layers "F.Cu" "F.Mask" "F.Paste")
			(net 200 "+3V3")
			(pinfunction "VCCO_12")
			(pintype "passive")
		)
		(pad "AD23" smd circle
			(at 9.499 10.499 180)
			(size 0.5 0.5)
			(layers "F.Cu" "F.Mask" "F.Paste")
			(net 695 "/FPGA bank 12/HyperRAM.RWDS")
			(pinfunction "IO_L16P_T2_12")
			(pintype "bidirectional")
			(die_length 14.54)
		)
		(pad "AD24" smd circle
			(at 10.499 10.499 180)
			(size 0.5 0.5)
			(layers "F.Cu" "F.Mask" "F.Paste")
			(net 701 "/FPGA bank 12/HyperRAM.DQ7")
			(pinfunction "IO_L16N_T2_12")
			(pintype "bidirectional")
			(die_length 14.673)
		)
		(pad "AD25" smd circle
			(at 11.499 10.499 180)
			(size 0.5 0.5)
			(layers "F.Cu" "F.Mask" "F.Paste")
			(net 697 "/FPGA bank 12/HyperRAM.DQ1")
			(pinfunction "IO_L23P_T3_12")
			(pintype "bidirectional")
			(die_length 16.272)
		)
		(pad "AD26" smd circle
			(at 12.499 10.499 180)
			(size 0.5 0.5)
			(layers "F.Cu" "F.Mask" "F.Paste")
			(net 694 "/FPGA bank 12/HyperRAM.CK_P")
			(pinfunction "IO_L21P_T3_DQS_12")
			(pintype "bidirectional")
			(die_length 17.707)
		)
		(pad "AE1" smd circle
			(at -12.5 11.499 180)
			(size 0.5 0.5)
			(layers "F.Cu" "F.Mask" "F.Paste")
			(net 213 "/DDR5 SODIMM/B.DQ6")
			(pinfunction "IO_L20N_T3_34")
			(pintype "bidirectional")
			(die_length 23.86)
		)
		(pad "AE2" smd circle
			(at -11.5 11.499 180)
			(size 0.5 0.5)
			(layers "F.Cu" "F.Mask" "F.Paste")
			(net 212 "/DDR5 SODIMM/B.DQ5")
			(pinfunction "IO_L22N_T3_34")
			(pintype "bidirectional")
			(die_length 25.162)
		)
		(pad "AE3" smd circle
			(at -10.5 11.499 180)
			(size 0.5 0.5)
			(layers "F.Cu" "F.Mask" "F.Paste")
			(net 202 "/DDR5 SODIMM/B.~{DM0}")
			(pinfunction "IO_L22P_T3_34")
			(pintype "bidirectional")
			(die_length 24.57)
		)
		(pad "AE4" smd circle
			(at -9.5 11.499 180)
			(size 0.5 0.5)
			(layers "F.Cu" "F.Mask" "F.Paste")
			(net 1 "GND")
			(pinfunction "GND")
			(pintype "passive")
		)
		(pad "AE5" smd circle
			(at -8.5 11.499 180)
			(size 0.5 0.5)
			(layers "F.Cu" "F.Mask" "F.Paste")
			(net 195 "/DDR5 SODIMM/B.DQ0")
			(pinfunction "IO_L23N_T3_34")
			(pintype "bidirectional")
			(die_length 20.276)
		)
		(pad "AE6" smd circle
			(at -7.5 11.499 180)
			(size 0.5 0.5)
			(layers "F.Cu" "F.Mask" "F.Paste")
			(net 198 "/DDR5 SODIMM/B.DQ3")
			(pinfunction "IO_L23P_T3_34")
			(pintype "bidirectional")
			(die_length 20.819)
		)
		(pad "AE7" smd circle
			(at -6.5 11.499 180)
			(size 0.5 0.5)
			(layers "F.Cu" "F.Mask" "F.Paste")
			(net 191 "/DDR5 SODIMM/B.DQS4_P")
			(pinfunction "IO_L7P_T1_33")
			(pintype "bidirectional")
			(die_length 17.815)
		)
		(pad "AE8" smd circle
			(at -5.5 11.499 180)
			(size 0.5 0.5)
			(layers "F.Cu" "F.Mask" "F.Paste")
			(net 118 "/DDR5 SODIMM/A.DQS4_P")
			(pinfunction "IO_L22P_T3_33")
			(pintype "bidirectional")
			(die_length 19.534)
		)
		(pad "AE9" smd circle
			(at -4.5 11.499 180)
			(size 0.5 0.5)
			(layers "F.Cu" "F.Mask" "F.Paste")
			(net 206 "+1V1")
			(pinfunction "VCCO_33")
			(pintype "passive")
		)
		(pad "AE10" smd circle
			(at -3.5 11.499 180)
			(size 0.5 0.5)
			(layers "F.Cu" "F.Mask" "F.Paste")
			(net 751 "unconnected-(U4G-IO_L20N_T3_33-PadAE10)")
			(pinfunction "IO_L20N_T3_33")
			(pintype "bidirectional+no_connect")
			(die_length 16.714)
		)
		(pad "AE11" smd circle
			(at -2.5 11.499 180)
			(size 0.5 0.5)
			(layers "F.Cu" "F.Mask" "F.Paste")
			(net 10 "/FPGA banks HP/VREF")
			(pinfunction "IO_L19N_T3_VREF_33")
			(pintype "bidirectional")
			(die_length 17.525)
		)
		(pad "AE12" smd circle
			(at -1.5 11.499 180)
			(size 0.5 0.5)
			(layers "F.Cu" "F.Mask" "F.Paste")
			(net 158 "/DDR5 SODIMM/A.CK1_P")
			(pinfunction "IO_L21P_T3_DQS_33")
			(pintype "bidirectional")
			(die_length 19.187)
		)
		(pad "AE13" smd circle
			(at -0.5 11.499 180)
			(size 0.5 0.5)
			(layers "F.Cu" "F.Mask" "F.Paste")
			(net 162 "/DDR5 SODIMM/B.CK1_P")
			(pinfunction "IO_L23P_T3_33")
			(pintype "bidirectional")
			(die_length 20.167)
		)
		(pad "AE14" smd circle
			(at 0.499 11.499 180)
			(size 0.5 0.5)
			(layers "F.Cu" "F.Mask" "F.Paste")
			(net 1 "GND")
			(pinfunction "GND")
			(pintype "passive")
		)
		(pad "AE15" smd circle
			(at 1.499 11.499 180)
			(size 0.5 0.5)
			(layers "F.Cu" "F.Mask" "F.Paste")
			(net 111 "/DDR5 SODIMM/A.DQ29")
			(pinfunction "IO_L4N_T0_32")
			(pintype "bidirectional")
			(die_length 20.349)
		)
		(pad "AE16" smd circle
			(at 2.499 11.499 180)
			(size 0.5 0.5)
			(layers "F.Cu" "F.Mask" "F.Paste")
			(net 10 "/FPGA banks HP/VREF")
			(pinfunction "IO_L6N_T0_VREF_32")
			(pintype "bidirectional")
			(die_length 18.914)
		)
		(pad "AE17" smd circle
			(at 3.499 11.499 180)
			(size 0.5 0.5)
			(layers "F.Cu" "F.Mask" "F.Paste")
			(net 105 "/DDR5 SODIMM/A.DQ27")
			(pinfunction "IO_L1P_T0_32")
			(pintype "bidirectional")
			(die_length 25.66)
		)
		(pad "AE18" smd circle
			(at 4.499 11.499 180)
			(size 0.5 0.5)
			(layers "F.Cu" "F.Mask" "F.Paste")
			(net 108 "/DDR5 SODIMM/A.DQS3_P")
			(pinfunction "IO_L3P_T0_DQS_32")
			(pintype "bidirectional")
			(die_length 23.868)
		)
		(pad "AE19" smd circle
			(at 5.499 11.499 180)
			(size 0.5 0.5)
			(layers "F.Cu" "F.Mask" "F.Paste")
			(net 206 "+1V1")
			(pinfunction "VCCO_32")
			(pintype "passive")
		)
		(pad "AE20" smd circle
			(at 6.499 11.499 180)
			(size 0.5 0.5)
			(layers "F.Cu" "F.Mask" "F.Paste")
			(net 81 "/DDR5 SODIMM/A.DQS1_N")
			(pinfunction "IO_L15N_T2_DQS_32")
			(pintype "bidirectional")
			(die_length 21.92)
		)
		(pad "AE21" smd circle
			(at 7.499 11.499 180)
			(size 0.5 0.5)
			(layers "F.Cu" "F.Mask" "F.Paste")
			(net 249 "TB_DETECT")
			(pinfunction "IO_L19N_T3_VREF_12")
			(pintype "bidirectional")
			(die_length 13.224)
		)
		(pad "AE22" smd circle
			(at 8.499 11.499 180)
			(size 0.5 0.5)
			(layers "F.Cu" "F.Mask" "F.Paste")
			(net 699 "/FPGA bank 12/HyperRAM.DQ3")
			(pinfunction "IO_L24P_T3_12")
			(pintype "bidirectional")
			(die_length 13.617)
		)
		(pad "AE23" smd circle
			(at 9.499 11.499 180)
			(size 0.5 0.5)
			(layers "F.Cu" "F.Mask" "F.Paste")
			(net 698 "/FPGA bank 12/HyperRAM.DQ0")
			(pinfunction "IO_L22P_T3_12")
			(pintype "bidirectional")
			(die_length 17.11)
		)
		(pad "AE24" smd circle
			(at 10.499 11.499 180)
			(size 0.5 0.5)
			(layers "F.Cu" "F.Mask" "F.Paste")
			(net 1 "GND")
			(pinfunction "GND")
			(pintype "passive")
		)
		(pad "AE25" smd circle
			(at 11.499 11.499 180)
			(size 0.5 0.5)
			(layers "F.Cu" "F.Mask" "F.Paste")
			(net 702 "/FPGA bank 12/HyperRAM.DQ6")
			(pinfunction "IO_L23N_T3_12")
			(pintype "bidirectional")
			(die_length 16.458)
		)
		(pad "AE26" smd circle
			(at 12.499 11.499 180)
			(size 0.5 0.5)
			(layers "F.Cu" "F.Mask" "F.Paste")
			(net 693 "/FPGA bank 12/HyperRAM.CK_N")
			(pinfunction "IO_L21N_T3_DQS_12")
			(pintype "bidirectional")
			(die_length 17.907)
		)
		(pad "AF1" smd circle
			(at -12.5 12.499 180)
			(size 0.5 0.5)
			(layers "F.Cu" "F.Mask" "F.Paste")
			(net 1 "GND")
			(pinfunction "GND")
			(pintype "passive")
		)
		(pad "AF2" smd circle
			(at -11.5 12.499 180)
			(size 0.5 0.5)
			(layers "F.Cu" "F.Mask" "F.Paste")
			(net 205 "/DDR5 SODIMM/B.DQ4")
			(pinfunction "IO_L24N_T3_34")
			(pintype "bidirectional")
			(die_length 24.825)
		)
		(pad "AF3" smd circle
			(at -10.5 12.499 180)
			(size 0.5 0.5)
			(layers "F.Cu" "F.Mask" "F.Paste")
			(net 197 "/DDR5 SODIMM/B.DQ2")
			(pinfunction "IO_L24P_T3_34")
			(pintype "bidirectional")
			(die_length 23.875)
		)
		(pad "AF4" smd circle
			(at -9.5 12.499 180)
			(size 0.5 0.5)
			(layers "F.Cu" "F.Mask" "F.Paste")
			(net 203 "/DDR5 SODIMM/B.DQS0_N")
			(pinfunction "IO_L21N_T3_DQS_34")
			(pintype "bidirectional")
			(die_length 21.687)
		)
		(pad "AF5" smd circle
			(at -8.5 12.499 180)
			(size 0.5 0.5)
			(layers "F.Cu" "F.Mask" "F.Paste")
			(net 204 "/DDR5 SODIMM/B.DQS0_P")
			(pinfunction "IO_L21P_T3_DQS_34")
			(pintype "bidirectional")
			(die_length 22.107)
		)
		(pad "AF6" smd circle
			(at -7.5 12.499 180)
			(size 0.5 0.5)
			(layers "F.Cu" "F.Mask" "F.Paste")
			(net 206 "+1V1")
			(pinfunction "VCCO_34")
			(pintype "passive")
		)
		(pad "AF7" smd circle
			(at -6.5 12.499 180)
			(size 0.5 0.5)
			(layers "F.Cu" "F.Mask" "F.Paste")
			(net 190 "/DDR5 SODIMM/B.DQS4_N")
			(pinfunction "IO_L7N_T1_33")
			(pintype "bidirectional")
			(die_length 18.816)
		)
		(pad "AF8" smd circle
			(at -5.5 12.499 180)
			(size 0.5 0.5)
			(layers "F.Cu" "F.Mask" "F.Paste")
			(net 117 "/DDR5 SODIMM/A.DQS4_N")
			(pinfunction "IO_L22N_T3_33")
			(pintype "bidirectional")
			(die_length 19.356)
		)
		(pad "AF9" smd circle
			(at -4.5 12.499 180)
			(size 0.5 0.5)
			(layers "F.Cu" "F.Mask" "F.Paste")
			(net 182 "/DDR5 SODIMM/Control.~{RESET}")
			(pinfunction "IO_L24N_T3_33")
			(pintype "bidirectional")
			(die_length 18.041)
		)
		(pad "AF10" smd circle
			(at -3.5 12.499 180)
			(size 0.5 0.5)
			(layers "F.Cu" "F.Mask" "F.Paste")
			(net 184 "/DDR5 SODIMM/B.~{CS1}")
			(pinfunction "IO_L24P_T3_33")
			(pintype "bidirectional")
			(die_length 18.552)
		)
		(pad "AF11" smd circle
			(at -2.5 12.499 180)
			(size 0.5 0.5)
			(layers "F.Cu" "F.Mask" "F.Paste")
			(net 1 "GND")
			(pinfunction "GND")
			(pintype "passive")
		)
		(pad "AF12" smd circle
			(at -1.5 12.499 180)
			(size 0.5 0.5)
			(layers "F.Cu" "F.Mask" "F.Paste")
			(net 160 "/DDR5 SODIMM/A.CK1_N")
			(pinfunction "IO_L21N_T3_DQS_33")
			(pintype "bidirectional")
			(die_length 18.818)
		)
		(pad "AF13" smd circle
			(at -0.5 12.499 180)
			(size 0.5 0.5)
			(layers "F.Cu" "F.Mask" "F.Paste")
			(net 164 "/DDR5 SODIMM/B.CK1_N")
			(pinfunction "IO_L23N_T3_33")
			(pintype "bidirectional")
			(die_length 20.747)
		)
		(pad "AF14" smd circle
			(at 0.499 12.499 180)
			(size 0.5 0.5)
			(layers "F.Cu" "F.Mask" "F.Paste")
			(net 113 "/DDR5 SODIMM/A.DQ31")
			(pinfunction "IO_L2P_T0_32")
			(pintype "bidirectional")
			(die_length 20.408)
		)
		(pad "AF15" smd circle
			(at 1.499 12.499 180)
			(size 0.5 0.5)
			(layers "F.Cu" "F.Mask" "F.Paste")
			(net 112 "/DDR5 SODIMM/A.DQ30")
			(pinfunction "IO_L2N_T0_32")
			(pintype "bidirectional")
			(die_length 21.691)
		)
		(pad "AF16" smd circle
			(at 2.499 12.499 180)
			(size 0.5 0.5)
			(layers "F.Cu" "F.Mask" "F.Paste")
			(net 206 "+1V1")
			(pinfunction "VCCO_32")
			(pintype "passive")
		)
		(pad "AF17" smd circle
			(at 3.499 12.499 180)
			(size 0.5 0.5)
			(layers "F.Cu" "F.Mask" "F.Paste")
			(net 109 "/DDR5 SODIMM/A.~{DM3}")
			(pinfunction "IO_L1N_T0_32")
			(pintype "bidirectional")
			(die_length 25.392)
		)
		(pad "AF18" smd circle
			(at 4.499 12.499 180)
			(size 0.5 0.5)
			(layers "F.Cu" "F.Mask" "F.Paste")
			(net 107 "/DDR5 SODIMM/A.DQS3_N")
			(pinfunction "IO_L3N_T0_DQS_32")
			(pintype "bidirectional")
			(die_length 23.477)
		)
		(pad "AF19" smd circle
			(at 5.499 12.499 180)
			(size 0.5 0.5)
			(layers "F.Cu" "F.Mask" "F.Paste")
			(net 104 "/DDR5 SODIMM/A.DQ26")
			(pinfunction "IO_L5P_T0_32")
			(pintype "bidirectional")
			(die_length 22.609)
		)
		(pad "AF20" smd circle
			(at 6.499 12.499 180)
			(size 0.5 0.5)
			(layers "F.Cu" "F.Mask" "F.Paste")
			(net 102 "/DDR5 SODIMM/A.DQ24")
			(pinfunction "IO_L5N_T0_32")
			(pintype "bidirectional")
			(die_length 22.255)
		)
		(pad "AF21" smd circle
			(at 7.499 12.499 180)
			(size 0.5 0.5)
			(layers "F.Cu" "F.Mask" "F.Paste")
			(net 1 "GND")
			(pinfunction "GND")
			(pintype "passive")
		)
		(pad "AF22" smd circle
			(at 8.499 12.499 180)
			(size 0.5 0.5)
			(layers "F.Cu" "F.Mask" "F.Paste")
			(net 248 "~{DDR_PRESENCE}")
			(pinfunction "IO_L24N_T3_12")
			(pintype "bidirectional")
			(die_length 14.462)
		)
		(pad "AF23" smd circle
			(at 9.499 12.499 180)
			(size 0.5 0.5)
			(layers "F.Cu" "F.Mask" "F.Paste")
			(net 700 "/FPGA bank 12/HyperRAM.DQ4")
			(pinfunction "IO_L22N_T3_12")
			(pintype "bidirectional")
			(die_length 16.26)
		)
		(pad "AF24" smd circle
			(at 10.499 12.499 180)
			(size 0.5 0.5)
			(layers "F.Cu" "F.Mask" "F.Paste")
			(net 696 "/FPGA bank 12/HyperRAM.DQ2")
			(pinfunction "IO_L20P_T3_12")
			(pintype "bidirectional")
			(die_length 17.799)
		)
		(pad "AF25" smd circle
			(at 11.499 12.499 180)
			(size 0.5 0.5)
			(layers "F.Cu" "F.Mask" "F.Paste")
			(net 703 "/FPGA bank 12/HyperRAM.DQ5")
			(pinfunction "IO_L20N_T3_12")
			(pintype "bidirectional")
			(die_length 18.603)
		)
		(pad "AF26" smd circle
			(at 12.499 12.499 180)
			(size 0.5 0.5)
			(layers "F.Cu" "F.Mask" "F.Paste")
			(net 200 "+3V3")
			(pinfunction "VCCO_12")
			(pintype "passive")
		)
		(pad "B1" smd circle
			(at -12.5 -11.5 180)
			(size 0.5 0.5)
			(layers "F.Cu" "F.Mask" "F.Paste")
			(net 30 "/FPGA MGT Interface/GTX_TX2_N")
			(pinfunction "MGTXTXN2_116")
			(pintype "bidirectional")
			(die_length 15.86)
		)
		(pad "B2" smd circle
			(at -11.5 -11.5 180)
			(size 0.5 0.5)
			(layers "F.Cu" "F.Mask" "F.Paste")
			(net 21 "/FPGA MGT Interface/GTX_TX2_P")
			(pinfunction "MGTXTXP2_116")
			(pintype "bidirectional")
			(die_length 16.008)
		)
		(pad "B3" smd circle
			(at -10.5 -11.5 180)
			(size 0.5 0.5)
			(layers "F.Cu" "F.Mask" "F.Paste")
			(net 226 "+1V2_MGTAVTT")
			(pinfunction "MGTAVTT")
			(pintype "power_in")
		)
		(pad "B4" smd circle
			(at -9.5 -11.5 180)
			(size 0.5 0.5)
			(layers "F.Cu" "F.Mask" "F.Paste")
			(net 1 "GND")
			(pinfunction "GND")
			(pintype "passive")
		)
		(pad "B5" smd circle
			(at -8.5 -11.5 180)
			(size 0.5 0.5)
			(layers "F.Cu" "F.Mask" "F.Paste")
			(net 605 "/FPGA MGT Interface/PCIE.RXD0_N")
			(pinfunction "MGTXRXN3_116")
			(pintype "bidirectional")
			(die_length 13.646)
		)
		(pad "B6" smd circle
			(at -7.5 -11.5 180)
			(size 0.5 0.5)
			(layers "F.Cu" "F.Mask" "F.Paste")
			(net 604 "/FPGA MGT Interface/PCIE.RXD0_P")
			(pinfunction "MGTXRXP3_116")
			(pintype "bidirectional")
			(die_length 13.747)
		)
		(pad "B7" smd circle
			(at -6.5 -11.5 180)
			(size 0.5 0.5)
			(layers "F.Cu" "F.Mask" "F.Paste")
			(net 1 "GND")
			(pinfunction "GND")
			(pintype "passive")
		)
		(pad "B8" smd circle
			(at -5.5 -11.5 180)
			(size 0.5 0.5)
			(layers "F.Cu" "F.Mask" "F.Paste")
			(net 200 "+3V3")
			(pinfunction "VCCO_16")
			(pintype "passive")
		)
		(pad "B9" smd circle
			(at -4.5 -11.5 180)
			(size 0.5 0.5)
			(layers "F.Cu" "F.Mask" "F.Paste")
			(net 401 "unconnected-(U4E-IO_L10N_T1_16-PadB9)")
			(pinfunction "IO_L10N_T1_16")
			(pintype "bidirectional+no_connect")
			(die_length 21.661)
		)
		(pad "B10" smd circle
			(at -3.5 -11.5 180)
			(size 0.5 0.5)
			(layers "F.Cu" "F.Mask" "F.Paste")
			(net 660 "/FPGA bank 16/HDMI.D2_P")
			(pinfunction "IO_L22P_T3_16")
			(pintype "bidirectional")
			(die_length 19.148)
		)
		(pad "B11" smd circle
			(at -2.5 -11.5 180)
			(size 0.5 0.5)
			(layers "F.Cu" "F.Mask" "F.Paste")
			(net 402 "unconnected-(U4E-IO_L20N_T3_16-PadB11)")
			(pinfunction "IO_L20N_T3_16")
			(pintype "bidirectional+no_connect")
			(die_length 19.129)
		)
		(pad "B12" smd circle
			(at -1.5 -11.5 180)
			(size 0.5 0.5)
			(layers "F.Cu" "F.Mask" "F.Paste")
			(net 403 "unconnected-(U4E-IO_L20P_T3_16-PadB12)")
			(pinfunction "IO_L20P_T3_16")
			(pintype "bidirectional+no_connect")
			(die_length 19.084)
		)
		(pad "B13" smd circle
			(at -0.5 -11.5 180)
			(size 0.5 0.5)
			(layers "F.Cu" "F.Mask" "F.Paste")
			(net 1 "GND")
			(pinfunction "GND")
			(pintype "passive")
		)
		(pad "B14" smd circle
			(at 0.499 -11.5 180)
			(size 0.5 0.5)
			(layers "F.Cu" "F.Mask" "F.Paste")
			(net 664 "/FPGA bank 16/HDMI.D0_P")
			(pinfunction "IO_L21P_T3_DQS_16")
			(pintype "bidirectional")
			(die_length 17.698)
		)
		(pad "B15" smd circle
			(at 1.499 -11.5 180)
			(size 0.5 0.5)
			(layers "F.Cu" "F.Mask" "F.Paste")
			(net 666 "/FPGA bank 16/HDMI.CLK_P")
			(pinfunction "IO_L23P_T3_16")
			(pintype "bidirectional")
			(die_length 17.518)
		)
		(pad "B16" smd circle
			(at 2.499 -11.5 180)
			(size 0.5 0.5)
			(layers "F.Cu" "F.Mask" "F.Paste")
			(net 404 "unconnected-(U4D-IO_L1N_T0_AD0N_15-PadB16)")
			(pinfunction "IO_L1N_T0_AD0N_15")
			(pintype "bidirectional+no_connect")
			(die_length 16.625)
		)
		(pad "B17" smd circle
			(at 3.499 -11.5 180)
			(size 0.5 0.5)
			(layers "F.Cu" "F.Mask" "F.Paste")
			(net 405 "unconnected-(U4D-IO_L3P_T0_DQS_AD1P_15-PadB17)")
			(pinfunction "IO_L3P_T0_DQS_AD1P_15")
			(pintype "bidirectional+no_connect")
			(die_length 17.668)
		)
		(pad "B18" smd circle
			(at 4.499 -11.5 180)
			(size 0.5 0.5)
			(layers "F.Cu" "F.Mask" "F.Paste")
			(net 377 "Net-(R97-Pad2)")
			(pinfunction "VCCO_15")
			(pintype "power_in")
		)
		(pad "B19" smd circle
			(at 5.499 -11.5 180)
			(size 0.5 0.5)
			(layers "F.Cu" "F.Mask" "F.Paste")
			(net 406 "unconnected-(U4D-IO_L4N_T0_AD9N_15-PadB19)")
			(pinfunction "IO_L4N_T0_AD9N_15")
			(pintype "bidirectional+no_connect")
			(die_length 18.77)
		)
		(pad "B20" smd circle
			(at 6.499 -11.5 180)
			(size 0.5 0.5)
			(layers "F.Cu" "F.Mask" "F.Paste")
			(net 619 "/FPGA bank 14/USR_LED2")
			(pinfunction "IO_L8P_T1_D11_14")
			(pintype "bidirectional")
			(die_length 20.881)
		)
		(pad "B21" smd circle
			(at 7.499 -11.5 180)
			(size 0.5 0.5)
			(layers "F.Cu" "F.Mask" "F.Paste")
			(net 617 "/FPGA bank 14/USR_LED3")
			(pinfunction "IO_L10N_T1_D15_14")
			(pintype "bidirectional")
			(die_length 22.228)
		)
		(pad "B22" smd circle
			(at 8.499 -11.5 180)
			(size 0.5 0.5)
			(layers "F.Cu" "F.Mask" "F.Paste")
			(net 628 "/FPGA Config/FLASH.IO2")
			(pinfunction "IO_L2P_T0_D02_14")
			(pintype "bidirectional")
			(die_length 20.4)
		)
		(pad "B23" smd circle
			(at 9.499 -11.5 180)
			(size 0.5 0.5)
			(layers "F.Cu" "F.Mask" "F.Paste")
			(net 1 "GND")
			(pinfunction "GND")
			(pintype "passive")
		)
		(pad "B24" smd circle
			(at 10.499 -11.5 180)
			(size 0.5 0.5)
			(layers "F.Cu" "F.Mask" "F.Paste")
			(net 626 "/FPGA Config/FLASH.IO0")
			(pinfunction "IO_L1P_T0_D00_MOSI_14")
			(pintype "bidirectional")
			(die_length 22.518)
		)
		(pad "B25" smd circle
			(at 11.499 -11.5 180)
			(size 0.5 0.5)
			(layers "F.Cu" "F.Mask" "F.Paste")
			(net 612 "/FPGA bank 14/PUDC_B")
			(pinfunction "IO_L3P_T0_DQS_PUDC_B_14")
			(pintype "bidirectional")
			(die_length 23.894)
		)
		(pad "B26" smd circle
			(at 12.499 -11.5 180)
			(size 0.5 0.5)
			(layers "F.Cu" "F.Mask" "F.Paste")
			(net 44 "/FPGA bank 14/EMCCLK")
			(pinfunction "IO_L3N_T0_DQS_EMCCLK_14")
			(pintype "bidirectional")
			(die_length 24.039)
		)
		(pad "C1" smd circle
			(at -12.5 -10.5 180)
			(size 0.5 0.5)
			(layers "F.Cu" "F.Mask" "F.Paste")
			(net 1 "GND")
			(pinfunction "GND")
			(pintype "passive")
		)
		(pad "C2" smd circle
			(at -11.5 -10.5 180)
			(size 0.5 0.5)
			(layers "F.Cu" "F.Mask" "F.Paste")
			(net 226 "+1V2_MGTAVTT")
			(pinfunction "MGTAVTT")
			(pintype "passive")
		)
		(pad "C3" smd circle
			(at -10.5 -10.5 180)
			(size 0.5 0.5)
			(layers "F.Cu" "F.Mask" "F.Paste")
			(net 607 "/FPGA MGT Interface/PCIE.RXD1_N")
			(pinfunction "MGTXRXN2_116")
			(pintype "bidirectional")
			(die_length 14.495)
		)
		(pad "C4" smd circle
			(at -9.5 -10.5 180)
			(size 0.5 0.5)
			(layers "F.Cu" "F.Mask" "F.Paste")
			(net 606 "/FPGA MGT Interface/PCIE.RXD1_P")
			(pinfunction "MGTXRXP2_116")
			(pintype "bidirectional")
			(die_length 14.581)
		)
		(pad "C5" smd circle
			(at -8.5 -10.5 180)
			(size 0.5 0.5)
			(layers "F.Cu" "F.Mask" "F.Paste")
			(net 1 "GND")
			(pinfunction "GND")
			(pintype "passive")
		)
		(pad "C6" smd circle
			(at -7.5 -10.5 180)
			(size 0.5 0.5)
			(layers "F.Cu" "F.Mask" "F.Paste")
			(net 187 "+1V0_MGTAVCC")
			(pinfunction "MGTAVCC")
			(pintype "power_in")
		)
		(pad "C7" smd circle
			(at -6.5 -10.5 180)
			(size 0.5 0.5)
			(layers "F.Cu" "F.Mask" "F.Paste")
			(net 1 "GND")
			(pinfunction "GND")
			(pintype "passive")
		)
		(pad "C8" smd circle
			(at -5.5 -10.5 180)
			(size 0.5 0.5)
			(layers "F.Cu" "F.Mask" "F.Paste")
			(net 630 "/FPGA Config/FLASH.SCK")
			(pinfunction "CCLK_0")
			(pintype "bidirectional")
			(die_length 21.831)
		)
		(pad "C9" smd circle
			(at -4.5 -10.5 180)
			(size 0.5 0.5)
			(layers "F.Cu" "F.Mask" "F.Paste")
			(net 350 "/FPGA bank 16/SD.DAT2")
			(pinfunction "IO_L10P_T1_16")
			(pintype "bidirectional")
			(die_length 20.913)
		)
		(pad "C10" smd circle
			(at -3.5 -10.5 180)
			(size 0.5 0.5)
			(layers "F.Cu" "F.Mask" "F.Paste")
			(net 1 "GND")
			(pinfunction "GND")
			(pintype "passive")
		)
		(pad "C11" smd circle
			(at -2.5 -10.5 180)
			(size 0.5 0.5)
			(layers "F.Cu" "F.Mask" "F.Paste")
			(net 407 "unconnected-(U4E-IO_L13N_T2_MRCC_16-PadC11)")
			(pinfunction "IO_L13N_T2_MRCC_16")
			(pintype "bidirectional+no_connect")
			(die_length 19.377)
		)
		(pad "C12" smd circle
			(at -1.5 -10.5 180)
			(size 0.5 0.5)
			(layers "F.Cu" "F.Mask" "F.Paste")
			(net 706 "/FPGA bank 16/GCLK100")
			(pinfunction "IO_L13P_T2_MRCC_16")
			(pintype "bidirectional")
			(die_length 19.317)
		)
		(pad "C13" smd circle
			(at -0.5 -10.5 180)
			(size 0.5 0.5)
			(layers "F.Cu" "F.Mask" "F.Paste")
			(net 408 "unconnected-(U4E-IO_L19N_T3_VREF_16-PadC13)")
			(pinfunction "IO_L19N_T3_VREF_16")
			(pintype "bidirectional+no_connect")
			(die_length 16.263)
		)
		(pad "C14" smd circle
			(at 0.499 -10.5 180)
			(size 0.5 0.5)
			(layers "F.Cu" "F.Mask" "F.Paste")
			(net 409 "unconnected-(U4E-IO_L19P_T3_16-PadC14)")
			(pinfunction "IO_L19P_T3_16")
			(pintype "bidirectional+no_connect")
			(die_length 15.843)
		)
		(pad "C15" smd circle
			(at 1.499 -10.5 180)
			(size 0.5 0.5)
			(layers "F.Cu" "F.Mask" "F.Paste")
			(net 200 "+3V3")
			(pinfunction "VCCO_16")
			(pintype "passive")
		)
		(pad "C16" smd circle
			(at 2.499 -10.5 180)
			(size 0.5 0.5)
			(layers "F.Cu" "F.Mask" "F.Paste")
			(net 410 "unconnected-(U4D-IO_L1P_T0_AD0P_15-PadC16)")
			(pinfunction "IO_L1P_T0_AD0P_15")
			(pintype "bidirectional+no_connect")
			(die_length 14.788)
		)
		(pad "C17" smd circle
			(at 3.499 -10.5 180)
			(size 0.5 0.5)
			(layers "F.Cu" "F.Mask" "F.Paste")
			(net 411 "unconnected-(U4D-IO_L5P_T0_AD2P_15-PadC17)")
			(pinfunction "IO_L5P_T0_AD2P_15")
			(pintype "bidirectional+no_connect")
			(die_length 15.703)
		)
		(pad "C18" smd circle
			(at 4.499 -10.5 180)
			(size 0.5 0.5)
			(layers "F.Cu" "F.Mask" "F.Paste")
			(net 412 "unconnected-(U4D-IO_L5N_T0_AD2N_15-PadC18)")
			(pinfunction "IO_L5N_T0_AD2N_15")
			(pintype "bidirectional+no_connect")
			(die_length 17.41)
		)
		(pad "C19" smd circle
			(at 5.499 -10.5 180)
			(size 0.5 0.5)
			(layers "F.Cu" "F.Mask" "F.Paste")
			(net 413 "unconnected-(U4D-IO_L4P_T0_AD9P_15-PadC19)")
			(pinfunction "IO_L4P_T0_AD9P_15")
			(pintype "bidirectional+no_connect")
			(die_length 16.927)
		)
		(pad "C20" smd circle
			(at 6.499 -10.5 180)
			(size 0.5 0.5)
			(layers "F.Cu" "F.Mask" "F.Paste")
			(net 1 "GND")
			(pinfunction "GND")
			(pintype "passive")
		)
		(pad "C21" smd circle
			(at 7.499 -10.5 180)
			(size 0.5 0.5)
			(layers "F.Cu" "F.Mask" "F.Paste")
			(net 106 "HOT_SWAP_BUTTON")
			(pinfunction "IO_L10P_T1_D14_14")
			(pintype "bidirectional")
			(die_length 20.52)
		)
		(pad "C22" smd circle
			(at 8.499 -10.5 180)
			(size 0.5 0.5)
			(layers "F.Cu" "F.Mask" "F.Paste")
			(net 621 "/FPGA bank 14/USR_LED4")
			(pinfunction "IO_L7N_T1_D10_14")
			(pintype "bidirectional")
			(die_length 20.673)
		)
		(pad "C23" smd circle
			(at 9.499 -10.5 180)
			(size 0.5 0.5)
			(layers "F.Cu" "F.Mask" "F.Paste")
			(net 625 "/FPGA Config/FLASH.~{CS}")
			(pinfunction "IO_L6P_T0_FCS_B_14")
			(pintype "bidirectional")
			(die_length 20.723)
		)
		(pad "C24" smd circle
			(at 10.499 -10.5 180)
			(size 0.5 0.5)
			(layers "F.Cu" "F.Mask" "F.Paste")
			(net 647 "/Debug FTDI/AUX.TCK")
			(pinfunction "IO_L6N_T0_D08_VREF_14")
			(pintype "bidirectional")
			(die_length 22.056)
		)
		(pad "C25" smd circle
			(at 11.499 -10.5 180)
			(size 0.5 0.5)
			(layers "F.Cu" "F.Mask" "F.Paste")
			(net 200 "+3V3")
			(pinfunction "VCCO_14")
			(pintype "passive")
		)
		(pad "C26" smd circle
			(at 12.499 -10.5 180)
			(size 0.5 0.5)
			(layers "F.Cu" "F.Mask" "F.Paste")
			(net 651 "/Debug FTDI/AUX.TDO")
			(pinfunction "IO_L5N_T0_D07_14")
			(pintype "bidirectional")
			(die_length 24.432)
		)
		(pad "D1" smd circle
			(at -12.5 -9.5 180)
			(size 0.5 0.5)
			(layers "F.Cu" "F.Mask" "F.Paste")
			(net 27 "/FPGA MGT Interface/GTX_TX1_N")
			(pinfunction "MGTXTXN1_116")
			(pintype "bidirectional")
			(die_length 15.23)
		)
		(pad "D2" smd circle
			(at -11.5 -9.5 180)
			(size 0.5 0.5)
			(layers "F.Cu" "F.Mask" "F.Paste")
			(net 19 "/FPGA MGT Interface/GTX_TX1_P")
			(pinfunction "MGTXTXP1_116")
			(pintype "bidirectional")
			(die_length 15.219)
		)
		(pad "D3" smd circle
			(at -10.5 -9.5 180)
			(size 0.5 0.5)
			(layers "F.Cu" "F.Mask" "F.Paste")
			(net 226 "+1V2_MGTAVTT")
			(pinfunction "MGTAVTT")
			(pintype "passive")
		)
		(pad "D4" smd circle
			(at -9.5 -9.5 180)
			(size 0.5 0.5)
			(layers "F.Cu" "F.Mask" "F.Paste")
			(net 1 "GND")
			(pinfunction "GND")
			(pintype "passive")
		)
		(pad "D5" smd circle
			(at -8.5 -9.5 180)
			(size 0.5 0.5)
			(layers "F.Cu" "F.Mask" "F.Paste")
			(net 15 "/FPGA MGT Interface/GTR_REFCLK0_N")
			(pinfunction "MGTREFCLK0N_116")
			(pintype "bidirectional")
			(die_length 13.229)
		)
		(pad "D6" smd circle
			(at -7.5 -9.5 180)
			(size 0.5 0.5)
			(layers "F.Cu" "F.Mask" "F.Paste")
			(net 13 "/FPGA MGT Interface/GTR_REFCLK0_P")
			(pinfunction "MGTREFCLK0P_116")
			(pintype "bidirectional")
			(die_length 13.265)
		)
		(pad "D7" smd circle
			(at -6.5 -9.5 180)
			(size 0.5 0.5)
			(layers "F.Cu" "F.Mask" "F.Paste")
			(net 1 "GND")
			(pinfunction "GND")
			(pintype "passive")
		)
		(pad "D8" smd circle
			(at -5.5 -9.5 180)
			(size 0.5 0.5)
			(layers "F.Cu" "F.Mask" "F.Paste")
			(net 372 "/FPGA bank 16/SD.CMD")
			(pinfunction "IO_L8N_T1_16")
			(pintype "bidirectional")
			(die_length 19.972)
		)
		(pad "D9" smd circle
			(at -4.5 -9.5 180)
			(size 0.5 0.5)
			(layers "F.Cu" "F.Mask" "F.Paste")
			(net 371 "/FPGA bank 16/SD.DAT3")
			(pinfunction "IO_L8P_T1_16")
			(pintype "bidirectional")
			(die_length 18.666)
		)
		(pad "D10" smd circle
			(at -3.5 -9.5 180)
			(size 0.5 0.5)
			(layers "F.Cu" "F.Mask" "F.Paste")
			(net 373 "/FPGA bank 16/SD.CLK")
			(pinfunction "IO_L12N_T1_MRCC_16")
			(pintype "bidirectional")
			(die_length 17.142)
		)
		(pad "D11" smd circle
			(at -2.5 -9.5 180)
			(size 0.5 0.5)
			(layers "F.Cu" "F.Mask" "F.Paste")
			(net 414 "unconnected-(U4E-IO_L14N_T2_SRCC_16-PadD11)")
			(pinfunction "IO_L14N_T2_SRCC_16")
			(pintype "bidirectional+no_connect")
			(die_length 15.596)
		)
		(pad "D12" smd circle
			(at -1.5 -9.5 180)
			(size 0.5 0.5)
			(layers "F.Cu" "F.Mask" "F.Paste")
			(net 200 "+3V3")
			(pinfunction "VCCO_16")
			(pintype "passive")
		)
		(pad "D13" smd circle
			(at -0.5 -9.5 180)
			(size 0.5 0.5)
			(layers "F.Cu" "F.Mask" "F.Paste")
			(net 415 "unconnected-(U4E-IO_L17N_T2_16-PadD13)")
			(pinfunction "IO_L17N_T2_16")
			(pintype "bidirectional+no_connect")
			(die_length 16.197)
		)
		(pad "D14" smd circle
			(at 0.499 -9.5 180)
			(size 0.5 0.5)
			(layers "F.Cu" "F.Mask" "F.Paste")
			(net 416 "unconnected-(U4E-IO_L17P_T2_16-PadD14)")
			(pinfunction "IO_L17P_T2_16")
			(pintype "bidirectional+no_connect")
			(die_length 15.301)
		)
		(pad "D15" smd circle
			(at 1.499 -9.5 180)
			(size 0.5 0.5)
			(layers "F.Cu" "F.Mask" "F.Paste")
			(net 417 "unconnected-(U4D-IO_L6P_T0_15-PadD15)")
			(pinfunction "IO_L6P_T0_15")
			(pintype "bidirectional+no_connect")
			(die_length 17.491)
		)
		(pad "D16" smd circle
			(at 2.499 -9.5 180)
			(size 0.5 0.5)
			(layers "F.Cu" "F.Mask" "F.Paste")
			(net 418 "unconnected-(U4D-IO_L6N_T0_VREF_15-PadD16)")
			(pinfunction "IO_L6N_T0_VREF_15")
			(pintype "bidirectional+no_connect")
			(die_length 17.595)
		)
		(pad "D17" smd circle
			(at 3.499 -9.5 180)
			(size 0.5 0.5)
			(layers "F.Cu" "F.Mask" "F.Paste")
			(net 1 "GND")
			(pinfunction "GND")
			(pintype "passive")
		)
		(pad "D18" smd circle
			(at 4.499 -9.5 180)
			(size 0.5 0.5)
			(layers "F.Cu" "F.Mask" "F.Paste")
			(net 419 "unconnected-(U4D-IO_L13N_T2_MRCC_15-PadD18)")
			(pinfunction "IO_L13N_T2_MRCC_15")
			(pintype "bidirectional+no_connect")
			(die_length 16.746)
		)
		(pad "D19" smd circle
			(at 5.499 -9.5 180)
			(size 0.5 0.5)
			(layers "F.Cu" "F.Mask" "F.Paste")
			(net 420 "unconnected-(U4D-IO_L15P_T2_DQS_15-PadD19)")
			(pinfunction "IO_L15P_T2_DQS_15")
			(pintype "bidirectional+no_connect")
			(die_length 16.273)
		)
		(pad "D20" smd circle
			(at 6.499 -9.5 180)
			(size 0.5 0.5)
			(layers "F.Cu" "F.Mask" "F.Paste")
			(net 421 "unconnected-(U4D-IO_L15N_T2_DQS_ADV_B_15-PadD20)")
			(pinfunction "IO_L15N_T2_DQS_ADV_B_15")
			(pintype "bidirectional+no_connect")
			(die_length 16.189)
		)
		(pad "D21" smd circle
			(at 7.499 -9.5 180)
			(size 0.5 0.5)
			(layers "F.Cu" "F.Mask" "F.Paste")
			(net 615 "/FPGA bank 14/USR_LED1")
			(pinfunction "IO_L7P_T1_D09_14")
			(pintype "bidirectional")
			(die_length 20.735)
		)
		(pad "D22" smd circle
			(at 8.499 -9.5 180)
			(size 0.5 0.5)
			(layers "F.Cu" "F.Mask" "F.Paste")
			(net 200 "+3V3")
			(pinfunction "VCCO_14")
			(pintype "passive")
		)
		(pad "D23" smd circle
			(at 9.499 -9.5 180)
			(size 0.5 0.5)
			(layers "F.Cu" "F.Mask" "F.Paste")
			(net 235 "HOT_SWAP_GREEN")
			(pinfunction "IO_L11P_T1_SRCC_14")
			(pintype "bidirectional")
			(die_length 20.085)
		)
		(pad "D24" smd circle
			(at 10.499 -9.5 180)
			(size 0.5 0.5)
			(layers "F.Cu" "F.Mask" "F.Paste")
			(net 649 "/Debug FTDI/AUX.TDI")
			(pinfunction "IO_L11N_T1_SRCC_14")
			(pintype "bidirectional")
			(die_length 20.314)
		)
		(pad "D25" smd circle
			(at 11.499 -9.5 180)
			(size 0.5 0.5)
			(layers "F.Cu" "F.Mask" "F.Paste")
			(net 653 "/Debug FTDI/AUX.TMS")
			(pinfunction "IO_L15N_T2_DQS_DOUT_CSO_B_14")
			(pintype "bidirectional")
			(die_length 20.821)
		)
		(pad "D26" smd circle
			(at 12.499 -9.5 180)
			(size 0.5 0.5)
			(layers "F.Cu" "F.Mask" "F.Paste")
			(net 683 "/FPGA bank 14/FPGA_DDR.SDA")
			(pinfunction "IO_L5P_T0_D06_14")
			(pintype "bidirectional")
			(die_length 24.394)
		)
		(pad "E1" smd circle
			(at -12.5 -8.5 180)
			(size 0.5 0.5)
			(layers "F.Cu" "F.Mask" "F.Paste")
			(net 1 "GND")
			(pinfunction "GND")
			(pintype "passive")
		)
		(pad "E2" smd circle
			(at -11.5 -8.5 180)
			(size 0.5 0.5)
			(layers "F.Cu" "F.Mask" "F.Paste")
			(net 1 "GND")
			(pinfunction "GND")
			(pintype "passive")
		)
		(pad "E3" smd circle
			(at -10.5 -8.5 180)
			(size 0.5 0.5)
			(layers "F.Cu" "F.Mask" "F.Paste")
			(net 609 "/FPGA MGT Interface/PCIE.RXD2_N")
			(pinfunction "MGTXRXN1_116")
			(pintype "bidirectional")
			(die_length 13.353)
		)
		(pad "E4" smd circle
			(at -9.5 -8.5 180)
			(size 0.5 0.5)
			(layers "F.Cu" "F.Mask" "F.Paste")
			(net 608 "/FPGA MGT Interface/PCIE.RXD2_P")
			(pinfunction "MGTXRXP1_116")
			(pintype "bidirectional")
			(die_length 13.435)
		)
		(pad "E5" smd circle
			(at -8.5 -8.5 180)
			(size 0.5 0.5)
			(layers "F.Cu" "F.Mask" "F.Paste")
			(net 1 "GND")
			(pinfunction "GND")
			(pintype "passive")
		)
		(pad "E6" smd circle
			(at -7.5 -8.5 180)
			(size 0.5 0.5)
			(layers "F.Cu" "F.Mask" "F.Paste")
			(net 187 "+1V0_MGTAVCC")
			(pinfunction "MGTAVCC")
			(pintype "passive")
		)
		(pad "E7" smd circle
			(at -6.5 -8.5 180)
			(size 0.5 0.5)
			(layers "F.Cu" "F.Mask" "F.Paste")
			(net 1 "GND")
			(pinfunction "GND")
			(pintype "passive")
		)
		(pad "E8" smd circle
			(at -5.5 -8.5 180)
			(size 0.5 0.5)
			(layers "F.Cu" "F.Mask" "F.Paste")
			(net 188 "+1V8")
			(pinfunction "VCCBATT_0")
			(pintype "power_in")
		)
		(pad "E9" smd circle
			(at -4.5 -8.5 180)
			(size 0.5 0.5)
			(layers "F.Cu" "F.Mask" "F.Paste")
			(net 200 "+3V3")
			(pinfunction "VCCO_16")
			(pintype "passive")
		)
		(pad "E10" smd circle
			(at -3.5 -8.5 180)
			(size 0.5 0.5)
			(layers "F.Cu" "F.Mask" "F.Paste")
			(net 374 "/FPGA bank 16/SD.DAT0")
			(pinfunction "IO_L12P_T1_MRCC_16")
			(pintype "bidirectional")
			(die_length 17.165)
		)
		(pad "E11" smd circle
			(at -2.5 -8.5 180)
			(size 0.5 0.5)
			(layers "F.Cu" "F.Mask" "F.Paste")
			(net 422 "unconnected-(U4E-IO_L14P_T2_SRCC_16-PadE11)")
			(pinfunction "IO_L14P_T2_SRCC_16")
			(pintype "bidirectional+no_connect")
			(die_length 15.195)
		)
		(pad "E12" smd circle
			(at -1.5 -8.5 180)
			(size 0.5 0.5)
			(layers "F.Cu" "F.Mask" "F.Paste")
			(net 423 "unconnected-(U4E-IO_L18N_T2_16-PadE12)")
			(pinfunction "IO_L18N_T2_16")
			(pintype "bidirectional+no_connect")
			(die_length 14.446)
		)
		(pad "E13" smd circle
			(at -0.5 -8.5 180)
			(size 0.5 0.5)
			(layers "F.Cu" "F.Mask" "F.Paste")
			(net 424 "unconnected-(U4E-IO_L18P_T2_16-PadE13)")
			(pinfunction "IO_L18P_T2_16")
			(pintype "bidirectional+no_connect")
			(die_length 14.156)
		)
		(pad "E14" smd circle
			(at 0.499 -8.5 180)
			(size 0.5 0.5)
			(layers "F.Cu" "F.Mask" "F.Paste")
			(net 1 "GND")
			(pinfunction "GND")
			(pintype "passive")
		)
		(pad "E15" smd circle
			(at 1.499 -8.5 180)
			(size 0.5 0.5)
			(layers "F.Cu" "F.Mask" "F.Paste")
			(net 425 "unconnected-(U4D-IO_L10P_T1_AD4P_15-PadE15)")
			(pinfunction "IO_L10P_T1_AD4P_15")
			(pintype "bidirectional+no_connect")
			(die_length 18.592)
		)
		(pad "E16" smd circle
			(at 2.499 -8.5 180)
			(size 0.5 0.5)
			(layers "F.Cu" "F.Mask" "F.Paste")
			(net 426 "unconnected-(U4D-IO_L10N_T1_AD4N_15-PadE16)")
			(pinfunction "IO_L10N_T1_AD4N_15")
			(pintype "bidirectional+no_connect")
			(die_length 18.741)
		)
		(pad "E17" smd circle
			(at 3.499 -8.5 180)
			(size 0.5 0.5)
			(layers "F.Cu" "F.Mask" "F.Paste")
			(net 427 "unconnected-(U4D-IO_L12N_T1_MRCC_AD5N_15-PadE17)")
			(pinfunction "IO_L12N_T1_MRCC_AD5N_15")
			(pintype "bidirectional+no_connect")
			(die_length 14.038)
		)
		(pad "E18" smd circle
			(at 4.499 -8.5 180)
			(size 0.5 0.5)
			(layers "F.Cu" "F.Mask" "F.Paste")
			(net 428 "unconnected-(U4D-IO_L13P_T2_MRCC_15-PadE18)")
			(pinfunction "IO_L13P_T2_MRCC_15")
			(pintype "bidirectional+no_connect")
			(die_length 17.01)
		)
		(pad "E19" smd circle
			(at 5.499 -8.5 180)
			(size 0.5 0.5)
			(layers "F.Cu" "F.Mask" "F.Paste")
			(net 377 "Net-(R97-Pad2)")
			(pinfunction "VCCO_15")
			(pintype "passive")
		)
		(pad "E20" smd circle
			(at 6.499 -8.5 180)
			(size 0.5 0.5)
			(layers "F.Cu" "F.Mask" "F.Paste")
			(net 429 "unconnected-(U4D-IO_L17N_T2_A25_15-PadE20)")
			(pinfunction "IO_L17N_T2_A25_15")
			(pintype "bidirectional+no_connect")
			(die_length 13.703)
		)
		(pad "E21" smd circle
			(at 7.499 -8.5 180)
			(size 0.5 0.5)
			(layers "F.Cu" "F.Mask" "F.Paste")
			(net 236 "HOT_SWAP_RED")
			(pinfunction "IO_L9P_T1_DQS_14")
			(pintype "bidirectional")
			(die_length 20.497)
		)
		(pad "E22" smd circle
			(at 8.499 -8.5 180)
			(size 0.5 0.5)
			(layers "F.Cu" "F.Mask" "F.Paste")
			(net 622 "/FPGA bank 14/USR_LED5")
			(pinfunction "IO_L9N_T1_DQS_D13_14")
			(pintype "bidirectional")
			(die_length 20.469)
		)
		(pad "E23" smd circle
			(at 9.499 -8.5 180)
			(size 0.5 0.5)
			(layers "F.Cu" "F.Mask" "F.Paste")
			(net 430 "unconnected-(U4C-IO_L12N_T1_MRCC_14-PadE23)")
			(pinfunction "IO_L12N_T1_MRCC_14")
			(pintype "bidirectional+no_connect")
			(die_length 19.664)
		)
		(pad "E24" smd circle
			(at 10.499 -8.5 180)
			(size 0.5 0.5)
			(layers "F.Cu" "F.Mask" "F.Paste")
			(net 1 "GND")
			(pinfunction "GND")
			(pintype "passive")
		)
		(pad "E25" smd circle
			(at 11.499 -8.5 180)
			(size 0.5 0.5)
			(layers "F.Cu" "F.Mask" "F.Paste")
			(net 682 "/FPGA bank 14/FPGA_DDR.SCL")
			(pinfunction "IO_L15P_T2_DQS_RDWR_B_14")
			(pintype "bidirectional")
			(die_length 20.423)
		)
		(pad "E26" smd circle
			(at 12.499 -8.5 180)
			(size 0.5 0.5)
			(layers "F.Cu" "F.Mask" "F.Paste")
			(net 641 "/Debug FTDI/UART0.TX")
			(pinfunction "IO_L17N_T2_A13_D29_14")
			(pintype "bidirectional")
			(die_length 20.928)
		)
		(pad "F1" smd circle
			(at -12.5 -7.5 180)
			(size 0.5 0.5)
			(layers "F.Cu" "F.Mask" "F.Paste")
			(net 25 "/FPGA MGT Interface/GTX_TX0_N")
			(pinfunction "MGTXTXN0_116")
			(pintype "bidirectional")
			(die_length 14.583)
		)
		(pad "F2" smd circle
			(at -11.5 -7.5 180)
			(size 0.5 0.5)
			(layers "F.Cu" "F.Mask" "F.Paste")
			(net 17 "/FPGA MGT Interface/GTX_TX0_P")
			(pinfunction "MGTXTXP0_116")
			(pintype "bidirectional")
			(die_length 14.603)
		)
		(pad "F3" smd circle
			(at -10.5 -7.5 180)
			(size 0.5 0.5)
			(layers "F.Cu" "F.Mask" "F.Paste")
			(net 1 "GND")
			(pinfunction "GND")
			(pintype "passive")
		)
		(pad "F4" smd circle
			(at -9.5 -7.5 180)
			(size 0.5 0.5)
			(layers "F.Cu" "F.Mask" "F.Paste")
			(net 1 "GND")
			(pinfunction "GND")
			(pintype "passive")
		)
		(pad "F5" smd circle
			(at -8.5 -7.5 180)
			(size 0.5 0.5)
			(layers "F.Cu" "F.Mask" "F.Paste")
			(net 431 "unconnected-(U4I-MGTREFCLK1N_116-PadF5)")
			(pinfunction "MGTREFCLK1N_116")
			(pintype "bidirectional+no_connect")
			(die_length 12.724)
		)
		(pad "F6" smd circle
			(at -7.5 -7.5 180)
			(size 0.5 0.5)
			(layers "F.Cu" "F.Mask" "F.Paste")
			(net 432 "unconnected-(U4I-MGTREFCLK1P_116-PadF6)")
			(pinfunction "MGTREFCLK1P_116")
			(pintype "bidirectional+no_connect")
			(die_length 13.203)
		)
		(pad "F7" smd circle
			(at -6.5 -7.5 180)
			(size 0.5 0.5)
			(layers "F.Cu" "F.Mask" "F.Paste")
			(net 1 "GND")
			(pinfunction "GND")
			(pintype "passive")
		)
		(pad "F8" smd circle
			(at -5.5 -7.5 180)
			(size 0.5 0.5)
			(layers "F.Cu" "F.Mask" "F.Paste")
			(net 594 "/FPGA bank 16/SD.DAT1")
			(pinfunction "IO_L7N_T1_16")
			(pintype "bidirectional")
			(die_length 17.801)
		)
		(pad "F9" smd circle
			(at -4.5 -7.5 180)
			(size 0.5 0.5)
			(layers "F.Cu" "F.Mask" "F.Paste")
			(net 669 "/FPGA bank 16/SD.CD")
			(pinfunction "IO_L7P_T1_16")
			(pintype "bidirectional")
			(die_length 16.924)
		)
		(pad "F10" smd circle
			(at -3.5 -7.5 180)
			(size 0.5 0.5)
			(layers "F.Cu" "F.Mask" "F.Paste")
			(net 433 "unconnected-(U4E-IO_L11N_T1_SRCC_16-PadF10)")
			(pinfunction "IO_L11N_T1_SRCC_16")
			(pintype "bidirectional+no_connect")
			(die_length 15.436)
		)
		(pad "F11" smd circle
			(at -2.5 -7.5 180)
			(size 0.5 0.5)
			(layers "F.Cu" "F.Mask" "F.Paste")
			(net 1 "GND")
			(pinfunction "GND")
			(pintype "passive")
		)
		(pad "F12" smd circle
			(at -1.5 -7.5 180)
			(size 0.5 0.5)
			(layers "F.Cu" "F.Mask" "F.Paste")
			(net 434 "unconnected-(U4E-IO_L16N_T2_16-PadF12)")
			(pinfunction "IO_L16N_T2_16")
			(pintype "bidirectional+no_connect")
			(die_length 13.211)
		)
		(pad "F13" smd circle
			(at -0.5 -7.5 180)
			(size 0.5 0.5)
			(layers "F.Cu" "F.Mask" "F.Paste")
			(net 435 "unconnected-(U4E-IO_L15N_T2_DQS_16-PadF13)")
			(pinfunction "IO_L15N_T2_DQS_16")
			(pintype "bidirectional+no_connect")
			(die_length 15.248)
		)
		(pad "F14" smd circle
			(at 0.499 -7.5 180)
			(size 0.5 0.5)
			(layers "F.Cu" "F.Mask" "F.Paste")
			(net 436 "unconnected-(U4E-IO_L15P_T2_DQS_16-PadF14)")
			(pinfunction "IO_L15P_T2_DQS_16")
			(pintype "bidirectional+no_connect")
			(die_length 15.557)
		)
		(pad "F15" smd circle
			(at 1.499 -7.5 180)
			(size 0.5 0.5)
			(layers "F.Cu" "F.Mask" "F.Paste")
			(net 437 "unconnected-(U4D-IO_L8N_T1_AD3N_15-PadF15)")
			(pinfunction "IO_L8N_T1_AD3N_15")
			(pintype "bidirectional+no_connect")
			(die_length 18.872)
		)
		(pad "F16" smd circle
			(at 2.499 -7.5 180)
			(size 0.5 0.5)
			(layers "F.Cu" "F.Mask" "F.Paste")
			(net 377 "Net-(R97-Pad2)")
			(pinfunction "VCCO_15")
			(pintype "passive")
		)
		(pad "F17" smd circle
			(at 3.499 -7.5 180)
			(size 0.5 0.5)
			(layers "F.Cu" "F.Mask" "F.Paste")
			(net 438 "unconnected-(U4D-IO_L12P_T1_MRCC_AD5P_15-PadF17)")
			(pinfunction "IO_L12P_T1_MRCC_AD5P_15")
			(pintype "bidirectional+no_connect")
			(die_length 13.832)
		)
		(pad "F18" smd circle
			(at 4.499 -7.5 180)
			(size 0.5 0.5)
			(layers "F.Cu" "F.Mask" "F.Paste")
			(net 439 "unconnected-(U4D-IO_L11N_T1_SRCC_AD12N_15-PadF18)")
			(pinfunction "IO_L11N_T1_SRCC_AD12N_15")
			(pintype "bidirectional+no_connect")
			(die_length 12.908)
		)
		(pad "F19" smd circle
			(at 5.499 -7.5 180)
			(size 0.5 0.5)
			(layers "F.Cu" "F.Mask" "F.Paste")
			(net 440 "unconnected-(U4D-IO_L17P_T2_A26_15-PadF19)")
			(pinfunction "IO_L17P_T2_A26_15")
			(pintype "bidirectional+no_connect")
			(die_length 14.191)
		)
		(pad "F20" smd circle
			(at 6.499 -7.5 180)
			(size 0.5 0.5)
			(layers "F.Cu" "F.Mask" "F.Paste")
			(net 441 "unconnected-(U4D-IO_L16N_T2_A27_15-PadF20)")
			(pinfunction "IO_L16N_T2_A27_15")
			(pintype "bidirectional+no_connect")
			(die_length 12.487)
		)
		(pad "F21" smd circle
			(at 7.499 -7.5 180)
			(size 0.5 0.5)
			(layers "F.Cu" "F.Mask" "F.Paste")
			(net 1 "GND")
			(pinfunction "GND")
			(pintype "passive")
		)
		(pad "F22" smd circle
			(at 8.499 -7.5 180)
			(size 0.5 0.5)
			(layers "F.Cu" "F.Mask" "F.Paste")
			(net 442 "unconnected-(U4C-IO_L12P_T1_MRCC_14-PadF22)")
			(pinfunction "IO_L12P_T1_MRCC_14")
			(pintype "bidirectional+no_connect")
			(die_length 19.515)
		)
		(pad "F23" smd circle
			(at 9.499 -7.5 180)
			(size 0.5 0.5)
			(layers "F.Cu" "F.Mask" "F.Paste")
			(net 242 "FPGA_POWER_OFF")
			(pinfunction "IO_L13N_T2_MRCC_14")
			(pintype "bidirectional")
			(die_length 17.933)
		)
		(pad "F24" smd circle
			(at 10.499 -7.5 180)
			(size 0.5 0.5)
			(layers "F.Cu" "F.Mask" "F.Paste")
			(net 443 "unconnected-(U4C-IO_L14N_T2_SRCC_14-PadF24)")
			(pinfunction "IO_L14N_T2_SRCC_14")
			(pintype "bidirectional+no_connect")
			(die_length 19.105)
		)
		(pad "F25" smd circle
			(at 11.499 -7.5 180)
			(size 0.5 0.5)
			(layers "F.Cu" "F.Mask" "F.Paste")
			(net 639 "/Debug FTDI/UART0.RX")
			(pinfunction "IO_L17P_T2_A14_D30_14")
			(pintype "bidirectional")
			(die_length 19.892)
		)
		(pad "F26" smd circle
			(at 12.499 -7.5 180)
			(size 0.5 0.5)
			(layers "F.Cu" "F.Mask" "F.Paste")
			(net 200 "+3V3")
			(pinfunction "VCCO_14")
			(pintype "passive")
		)
		(pad "G1" smd circle
			(at -12.5 -6.5 180)
			(size 0.5 0.5)
			(layers "F.Cu" "F.Mask" "F.Paste")
			(net 1 "GND")
			(pinfunction "GND")
			(pintype "passive")
		)
		(pad "G2" smd circle
			(at -11.5 -6.5 180)
			(size 0.5 0.5)
			(layers "F.Cu" "F.Mask" "F.Paste")
			(net 226 "+1V2_MGTAVTT")
			(pinfunction "MGTAVTT")
			(pintype "passive")
		)
		(pad "G3" smd circle
			(at -10.5 -6.5 180)
			(size 0.5 0.5)
			(layers "F.Cu" "F.Mask" "F.Paste")
			(net 611 "/FPGA MGT Interface/PCIE.RXD3_N")
			(pinfunction "MGTXRXN0_116")
			(pintype "bidirectional")
			(die_length 12.486)
		)
		(pad "G4" smd circle
			(at -9.5 -6.5 180)
			(size 0.5 0.5)
			(layers "F.Cu" "F.Mask" "F.Paste")
			(net 610 "/FPGA MGT Interface/PCIE.RXD3_P")
			(pinfunction "MGTXRXP0_116")
			(pintype "bidirectional")
			(die_length 12.584)
		)
		(pad "G5" smd circle
			(at -8.5 -6.5 180)
			(size 0.5 0.5)
			(layers "F.Cu" "F.Mask" "F.Paste")
			(net 1 "GND")
			(pinfunction "GND")
			(pintype "passive")
		)
		(pad "G6" smd circle
			(at -7.5 -6.5 180)
			(size 0.5 0.5)
			(layers "F.Cu" "F.Mask" "F.Paste")
			(net 187 "+1V0_MGTAVCC")
			(pinfunction "MGTAVCC")
			(pintype "passive")
		)
		(pad "G7" smd circle
			(at -6.5 -6.5 180)
			(size 0.5 0.5)
			(layers "F.Cu" "F.Mask" "F.Paste")
			(net 614 "/FPGA Config/INIT_B")
			(pinfunction "INIT_B_0")
			(pintype "bidirectional")
			(die_length 30.602)
		)
		(pad "G8" smd circle
			(at -5.5 -6.5 180)
			(size 0.5 0.5)
			(layers "F.Cu" "F.Mask" "F.Paste")
			(net 1 "GND")
			(pinfunction "GND")
			(pintype "passive")
		)
		(pad "G9" smd circle
			(at -4.5 -6.5 180)
			(size 0.5 0.5)
			(layers "F.Cu" "F.Mask" "F.Paste")
			(net 444 "unconnected-(U4E-IO_L2N_T0_16-PadG9)")
			(pinfunction "IO_L2N_T0_16")
			(pintype "bidirectional+no_connect")
			(die_length 14.946)
		)
		(pad "G10" smd circle
			(at -3.5 -6.5 180)
			(size 0.5 0.5)
			(layers "F.Cu" "F.Mask" "F.Paste")
			(net 445 "unconnected-(U4E-IO_L2P_T0_16-PadG10)")
			(pinfunction "IO_L2P_T0_16")
			(pintype "bidirectional+no_connect")
			(die_length 13.481)
		)
		(pad "G11" smd circle
			(at -2.5 -6.5 180)
			(size 0.5 0.5)
			(layers "F.Cu" "F.Mask" "F.Paste")
			(net 446 "unconnected-(U4E-IO_L11P_T1_SRCC_16-PadG11)")
			(pinfunction "IO_L11P_T1_SRCC_16")
			(pintype "bidirectional+no_connect")
			(die_length 14.905)
		)
		(pad "G12" smd circle
			(at -1.5 -6.5 180)
			(size 0.5 0.5)
			(layers "F.Cu" "F.Mask" "F.Paste")
			(net 447 "unconnected-(U4E-IO_L16P_T2_16-PadG12)")
			(pinfunction "IO_L16P_T2_16")
			(pintype "bidirectional+no_connect")
			(die_length 13.211)
		)
		(pad "G13" smd circle
			(at -0.5 -6.5 180)
			(size 0.5 0.5)
			(layers "F.Cu" "F.Mask" "F.Paste")
			(net 200 "+3V3")
			(pinfunction "VCCO_16")
			(pintype "passive")
		)
		(pad "G14" smd circle
			(at 0.499 -6.5 180)
			(size 0.5 0.5)
			(layers "F.Cu" "F.Mask" "F.Paste")
			(net 448 "unconnected-(U4E-IO_L5N_T0_16-PadG14)")
			(pinfunction "IO_L5N_T0_16")
			(pintype "bidirectional+no_connect")
			(die_length 10.327)
		)
		(pad "G15" smd circle
			(at 1.499 -6.5 180)
			(size 0.5 0.5)
			(layers "F.Cu" "F.Mask" "F.Paste")
			(net 449 "unconnected-(U4D-IO_L8P_T1_AD3P_15-PadG15)")
			(pinfunction "IO_L8P_T1_AD3P_15")
			(pintype "bidirectional+no_connect")
			(die_length 19.124)
		)
		(pad "G16" smd circle
			(at 2.499 -6.5 180)
			(size 0.5 0.5)
			(layers "F.Cu" "F.Mask" "F.Paste")
			(net 450 "unconnected-(U4D-IO_L7N_T1_AD10N_15-PadG16)")
			(pinfunction "IO_L7N_T1_AD10N_15")
			(pintype "bidirectional+no_connect")
			(die_length 13.719)
		)
		(pad "G17" smd circle
			(at 3.499 -6.5 180)
			(size 0.5 0.5)
			(layers "F.Cu" "F.Mask" "F.Paste")
			(net 451 "unconnected-(U4D-IO_L11P_T1_SRCC_AD12P_15-PadG17)")
			(pinfunction "IO_L11P_T1_SRCC_AD12P_15")
			(pintype "bidirectional+no_connect")
			(die_length 12.537)
		)
		(pad "G18" smd circle
			(at 4.499 -6.5 180)
			(size 0.5 0.5)
			(layers "F.Cu" "F.Mask" "F.Paste")
			(net 1 "GND")
			(pinfunction "GND")
			(pintype "passive")
		)
		(pad "G19" smd circle
			(at 5.499 -6.5 180)
			(size 0.5 0.5)
			(layers "F.Cu" "F.Mask" "F.Paste")
			(net 452 "unconnected-(U4D-IO_L16P_T2_A28_15-PadG19)")
			(pinfunction "IO_L16P_T2_A28_15")
			(pintype "bidirectional+no_connect")
			(die_length 12.445)
		)
		(pad "G20" smd circle
			(at 6.499 -6.5 180)
			(size 0.5 0.5)
			(layers "F.Cu" "F.Mask" "F.Paste")
			(net 453 "unconnected-(U4D-IO_L18N_T2_A23_15-PadG20)")
			(pinfunction "IO_L18N_T2_A23_15")
			(pintype "bidirectional+no_connect")
			(die_length 11.544)
		)
		(pad "G21" smd circle
			(at 7.499 -6.5 180)
			(size 0.5 0.5)
			(layers "F.Cu" "F.Mask" "F.Paste")
			(net 454 "unconnected-(U4C-IO_L19N_T3_A09_D25_VREF_14-PadG21)")
			(pinfunction "IO_L19N_T3_A09_D25_VREF_14")
			(pintype "bidirectional+no_connect")
			(die_length 18.813)
		)
		(pad "G22" smd circle
			(at 8.499 -6.5 180)
			(size 0.5 0.5)
			(layers "F.Cu" "F.Mask" "F.Paste")
			(net 455 "unconnected-(U4C-IO_L13P_T2_MRCC_14-PadG22)")
			(pinfunction "IO_L13P_T2_MRCC_14")
			(pintype "bidirectional+no_connect")
			(die_length 18.389)
		)
		(pad "G23" smd circle
			(at 9.499 -6.5 180)
			(size 0.5 0.5)
			(layers "F.Cu" "F.Mask" "F.Paste")
			(net 200 "+3V3")
			(pinfunction "VCCO_14")
			(pintype "passive")
		)
		(pad "G24" smd circle
			(at 10.499 -6.5 180)
			(size 0.5 0.5)
			(layers "F.Cu" "F.Mask" "F.Paste")
			(net 688 "/FPGA bank 14/FPGA_PWR.SDA")
			(pinfunction "IO_L14P_T2_SRCC_14")
			(pintype "bidirectional")
			(die_length 19.02)
		)
		(pad "G25" smd circle
			(at 11.499 -6.5 180)
			(size 0.5 0.5)
			(layers "F.Cu" "F.Mask" "F.Paste")
			(net 655 "/Debug FTDI/AUX.RST")
			(pinfunction "IO_L16P_T2_CSI_B_14")
			(pintype "bidirectional")
			(die_length 19.777)
		)
		(pad "G26" smd circle
			(at 12.499 -6.5 180)
			(size 0.5 0.5)
			(layers "F.Cu" "F.Mask" "F.Paste")
			(net 241 "FPGA_POWER_CYCLE")
			(pinfunction "IO_L16N_T2_A15_D31_14")
			(pintype "bidirectional")
			(die_length 19.839)
		)
		(pad "H1" smd circle
			(at -12.5 -5.5 180)
			(size 0.5 0.5)
			(layers "F.Cu" "F.Mask" "F.Paste")
			(net 456 "unconnected-(U4I-MGTXTXN3_115-PadH1)")
			(pinfunction "MGTXTXN3_115")
			(pintype "bidirectional+no_connect")
			(die_length 13.778)
		)
		(pad "H2" smd circle
			(at -11.5 -5.5 180)
			(size 0.5 0.5)
			(layers "F.Cu" "F.Mask" "F.Paste")
			(net 457 "unconnected-(U4I-MGTXTXP3_115-PadH2)")
			(pinfunction "MGTXTXP3_115")
			(pintype "bidirectional+no_connect")
			(die_length 13.817)
		)
		(pad "H3" smd circle
			(at -10.5 -5.5 180)
			(size 0.5 0.5)
			(layers "F.Cu" "F.Mask" "F.Paste")
			(net 226 "+1V2_MGTAVTT")
			(pinfunction "MGTAVTT")
			(pintype "passive")
		)
		(pad "H4" smd circle
			(at -9.5 -5.5 180)
			(size 0.5 0.5)
			(layers "F.Cu" "F.Mask" "F.Paste")
			(net 1 "GND")
			(pinfunction "GND")
			(pintype "passive")
		)
		(pad "H5" smd circle
			(at -8.5 -5.5 180)
			(size 0.5 0.5)
			(layers "F.Cu" "F.Mask" "F.Paste")
			(net 458 "unconnected-(U4I-MGTREFCLK0N_115-PadH5)")
			(pinfunction "MGTREFCLK0N_115")
			(pintype "bidirectional+no_connect")
			(die_length 11.598)
		)
		(pad "H6" smd circle
			(at -7.5 -5.5 180)
			(size 0.5 0.5)
			(layers "F.Cu" "F.Mask" "F.Paste")
			(net 459 "unconnected-(U4I-MGTREFCLK0P_115-PadH6)")
			(pinfunction "MGTREFCLK0P_115")
			(pintype "bidirectional+no_connect")
			(die_length 11.559)
		)
		(pad "H7" smd circle
			(at -6.5 -5.5 180)
			(size 0.5 0.5)
			(layers "F.Cu" "F.Mask" "F.Paste")
			(net 1 "GND")
			(pinfunction "GND")
			(pintype "passive")
		)
		(pad "H8" smd circle
			(at -5.5 -5.5 180)
			(size 0.5 0.5)
			(layers "F.Cu" "F.Mask" "F.Paste")
			(net 460 "unconnected-(U4E-IO_L1N_T0_16-PadH8)")
			(pinfunction "IO_L1N_T0_16")
			(pintype "bidirectional+no_connect")
			(die_length 16.747)
		)
		(pad "H9" smd circle
			(at -4.5 -5.5 180)
			(size 0.5 0.5)
			(layers "F.Cu" "F.Mask" "F.Paste")
			(net 461 "unconnected-(U4E-IO_L1P_T0_16-PadH9)")
			(pinfunction "IO_L1P_T0_16")
			(pintype "bidirectional+no_connect")
			(die_length 15.601)
		)
		(pad "H10" smd circle
			(at -3.5 -5.5 180)
			(size 0.5 0.5)
			(layers "F.Cu" "F.Mask" "F.Paste")
			(net 200 "+3V3")
			(pinfunction "VCCO_16")
			(pintype "passive")
		)
		(pad "H11" smd circle
			(at -2.5 -5.5 180)
			(size 0.5 0.5)
			(layers "F.Cu" "F.Mask" "F.Paste")
			(net 462 "unconnected-(U4E-IO_L6N_T0_VREF_16-PadH11)")
			(pinfunction "IO_L6N_T0_VREF_16")
			(pintype "bidirectional+no_connect")
			(die_length 14.821)
		)
		(pad "H12" smd circle
			(at -1.5 -5.5 180)
			(size 0.5 0.5)
			(layers "F.Cu" "F.Mask" "F.Paste")
			(net 463 "unconnected-(U4E-IO_L6P_T0_16-PadH12)")
			(pinfunction "IO_L6P_T0_16")
			(pintype "bidirectional+no_connect")
			(die_length 13.516)
		)
		(pad "H13" smd circle
			(at -0.5 -5.5 180)
			(size 0.5 0.5)
			(layers "F.Cu" "F.Mask" "F.Paste")
			(net 464 "unconnected-(U4E-IO_L3N_T0_DQS_16-PadH13)")
			(pinfunction "IO_L3N_T0_DQS_16")
			(pintype "bidirectional+no_connect")
			(die_length 12.402)
		)
		(pad "H14" smd circle
			(at 0.499 -5.5 180)
			(size 0.5 0.5)
			(layers "F.Cu" "F.Mask" "F.Paste")
			(net 465 "unconnected-(U4E-IO_L5P_T0_16-PadH14)")
			(pinfunction "IO_L5P_T0_16")
			(pintype "bidirectional+no_connect")
			(die_length 10.698)
		)
		(pad "H15" smd circle
			(at 1.499 -5.5 180)
			(size 0.5 0.5)
			(layers "F.Cu" "F.Mask" "F.Paste")
			(net 1 "GND")
			(pinfunction "GND")
			(pintype "passive")
		)
		(pad "H16" smd circle
			(at 2.499 -5.5 180)
			(size 0.5 0.5)
			(layers "F.Cu" "F.Mask" "F.Paste")
			(net 466 "unconnected-(U4D-IO_L7P_T1_AD10P_15-PadH16)")
			(pinfunction "IO_L7P_T1_AD10P_15")
			(pintype "bidirectional+no_connect")
			(die_length 14.081)
		)
		(pad "H17" smd circle
			(at 3.499 -5.5 180)
			(size 0.5 0.5)
			(layers "F.Cu" "F.Mask" "F.Paste")
			(net 467 "unconnected-(U4D-IO_L14P_T2_SRCC_15-PadH17)")
			(pinfunction "IO_L14P_T2_SRCC_15")
			(pintype "bidirectional+no_connect")
			(die_length 11.166)
		)
		(pad "H18" smd circle
			(at 4.499 -5.5 180)
			(size 0.5 0.5)
			(layers "F.Cu" "F.Mask" "F.Paste")
			(net 468 "unconnected-(U4D-IO_L14N_T2_SRCC_15-PadH18)")
			(pinfunction "IO_L14N_T2_SRCC_15")
			(pintype "bidirectional+no_connect")
			(die_length 11.108)
		)
		(pad "H19" smd circle
			(at 5.499 -5.5 180)
			(size 0.5 0.5)
			(layers "F.Cu" "F.Mask" "F.Paste")
			(net 469 "unconnected-(U4D-IO_L18P_T2_A24_15-PadH19)")
			(pinfunction "IO_L18P_T2_A24_15")
			(pintype "bidirectional+no_connect")
			(die_length 11.791)
		)
		(pad "H20" smd circle
			(at 6.499 -5.5 180)
			(size 0.5 0.5)
			(layers "F.Cu" "F.Mask" "F.Paste")
			(net 377 "Net-(R97-Pad2)")
			(pinfunction "VCCO_15")
			(pintype "passive")
		)
		(pad "H21" smd circle
			(at 7.499 -5.5 180)
			(size 0.5 0.5)
			(layers "F.Cu" "F.Mask" "F.Paste")
			(net 272 "FAN_PWM")
			(pinfunction "IO_L19P_T3_A10_D26_14")
			(pintype "bidirectional")
			(die_length 18.685)
		)
		(pad "H22" smd circle
			(at 8.499 -5.5 180)
			(size 0.5 0.5)
			(layers "F.Cu" "F.Mask" "F.Paste")
			(net 689 "/FPGA bank 14/FPGA_PWR.SCL")
			(pinfunction "IO_L21N_T3_DQS_A06_D22_14")
			(pintype "bidirectional")
			(die_length 20.841)
		)
		(pad "H23" smd circle
			(at 9.499 -5.5 180)
			(size 0.5 0.5)
			(layers "F.Cu" "F.Mask" "F.Paste")
			(net 470 "unconnected-(U4C-IO_L20P_T3_A08_D24_14-PadH23)")
			(pinfunction "IO_L20P_T3_A08_D24_14")
			(pintype "bidirectional+no_connect")
			(die_length 18.73)
		)
		(pad "H24" smd circle
			(at 10.499 -5.5 180)
			(size 0.5 0.5)
			(layers "F.Cu" "F.Mask" "F.Paste")
			(net 471 "unconnected-(U4C-IO_L20N_T3_A07_D23_14-PadH24)")
			(pinfunction "IO_L20N_T3_A07_D23_14")
			(pintype "bidirectional+no_connect")
			(die_length 17.912)
		)
		(pad "H25" smd circle
			(at 11.499 -5.5 180)
			(size 0.5 0.5)
			(layers "F.Cu" "F.Mask" "F.Paste")
			(net 1 "GND")
			(pinfunction "GND")
			(pintype "passive")
		)
		(pad "H26" smd circle
			(at 12.499 -5.5 180)
			(size 0.5 0.5)
			(layers "F.Cu" "F.Mask" "F.Paste")
			(net 472 "unconnected-(U4C-IO_L18N_T2_A11_D27_14-PadH26)")
			(pinfunction "IO_L18N_T2_A11_D27_14")
			(pintype "bidirectional+no_connect")
			(die_length 19.909)
		)
		(pad "J1" smd circle
			(at -12.5 -4.5 180)
			(size 0.5 0.5)
			(layers "F.Cu" "F.Mask" "F.Paste")
			(net 1 "GND")
			(pinfunction "GND")
			(pintype "passive")
		)
		(pad "J2" smd circle
			(at -11.5 -4.5 180)
			(size 0.5 0.5)
			(layers "F.Cu" "F.Mask" "F.Paste")
			(net 1 "GND")
			(pinfunction "GND")
			(pintype "passive")
		)
		(pad "J3" smd circle
			(at -10.5 -4.5 180)
			(size 0.5 0.5)
			(layers "F.Cu" "F.Mask" "F.Paste")
			(net 473 "unconnected-(U4I-MGTXRXN3_115-PadJ3)")
			(pinfunction "MGTXRXN3_115")
			(pintype "bidirectional+no_connect")
			(die_length 11.806)
		)
		(pad "J4" smd circle
			(at -9.5 -4.5 180)
			(size 0.5 0.5)
			(layers "F.Cu" "F.Mask" "F.Paste")
			(net 474 "unconnected-(U4I-MGTXRXP3_115-PadJ4)")
			(pinfunction "MGTXRXP3_115")
			(pintype "bidirectional+no_connect")
			(die_length 11.935)
		)
		(pad "J5" smd circle
			(at -8.5 -4.5 180)
			(size 0.5 0.5)
			(layers "F.Cu" "F.Mask" "F.Paste")
			(net 1 "GND")
			(pinfunction "GND")
			(pintype "passive")
		)
		(pad "J6" smd circle
			(at -7.5 -4.5 180)
			(size 0.5 0.5)
			(layers "F.Cu" "F.Mask" "F.Paste")
			(net 187 "+1V0_MGTAVCC")
			(pinfunction "MGTAVCC")
			(pintype "passive")
		)
		(pad "J7" smd circle
			(at -6.5 -4.5 180)
			(size 0.5 0.5)
			(layers "F.Cu" "F.Mask" "F.Paste")
			(net 613 "/FPGA Config/DONE")
			(pinfunction "DONE_0")
			(pintype "bidirectional")
			(die_length 33.726)
		)
		(pad "J8" smd circle
			(at -5.5 -4.5 180)
			(size 0.5 0.5)
			(layers "F.Cu" "F.Mask" "F.Paste")
			(net 475 "unconnected-(U4E-IO_0_16-PadJ8)")
			(pinfunction "IO_0_16")
			(pintype "bidirectional+no_connect")
			(die_length 17.143)
		)
		(pad "J9" smd circle
			(at -4.5 -4.5 180)
			(size 0.5 0.5)
			(layers "F.Cu" "F.Mask" "F.Paste")
			(net 227 "+1V0")
			(pinfunction "VCCINT")
			(pintype "power_in")
		)
		(pad "J10" smd circle
			(at -3.5 -4.5 180)
			(size 0.5 0.5)
			(layers "F.Cu" "F.Mask" "F.Paste")
			(net 476 "unconnected-(U4E-IO_L4N_T0_16-PadJ10)")
			(pinfunction "IO_L4N_T0_16")
			(pintype "bidirectional+no_connect")
			(die_length 16.988)
		)
		(pad "J11" smd circle
			(at -2.5 -4.5 180)
			(size 0.5 0.5)
			(layers "F.Cu" "F.Mask" "F.Paste")
			(net 477 "unconnected-(U4E-IO_L4P_T0_16-PadJ11)")
			(pinfunction "IO_L4P_T0_16")
			(pintype "bidirectional+no_connect")
			(die_length 16.441)
		)
		(pad "J12" smd circle
			(at -1.5 -4.5 180)
			(size 0.5 0.5)
			(layers "F.Cu" "F.Mask" "F.Paste")
			(net 1 "GND")
			(pinfunction "GND")
			(pintype "passive")
		)
		(pad "J13" smd circle
			(at -0.5 -4.5 180)
			(size 0.5 0.5)
			(layers "F.Cu" "F.Mask" "F.Paste")
			(net 478 "unconnected-(U4E-IO_L3P_T0_DQS_16-PadJ13)")
			(pinfunction "IO_L3P_T0_DQS_16")
			(pintype "bidirectional+no_connect")
			(die_length 12.775)
		)
		(pad "J14" smd circle
			(at 0.499 -4.5 180)
			(size 0.5 0.5)
			(layers "F.Cu" "F.Mask" "F.Paste")
			(net 479 "unconnected-(U4E-IO_25_16-PadJ14)")
			(pinfunction "IO_25_16")
			(pintype "bidirectional+no_connect")
			(die_length 13.82)
		)
		(pad "J15" smd circle
			(at 1.499 -4.5 180)
			(size 0.5 0.5)
			(layers "F.Cu" "F.Mask" "F.Paste")
			(net 480 "unconnected-(U4D-IO_L9P_T1_DQS_AD11P_15-PadJ15)")
			(pinfunction "IO_L9P_T1_DQS_AD11P_15")
			(pintype "bidirectional+no_connect")
			(die_length 15.384)
		)
		(pad "J16" smd circle
			(at 2.499 -4.5 180)
			(size 0.5 0.5)
			(layers "F.Cu" "F.Mask" "F.Paste")
			(net 481 "unconnected-(U4D-IO_L9N_T1_DQS_AD11N_15-PadJ16)")
			(pinfunction "IO_L9N_T1_DQS_AD11N_15")
			(pintype "bidirectional+no_connect")
			(die_length 14.742)
		)
		(pad "J17" smd circle
			(at 3.499 -4.5 180)
			(size 0.5 0.5)
			(layers "F.Cu" "F.Mask" "F.Paste")
			(net 377 "Net-(R97-Pad2)")
			(pinfunction "VCCO_15")
			(pintype "passive")
		)
		(pad "J18" smd circle
			(at 4.499 -4.5 180)
			(size 0.5 0.5)
			(layers "F.Cu" "F.Mask" "F.Paste")
			(net 482 "unconnected-(U4D-IO_L20P_T3_A20_15-PadJ18)")
			(pinfunction "IO_L20P_T3_A20_15")
			(pintype "bidirectional+no_connect")
			(die_length 11.906)
		)
		(pad "J19" smd circle
			(at 5.499 -4.5 180)
			(size 0.5 0.5)
			(layers "F.Cu" "F.Mask" "F.Paste")
			(net 483 "unconnected-(U4D-IO_L20N_T3_A19_15-PadJ19)")
			(pinfunction "IO_L20N_T3_A19_15")
			(pintype "bidirectional+no_connect")
			(die_length 11.025)
		)
		(pad "J20" smd circle
			(at 6.499 -4.5 180)
			(size 0.5 0.5)
			(layers "F.Cu" "F.Mask" "F.Paste")
			(net 484 "unconnected-(U4D-IO_L19N_T3_A21_VREF_15-PadJ20)")
			(pinfunction "IO_L19N_T3_A21_VREF_15")
			(pintype "bidirectional+no_connect")
			(die_length 9.831)
		)
		(pad "J21" smd circle
			(at 7.499 -4.5 180)
			(size 0.5 0.5)
			(layers "F.Cu" "F.Mask" "F.Paste")
			(net 485 "unconnected-(U4C-IO_L21P_T3_DQS_14-PadJ21)")
			(pinfunction "IO_L21P_T3_DQS_14")
			(pintype "bidirectional+no_connect")
			(die_length 21.288)
		)
		(pad "J22" smd circle
			(at 8.499 -4.5 180)
			(size 0.5 0.5)
			(layers "F.Cu" "F.Mask" "F.Paste")
			(net 1 "GND")
			(pinfunction "GND")
			(pintype "passive")
		)
		(pad "J23" smd circle
			(at 9.499 -4.5 180)
			(size 0.5 0.5)
			(layers "F.Cu" "F.Mask" "F.Paste")
			(net 486 "unconnected-(U4C-IO_L24N_T3_A00_D16_14-PadJ23)")
			(pinfunction "IO_L24N_T3_A00_D16_14")
			(pintype "bidirectional+no_connect")
			(die_length 18.062)
		)
		(pad "J24" smd circle
			(at 10.499 -4.5 180)
			(size 0.5 0.5)
			(layers "F.Cu" "F.Mask" "F.Paste")
			(net 487 "unconnected-(U4C-IO_L22P_T3_A05_D21_14-PadJ24)")
			(pinfunction "IO_L22P_T3_A05_D21_14")
			(pintype "bidirectional+no_connect")
			(die_length 17.661)
		)
		(pad "J25" smd circle
			(at 11.499 -4.5 180)
			(size 0.5 0.5)
			(layers "F.Cu" "F.Mask" "F.Paste")
			(net 488 "unconnected-(U4C-IO_L22N_T3_A04_D20_14-PadJ25)")
			(pinfunction "IO_L22N_T3_A04_D20_14")
			(pintype "bidirectional+no_connect")
			(die_length 17.645)
		)
		(pad "J26" smd circle
			(at 12.499 -4.5 180)
			(size 0.5 0.5)
			(layers "F.Cu" "F.Mask" "F.Paste")
			(net 489 "unconnected-(U4C-IO_L18P_T2_A12_D28_14-PadJ26)")
			(pinfunction "IO_L18P_T2_A12_D28_14")
			(pintype "bidirectional+no_connect")
			(die_length 21.026)
		)
		(pad "K1" smd circle
			(at -12.5 -3.5 180)
			(size 0.5 0.5)
			(layers "F.Cu" "F.Mask" "F.Paste")
			(net 490 "unconnected-(U4I-MGTXTXN2_115-PadK1)")
			(pinfunction "MGTXTXN2_115")
			(pintype "bidirectional+no_connect")
			(die_length 13.554)
		)
		(pad "K2" smd circle
			(at -11.5 -3.5 180)
			(size 0.5 0.5)
			(layers "F.Cu" "F.Mask" "F.Paste")
			(net 491 "unconnected-(U4I-MGTXTXP2_115-PadK2)")
			(pinfunction "MGTXTXP2_115")
			(pintype "bidirectional+no_connect")
			(die_length 13.554)
		)
		(pad "K3" smd circle
			(at -10.5 -3.5 180)
			(size 0.5 0.5)
			(layers "F.Cu" "F.Mask" "F.Paste")
			(net 1 "GND")
			(pinfunction "GND")
			(pintype "passive")
		)
		(pad "K4" smd circle
			(at -9.5 -3.5 180)
			(size 0.5 0.5)
			(layers "F.Cu" "F.Mask" "F.Paste")
			(net 1 "GND")
			(pinfunction "GND")
			(pintype "passive")
		)
		(pad "K5" smd circle
			(at -8.5 -3.5 180)
			(size 0.5 0.5)
			(layers "F.Cu" "F.Mask" "F.Paste")
			(net 492 "unconnected-(U4I-MGTREFCLK1N_115-PadK5)")
			(pinfunction "MGTREFCLK1N_115")
			(pintype "bidirectional+no_connect")
			(die_length 11.876)
		)
		(pad "K6" smd circle
			(at -7.5 -3.5 180)
			(size 0.5 0.5)
			(layers "F.Cu" "F.Mask" "F.Paste")
			(net 493 "unconnected-(U4I-MGTREFCLK1P_115-PadK6)")
			(pinfunction "MGTREFCLK1P_115")
			(pintype "bidirectional+no_connect")
			(die_length 11.561)
		)
		(pad "K7" smd circle
			(at -6.5 -3.5 180)
			(size 0.5 0.5)
			(layers "F.Cu" "F.Mask" "F.Paste")
			(net 1 "GND")
			(pinfunction "GND")
			(pintype "passive")
		)
		(pad "K8" smd circle
			(at -5.5 -3.5 180)
			(size 0.5 0.5)
			(layers "F.Cu" "F.Mask" "F.Paste")
			(net 227 "+1V0")
			(pinfunction "VCCINT")
			(pintype "passive")
		)
		(pad "K9" smd circle
			(at -4.5 -3.5 180)
			(size 0.5 0.5)
			(layers "F.Cu" "F.Mask" "F.Paste")
			(net 1 "GND")
			(pinfunction "GND")
			(pintype "passive")
		)
		(pad "K10" smd circle
			(at -3.5 -3.5 180)
			(size 0.5 0.5)
			(layers "F.Cu" "F.Mask" "F.Paste")
			(net 227 "+1V0")
			(pinfunction "VCCINT")
			(pintype "passive")
		)
		(pad "K11" smd circle
			(at -2.5 -3.5 180)
			(size 0.5 0.5)
			(layers "F.Cu" "F.Mask" "F.Paste")
			(net 1 "GND")
			(pinfunction "GND")
			(pintype "passive")
		)
		(pad "K12" smd circle
			(at -1.5 -3.5 180)
			(size 0.5 0.5)
			(layers "F.Cu" "F.Mask" "F.Paste")
			(net 227 "+1V0")
			(pinfunction "VCCINT")
			(pintype "passive")
		)
		(pad "K13" smd circle
			(at -0.5 -3.5 180)
			(size 0.5 0.5)
			(layers "F.Cu" "F.Mask" "F.Paste")
			(net 1 "GND")
			(pinfunction "GND")
			(pintype "passive")
		)
		(pad "K14" smd circle
			(at 0.499 -3.5 180)
			(size 0.5 0.5)
			(layers "F.Cu" "F.Mask" "F.Paste")
			(net 227 "+1V0")
			(pinfunction "VCCINT")
			(pintype "passive")
		)
		(pad "K15" smd circle
			(at 1.499 -3.5 180)
			(size 0.5 0.5)
			(layers "F.Cu" "F.Mask" "F.Paste")
			(net 494 "unconnected-(U4D-IO_0_15-PadK15)")
			(pinfunction "IO_0_15")
			(pintype "bidirectional+no_connect")
			(die_length 6.731)
		)
		(pad "K16" smd circle
			(at 2.499 -3.5 180)
			(size 0.5 0.5)
			(layers "F.Cu" "F.Mask" "F.Paste")
			(net 495 "unconnected-(U4D-IO_L22P_T3_A17_15-PadK16)")
			(pinfunction "IO_L22P_T3_A17_15")
			(pintype "bidirectional+no_connect")
			(die_length 6.898)
		)
		(pad "K17" smd circle
			(at 3.499 -3.5 180)
			(size 0.5 0.5)
			(layers "F.Cu" "F.Mask" "F.Paste")
			(net 496 "unconnected-(U4D-IO_L22N_T3_A16_15-PadK17)")
			(pinfunction "IO_L22N_T3_A16_15")
			(pintype "bidirectional+no_connect")
			(die_length 7.2)
		)
		(pad "K18" smd circle
			(at 4.499 -3.5 180)
			(size 0.5 0.5)
			(layers "F.Cu" "F.Mask" "F.Paste")
			(net 497 "unconnected-(U4D-IO_L24N_T3_RS0_15-PadK18)")
			(pinfunction "IO_L24N_T3_RS0_15")
			(pintype "bidirectional+no_connect")
			(die_length 7.112)
		)
		(pad "K19" smd circle
			(at 5.499 -3.5 180)
			(size 0.5 0.5)
			(layers "F.Cu" "F.Mask" "F.Paste")
			(net 1 "GND")
			(pinfunction "GND")
			(pintype "passive")
		)
		(pad "K20" smd circle
			(at 6.499 -3.5 180)
			(size 0.5 0.5)
			(layers "F.Cu" "F.Mask" "F.Paste")
			(net 498 "unconnected-(U4D-IO_L19P_T3_A22_15-PadK20)")
			(pinfunction "IO_L19P_T3_A22_15")
			(pintype "bidirectional+no_connect")
			(die_length 8.708)
		)
		(pad "K21" smd circle
			(at 7.499 -3.5 180)
			(size 0.5 0.5)
			(layers "F.Cu" "F.Mask" "F.Paste")
			(net 499 "unconnected-(U4C-IO_0_14-PadK21)")
			(pinfunction "IO_0_14")
			(pintype "bidirectional+no_connect")
			(die_length 10.072)
		)
		(pad "K22" smd circle
			(at 8.499 -3.5 180)
			(size 0.5 0.5)
			(layers "F.Cu" "F.Mask" "F.Paste")
			(net 500 "unconnected-(U4C-IO_L23N_T3_A02_D18_14-PadK22)")
			(pinfunction "IO_L23N_T3_A02_D18_14")
			(pintype "bidirectional+no_connect")
			(die_length 16.883)
		)
		(pad "K23" smd circle
			(at 9.499 -3.5 180)
			(size 0.5 0.5)
			(layers "F.Cu" "F.Mask" "F.Paste")
			(net 501 "unconnected-(U4C-IO_L24P_T3_A01_D17_14-PadK23)")
			(pinfunction "IO_L24P_T3_A01_D17_14")
			(pintype "bidirectional+no_connect")
			(die_length 17.632)
		)
		(pad "K24" smd circle
			(at 10.499 -3.5 180)
			(size 0.5 0.5)
			(layers "F.Cu" "F.Mask" "F.Paste")
			(net 376 "Net-(R96-Pad2)")
			(pinfunction "VCCO_13")
			(pintype "power_in")
		)
		(pad "K25" smd circle
			(at 11.499 -3.5 180)
			(size 0.5 0.5)
			(layers "F.Cu" "F.Mask" "F.Paste")
			(net 502 "unconnected-(U4B-IO_L1P_T0_13-PadK25)")
			(pinfunction "IO_L1P_T0_13")
			(pintype "bidirectional+no_connect")
			(die_length 16.886)
		)
		(pad "K26" smd circle
			(at 12.499 -3.5 180)
			(size 0.5 0.5)
			(layers "F.Cu" "F.Mask" "F.Paste")
			(net 503 "unconnected-(U4B-IO_L1N_T0_13-PadK26)")
			(pinfunction "IO_L1N_T0_13")
			(pintype "bidirectional+no_connect")
			(die_length 17.592)
		)
		(pad "L1" smd circle
			(at -12.5 -2.5 180)
			(size 0.5 0.5)
			(layers "F.Cu" "F.Mask" "F.Paste")
			(net 1 "GND")
			(pinfunction "GND")
			(pintype "passive")
		)
		(pad "L2" smd circle
			(at -11.5 -2.5 180)
			(size 0.5 0.5)
			(layers "F.Cu" "F.Mask" "F.Paste")
			(net 226 "+1V2_MGTAVTT")
			(pinfunction "MGTAVTT")
			(pintype "passive")
		)
		(pad "L3" smd circle
			(at -10.5 -2.5 180)
			(size 0.5 0.5)
			(layers "F.Cu" "F.Mask" "F.Paste")
			(net 504 "unconnected-(U4I-MGTXRXN2_115-PadL3)")
			(pinfunction "MGTXRXN2_115")
			(pintype "bidirectional+no_connect")
			(die_length 11.935)
		)
		(pad "L4" smd circle
			(at -9.5 -2.5 180)
			(size 0.5 0.5)
			(layers "F.Cu" "F.Mask" "F.Paste")
			(net 505 "unconnected-(U4I-MGTXRXP2_115-PadL4)")
			(pinfunction "MGTXRXP2_115")
			(pintype "bidirectional+no_connect")
			(die_length 12.06)
		)
		(pad "L5" smd circle
			(at -8.5 -2.5 180)
			(size 0.5 0.5)
			(layers "F.Cu" "F.Mask" "F.Paste")
			(net 1 "GND")
			(pinfunction "GND")
			(pintype "passive")
		)
		(pad "L6" smd circle
			(at -7.5 -2.5 180)
			(size 0.5 0.5)
			(layers "F.Cu" "F.Mask" "F.Paste")
			(net 187 "+1V0_MGTAVCC")
			(pinfunction "MGTAVCC")
			(pintype "passive")
		)
		(pad "L7" smd circle
			(at -6.5 -2.5 180)
			(size 0.5 0.5)
			(layers "F.Cu" "F.Mask" "F.Paste")
			(net 200 "+3V3")
			(pinfunction "VCCO_0")
			(pintype "power_in")
		)
		(pad "L8" smd circle
			(at -5.5 -2.5 180)
			(size 0.5 0.5)
			(layers "F.Cu" "F.Mask" "F.Paste")
			(net 46 "/Debug FTDI/JTAG.TCK")
			(pinfunction "TCK_0")
			(pintype "bidirectional")
			(die_length 14.628)
		)
		(pad "L9" smd circle
			(at -4.5 -2.5 180)
			(size 0.5 0.5)
			(layers "F.Cu" "F.Mask" "F.Paste")
			(net 227 "+1V0")
			(pinfunction "VCCINT")
			(pintype "passive")
		)
		(pad "L10" smd circle
			(at -3.5 -2.5 180)
			(size 0.5 0.5)
			(layers "F.Cu" "F.Mask" "F.Paste")
			(net 1 "GND")
			(pinfunction "GND")
			(pintype "passive")
		)
		(pad "L11" smd circle
			(at -2.5 -2.5 180)
			(size 0.5 0.5)
			(layers "F.Cu" "F.Mask" "F.Paste")
			(net 188 "+1V8")
			(pinfunction "VCCAUX")
			(pintype "power_in")
		)
		(pad "L12" smd circle
			(at -1.5 -2.5 180)
			(size 0.5 0.5)
			(layers "F.Cu" "F.Mask" "F.Paste")
			(net 1 "GND")
			(pinfunction "GND")
			(pintype "passive")
		)
		(pad "L13" smd circle
			(at -0.5 -2.5 180)
			(size 0.5 0.5)
			(layers "F.Cu" "F.Mask" "F.Paste")
			(net 227 "+1V0")
			(pinfunction "VCCINT")
			(pintype "passive")
		)
		(pad "L14" smd circle
			(at 0.499 -2.5 180)
			(size 0.5 0.5)
			(layers "F.Cu" "F.Mask" "F.Paste")
			(net 1 "GND")
			(pinfunction "GND")
			(pintype "passive")
		)
		(pad "L15" smd circle
			(at 1.499 -2.5 180)
			(size 0.5 0.5)
			(layers "F.Cu" "F.Mask" "F.Paste")
			(net 227 "+1V0")
			(pinfunction "VCCINT")
			(pintype "passive")
		)
		(pad "L16" smd circle
			(at 2.499 -2.5 180)
			(size 0.5 0.5)
			(layers "F.Cu" "F.Mask" "F.Paste")
			(net 1 "GND")
			(pinfunction "GND")
			(pintype "passive")
		)
		(pad "L17" smd circle
			(at 3.499 -2.5 180)
			(size 0.5 0.5)
			(layers "F.Cu" "F.Mask" "F.Paste")
			(net 506 "unconnected-(U4D-IO_L24P_T3_RS1_15-PadL17)")
			(pinfunction "IO_L24P_T3_RS1_15")
			(pintype "bidirectional+no_connect")
			(die_length 6.318)
		)
		(pad "L18" smd circle
			(at 4.499 -2.5 180)
			(size 0.5 0.5)
			(layers "F.Cu" "F.Mask" "F.Paste")
			(net 507 "unconnected-(U4D-IO_L23N_T3_FWE_B_15-PadL18)")
			(pinfunction "IO_L23N_T3_FWE_B_15")
			(pintype "bidirectional+no_connect")
			(die_length 7.658)
		)
		(pad "L19" smd circle
			(at 5.499 -2.5 180)
			(size 0.5 0.5)
			(layers "F.Cu" "F.Mask" "F.Paste")
			(net 508 "unconnected-(U4D-IO_L21P_T3_DQS_15-PadL19)")
			(pinfunction "IO_L21P_T3_DQS_15")
			(pintype "bidirectional+no_connect")
			(die_length 7.664)
		)
		(pad "L20" smd circle
			(at 6.499 -2.5 180)
			(size 0.5 0.5)
			(layers "F.Cu" "F.Mask" "F.Paste")
			(net 509 "unconnected-(U4D-IO_L21N_T3_DQS_A18_15-PadL20)")
			(pinfunction "IO_L21N_T3_DQS_A18_15")
			(pintype "bidirectional+no_connect")
			(die_length 7.681)
		)
		(pad "L21" smd circle
			(at 7.499 -2.5 180)
			(size 0.5 0.5)
			(layers "F.Cu" "F.Mask" "F.Paste")
			(net 200 "+3V3")
			(pinfunction "VCCO_14")
			(pintype "passive")
		)
		(pad "L22" smd circle
			(at 8.499 -2.5 180)
			(size 0.5 0.5)
			(layers "F.Cu" "F.Mask" "F.Paste")
			(net 510 "unconnected-(U4C-IO_L23P_T3_A03_D19_14-PadL22)")
			(pinfunction "IO_L23P_T3_A03_D19_14")
			(pintype "bidirectional+no_connect")
			(die_length 16.198)
		)
		(pad "L23" smd circle
			(at 9.499 -2.5 180)
			(size 0.5 0.5)
			(layers "F.Cu" "F.Mask" "F.Paste")
			(net 511 "unconnected-(U4C-IO_25_14-PadL23)")
			(pinfunction "IO_25_14")
			(pintype "bidirectional+no_connect")
			(die_length 15.436)
		)
		(pad "L24" smd circle
			(at 10.499 -2.5 180)
			(size 0.5 0.5)
			(layers "F.Cu" "F.Mask" "F.Paste")
			(net 512 "unconnected-(U4B-IO_L8N_T1_13-PadL24)")
			(pinfunction "IO_L8N_T1_13")
			(pintype "bidirectional+no_connect")
			(die_length 16.877)
		)
		(pad "L25" smd circle
			(at 11.499 -2.5 180)
			(size 0.5 0.5)
			(layers "F.Cu" "F.Mask" "F.Paste")
			(net 513 "unconnected-(U4B-IO_L3N_T0_DQS_13-PadL25)")
			(pinfunction "IO_L3N_T0_DQS_13")
			(pintype "bidirectional+no_connect")
			(die_length 16.692)
		)
		(pad "L26" smd circle
			(at 12.499 -2.5 180)
			(size 0.5 0.5)
			(layers "F.Cu" "F.Mask" "F.Paste")
			(net 1 "GND")
			(pinfunction "GND")
			(pintype "passive")
		)
		(pad "M1" smd circle
			(at -12.5 -1.5 180)
			(size 0.5 0.5)
			(layers "F.Cu" "F.Mask" "F.Paste")
			(net 514 "unconnected-(U4I-MGTXTXN1_115-PadM1)")
			(pinfunction "MGTXTXN1_115")
			(pintype "bidirectional+no_connect")
			(die_length 13.445)
		)
		(pad "M2" smd circle
			(at -11.5 -1.5 180)
			(size 0.5 0.5)
			(layers "F.Cu" "F.Mask" "F.Paste")
			(net 515 "unconnected-(U4I-MGTXTXP1_115-PadM2)")
			(pinfunction "MGTXTXP1_115")
			(pintype "bidirectional+no_connect")
			(die_length 13.639)
		)
		(pad "M3" smd circle
			(at -10.5 -1.5 180)
			(size 0.5 0.5)
			(layers "F.Cu" "F.Mask" "F.Paste")
			(net 226 "+1V2_MGTAVTT")
			(pinfunction "MGTAVTT")
			(pintype "passive")
		)
		(pad "M4" smd circle
			(at -9.5 -1.5 180)
			(size 0.5 0.5)
			(layers "F.Cu" "F.Mask" "F.Paste")
			(net 1 "GND")
			(pinfunction "GND")
			(pintype "passive")
		)
		(pad "M5" smd circle
			(at -8.5 -1.5 180)
			(size 0.5 0.5)
			(layers "F.Cu" "F.Mask" "F.Paste")
			(net 226 "+1V2_MGTAVTT")
			(pinfunction "MGTAVTTRCAL_115")
			(pintype "power_in")
		)
		(pad "M6" smd circle
			(at -7.5 -1.5 180)
			(size 0.5 0.5)
			(layers "F.Cu" "F.Mask" "F.Paste")
			(net 369 "Net-(U4J-MGTRREF_115)")
			(pinfunction "MGTRREF_115")
			(pintype "power_in")
			(die_length 11.045)
		)
		(pad "M7" smd circle
			(at -6.5 -1.5 180)
			(size 0.5 0.5)
			(layers "F.Cu" "F.Mask" "F.Paste")
			(net 1 "GND")
			(pinfunction "GND")
			(pintype "passive")
		)
		(pad "M8" smd circle
			(at -5.5 -1.5 180)
			(size 0.5 0.5)
			(layers "F.Cu" "F.Mask" "F.Paste")
			(net 227 "+1V0")
			(pinfunction "VCCINT")
			(pintype "passive")
		)
		(pad "M9" smd circle
			(at -4.5 -1.5 180)
			(size 0.5 0.5)
			(layers "F.Cu" "F.Mask" "F.Paste")
			(net 1 "GND")
			(pinfunction "GND")
			(pintype "passive")
		)
		(pad "M10" smd circle
			(at -3.5 -1.5 180)
			(size 0.5 0.5)
			(layers "F.Cu" "F.Mask" "F.Paste")
			(net 188 "+1V8")
			(pinfunction "VCCAUX")
			(pintype "passive")
		)
		(pad "M11" smd circle
			(at -2.5 -1.5 180)
			(size 0.5 0.5)
			(layers "F.Cu" "F.Mask" "F.Paste")
			(net 1 "GND")
			(pinfunction "GNDADC_0")
			(pintype "power_in")
		)
		(pad "M12" smd circle
			(at -1.5 -1.5 180)
			(size 0.5 0.5)
			(layers "F.Cu" "F.Mask" "F.Paste")
			(net 188 "+1V8")
			(pinfunction "VCCADC_0")
			(pintype "power_in")
		)
		(pad "M13" smd circle
			(at -0.5 -1.5 180)
			(size 0.5 0.5)
			(layers "F.Cu" "F.Mask" "F.Paste")
			(net 1 "GND")
			(pinfunction "GND")
			(pintype "passive")
		)
		(pad "M14" smd circle
			(at 0.499 -1.5 180)
			(size 0.5 0.5)
			(layers "F.Cu" "F.Mask" "F.Paste")
			(net 227 "+1V0")
			(pinfunction "VCCINT")
			(pintype "passive")
		)
		(pad "M15" smd circle
			(at 1.499 -1.5 180)
			(size 0.5 0.5)
			(layers "F.Cu" "F.Mask" "F.Paste")
			(net 1 "GND")
			(pinfunction "GND")
			(pintype "passive")
		)
		(pad "M16" smd circle
			(at 2.499 -1.5 180)
			(size 0.5 0.5)
			(layers "F.Cu" "F.Mask" "F.Paste")
			(net 516 "unconnected-(U4D-IO_25_15-PadM16)")
			(pinfunction "IO_25_15")
			(pintype "bidirectional+no_connect")
			(die_length 5.552)
		)
		(pad "M17" smd circle
			(at 3.499 -1.5 180)
			(size 0.5 0.5)
			(layers "F.Cu" "F.Mask" "F.Paste")
			(net 517 "unconnected-(U4D-IO_L23P_T3_FOE_B_15-PadM17)")
			(pinfunction "IO_L23P_T3_FOE_B_15")
			(pintype "bidirectional+no_connect")
			(die_length 8.087)
		)
		(pad "M18" smd circle
			(at 4.499 -1.5 180)
			(size 0.5 0.5)
			(layers "F.Cu" "F.Mask" "F.Paste")
			(net 377 "Net-(R97-Pad2)")
			(pinfunction "VCCO_15")
			(pintype "passive")
		)
		(pad "M19" smd circle
			(at 5.499 -1.5 180)
			(size 0.5 0.5)
			(layers "F.Cu" "F.Mask" "F.Paste")
			(net 518 "unconnected-(U4B-IO_L22N_T3_13-PadM19)")
			(pinfunction "IO_L22N_T3_13")
			(pintype "bidirectional+no_connect")
			(die_length 14.527)
		)
		(pad "M20" smd circle
			(at 6.499 -1.5 180)
			(size 0.5 0.5)
			(layers "F.Cu" "F.Mask" "F.Paste")
			(net 519 "unconnected-(U4B-IO_L7N_T1_13-PadM20)")
			(pinfunction "IO_L7N_T1_13")
			(pintype "bidirectional+no_connect")
			(die_length 12.084)
		)
		(pad "M21" smd circle
			(at 7.499 -1.5 180)
			(size 0.5 0.5)
			(layers "F.Cu" "F.Mask" "F.Paste")
			(net 520 "unconnected-(U4B-IO_L10P_T1_13-PadM21)")
			(pinfunction "IO_L10P_T1_13")
			(pintype "bidirectional+no_connect")
			(die_length 14.496)
		)
		(pad "M22" smd circle
			(at 8.499 -1.5 180)
			(size 0.5 0.5)
			(layers "F.Cu" "F.Mask" "F.Paste")
			(net 521 "unconnected-(U4B-IO_L10N_T1_13-PadM22)")
			(pinfunction "IO_L10N_T1_13")
			(pintype "bidirectional+no_connect")
			(die_length 14.558)
		)
		(pad "M23" smd circle
			(at 9.499 -1.5 180)
			(size 0.5 0.5)
			(layers "F.Cu" "F.Mask" "F.Paste")
			(net 1 "GND")
			(pinfunction "GND")
			(pintype "passive")
		)
		(pad "M24" smd circle
			(at 10.499 -1.5 180)
			(size 0.5 0.5)
			(layers "F.Cu" "F.Mask" "F.Paste")
			(net 522 "unconnected-(U4B-IO_L8P_T1_13-PadM24)")
			(pinfunction "IO_L8P_T1_13")
			(pintype "bidirectional+no_connect")
			(die_length 15.433)
		)
		(pad "M25" smd circle
			(at 11.499 -1.5 180)
			(size 0.5 0.5)
			(layers "F.Cu" "F.Mask" "F.Paste")
			(net 523 "unconnected-(U4B-IO_L3P_T0_DQS_13-PadM25)")
			(pinfunction "IO_L3P_T0_DQS_13")
			(pintype "bidirectional+no_connect")
			(die_length 16.172)
		)
		(pad "M26" smd circle
			(at 12.499 -1.5 180)
			(size 0.5 0.5)
			(layers "F.Cu" "F.Mask" "F.Paste")
			(net 524 "unconnected-(U4B-IO_L5N_T0_13-PadM26)")
			(pinfunction "IO_L5N_T0_13")
			(pintype "bidirectional+no_connect")
			(die_length 16.457)
		)
		(pad "N1" smd circle
			(at -12.5 -0.5 180)
			(size 0.5 0.5)
			(layers "F.Cu" "F.Mask" "F.Paste")
			(net 1 "GND")
			(pinfunction "GND")
			(pintype "passive")
		)
		(pad "N2" smd circle
			(at -11.5 -0.5 180)
			(size 0.5 0.5)
			(layers "F.Cu" "F.Mask" "F.Paste")
			(net 1 "GND")
			(pinfunction "GND")
			(pintype "passive")
		)
		(pad "N3" smd circle
			(at -10.5 -0.5 180)
			(size 0.5 0.5)
			(layers "F.Cu" "F.Mask" "F.Paste")
			(net 525 "unconnected-(U4I-MGTXRXN1_115-PadN3)")
			(pinfunction "MGTXRXN1_115")
			(pintype "bidirectional+no_connect")
			(die_length 12.774)
		)
		(pad "N4" smd circle
			(at -9.5 -0.5 180)
			(size 0.5 0.5)
			(layers "F.Cu" "F.Mask" "F.Paste")
			(net 526 "unconnected-(U4I-MGTXRXP1_115-PadN4)")
			(pinfunction "MGTXRXP1_115")
			(pintype "bidirectional+no_connect")
			(die_length 12.878)
		)
		(pad "N5" smd circle
			(at -8.5 -0.5 180)
			(size 0.5 0.5)
			(layers "F.Cu" "F.Mask" "F.Paste")
			(net 1 "GND")
			(pinfunction "GND")
			(pintype "passive")
		)
		(pad "N6" smd circle
			(at -7.5 -0.5 180)
			(size 0.5 0.5)
			(layers "F.Cu" "F.Mask" "F.Paste")
			(net 188 "+1V8")
			(pinfunction "MGTVCCAUX")
			(pintype "power_in")
		)
		(pad "N7" smd circle
			(at -6.5 -0.5 180)
			(size 0.5 0.5)
			(layers "F.Cu" "F.Mask" "F.Paste")
			(net 1 "GND")
			(pinfunction "GND")
			(pintype "passive")
		)
		(pad "N8" smd circle
			(at -5.5 -0.5 180)
			(size 0.5 0.5)
			(layers "F.Cu" "F.Mask" "F.Paste")
			(net 45 "/Debug FTDI/JTAG.TMS")
			(pinfunction "TMS_0")
			(pintype "bidirectional")
			(die_length 12.891)
		)
		(pad "N9" smd circle
			(at -4.5 -0.5 180)
			(size 0.5 0.5)
			(layers "F.Cu" "F.Mask" "F.Paste")
			(net 227 "+1V0")
			(pinfunction "VCCINT")
			(pintype "passive")
		)
		(pad "N10" smd circle
			(at -3.5 -0.5 180)
			(size 0.5 0.5)
			(layers "F.Cu" "F.Mask" "F.Paste")
			(net 1 "GND")
			(pinfunction "GND")
			(pintype "passive")
		)
		(pad "N11" smd circle
			(at -2.5 -0.5 180)
			(size 0.5 0.5)
			(layers "F.Cu" "F.Mask" "F.Paste")
			(net 1 "GND")
			(pinfunction "VREFN_0")
			(pintype "bidirectional")
			(die_length 14.753)
		)
		(pad "N12" smd circle
			(at -1.5 -0.5 180)
			(size 0.5 0.5)
			(layers "F.Cu" "F.Mask" "F.Paste")
			(net 1 "GND")
			(pinfunction "VP_0")
			(pintype "bidirectional")
			(die_length 12.915)
		)
		(pad "N13" smd circle
			(at -0.5 -0.5 180)
			(size 0.5 0.5)
			(layers "F.Cu" "F.Mask" "F.Paste")
			(net 227 "+1V0")
			(pinfunction "VCCBRAM")
			(pintype "power_in")
		)
		(pad "N14" smd circle
			(at 0.499 -0.5 180)
			(size 0.5 0.5)
			(layers "F.Cu" "F.Mask" "F.Paste")
			(net 1 "GND")
			(pinfunction "GND")
			(pintype "passive")
		)
		(pad "N15" smd circle
			(at 1.499 -0.5 180)
			(size 0.5 0.5)
			(layers "F.Cu" "F.Mask" "F.Paste")
			(net 227 "+1V0")
			(pinfunction "VCCINT")
			(pintype "passive")
		)
		(pad "N16" smd circle
			(at 2.499 -0.5 180)
			(size 0.5 0.5)
			(layers "F.Cu" "F.Mask" "F.Paste")
			(net 527 "unconnected-(U4B-IO_0_13-PadN16)")
			(pinfunction "IO_0_13")
			(pintype "bidirectional+no_connect")
			(die_length 6.733)
		)
		(pad "N17" smd circle
			(at 3.499 -0.5 180)
			(size 0.5 0.5)
			(layers "F.Cu" "F.Mask" "F.Paste")
			(net 528 "unconnected-(U4B-IO_L20N_T3_13-PadN17)")
			(pinfunction "IO_L20N_T3_13")
			(pintype "bidirectional+no_connect")
			(die_length 9.445)
		)
		(pad "N18" smd circle
			(at 4.499 -0.5 180)
			(size 0.5 0.5)
			(layers "F.Cu" "F.Mask" "F.Paste")
			(net 529 "unconnected-(U4B-IO_L22P_T3_13-PadN18)")
			(pinfunction "IO_L22P_T3_13")
			(pintype "bidirectional+no_connect")
			(die_length 11.191)
		)
		(pad "N19" smd circle
			(at 5.499 -0.5 180)
			(size 0.5 0.5)
			(layers "F.Cu" "F.Mask" "F.Paste")
			(net 530 "unconnected-(U4B-IO_L7P_T1_13-PadN19)")
			(pinfunction "IO_L7P_T1_13")
			(pintype "bidirectional+no_connect")
			(die_length 10.696)
		)
		(pad "N20" smd circle
			(at 6.499 -0.5 180)
			(size 0.5 0.5)
			(layers "F.Cu" "F.Mask" "F.Paste")
			(net 1 "GND")
			(pinfunction "GND")
			(pintype "passive")
		)
		(pad "N21" smd circle
			(at 7.499 -0.5 180)
			(size 0.5 0.5)
			(layers "F.Cu" "F.Mask" "F.Paste")
			(net 531 "unconnected-(U4B-IO_L12P_T1_MRCC_13-PadN21)")
			(pinfunction "IO_L12P_T1_MRCC_13")
			(pintype "bidirectional+no_connect")
			(die_length 11.848)
		)
		(pad "N22" smd circle
			(at 8.499 -0.5 180)
			(size 0.5 0.5)
			(layers "F.Cu" "F.Mask" "F.Paste")
			(net 532 "unconnected-(U4B-IO_L12N_T1_MRCC_13-PadN22)")
			(pinfunction "IO_L12N_T1_MRCC_13")
			(pintype "bidirectional+no_connect")
			(die_length 12.32)
		)
		(pad "N23" smd circle
			(at 9.499 -0.5 180)
			(size 0.5 0.5)
			(layers "F.Cu" "F.Mask" "F.Paste")
			(net 533 "unconnected-(U4B-IO_L11N_T1_SRCC_13-PadN23)")
			(pinfunction "IO_L11N_T1_SRCC_13")
			(pintype "bidirectional+no_connect")
			(die_length 14.434)
		)
		(pad "N24" smd circle
			(at 10.499 -0.5 180)
			(size 0.5 0.5)
			(layers "F.Cu" "F.Mask" "F.Paste")
			(net 534 "unconnected-(U4B-IO_L4N_T0_13-PadN24)")
			(pinfunction "IO_L4N_T0_13")
			(pintype "bidirectional+no_connect")
			(die_length 15.311)
		)
		(pad "N25" smd circle
			(at 11.499 -0.5 180)
			(size 0.5 0.5)
			(layers "F.Cu" "F.Mask" "F.Paste")
			(net 376 "Net-(R96-Pad2)")
			(pinfunction "VCCO_13")
			(pintype "passive")
		)
		(pad "N26" smd circle
			(at 12.499 -0.5 180)
			(size 0.5 0.5)
			(layers "F.Cu" "F.Mask" "F.Paste")
			(net 535 "unconnected-(U4B-IO_L5P_T0_13-PadN26)")
			(pinfunction "IO_L5P_T0_13")
			(pintype "bidirectional+no_connect")
			(die_length 16.049)
		)
		(pad "P1" smd circle
			(at -12.5 0.499 180)
			(size 0.5 0.5)
			(layers "F.Cu" "F.Mask" "F.Paste")
			(net 536 "unconnected-(U4I-MGTXTXN0_115-PadP1)")
			(pinfunction "MGTXTXN0_115")
			(pintype "bidirectional+no_connect")
			(die_length 14.843)
		)
		(pad "P2" smd circle
			(at -11.5 0.499 180)
			(size 0.5 0.5)
			(layers "F.Cu" "F.Mask" "F.Paste")
			(net 537 "unconnected-(U4I-MGTXTXP0_115-PadP2)")
			(pinfunction "MGTXTXP0_115")
			(pintype "bidirectional+no_connect")
			(die_length 15.009)
		)
		(pad "P3" smd circle
			(at -10.5 0.499 180)
			(size 0.5 0.5)
			(layers "F.Cu" "F.Mask" "F.Paste")
			(net 1 "GND")
			(pinfunction "GND")
			(pintype "passive")
		)
		(pad "P4" smd circle
			(at -9.5 0.499 180)
			(size 0.5 0.5)
			(layers "F.Cu" "F.Mask" "F.Paste")
			(net 1 "GND")
			(pinfunction "GND")
			(pintype "passive")
		)
		(pad "P5" smd circle
			(at -8.5 0.499 180)
			(size 0.5 0.5)
			(layers "F.Cu" "F.Mask" "F.Paste")
			(net 631 "/FPGA Config/MODE2")
			(pinfunction "M2_0")
			(pintype "bidirectional")
			(die_length 16.743)
		)
		(pad "P6" smd circle
			(at -7.5 0.499 180)
			(size 0.5 0.5)
			(layers "F.Cu" "F.Mask" "F.Paste")
			(net 634 "/FPGA Config/PROGRAM_B")
			(pinfunction "PROGRAM_B_0")
			(pintype "bidirectional")
			(die_length 16.276)
		)
		(pad "P7" smd circle
			(at -6.5 0.499 180)
			(size 0.5 0.5)
			(layers "F.Cu" "F.Mask" "F.Paste")
			(net 635 "/FPGA Config/CFGBVS")
			(pinfunction "CFGBVS_0")
			(pintype "bidirectional")
			(die_length 14.171)
		)
		(pad "P8" smd circle
			(at -5.5 0.499 180)
			(size 0.5 0.5)
			(layers "F.Cu" "F.Mask" "F.Paste")
			(net 188 "+1V8")
			(pinfunction "VCCAUX_IO_G0")
			(pintype "power_in")
		)
		(pad "P9" smd circle
			(at -4.5 0.499 180)
			(size 0.5 0.5)
			(layers "F.Cu" "F.Mask" "F.Paste")
			(net 1 "GND")
			(pinfunction "GND")
			(pintype "passive")
		)
		(pad "P10" smd circle
			(at -3.5 0.499 180)
			(size 0.5 0.5)
			(layers "F.Cu" "F.Mask" "F.Paste")
			(net 188 "+1V8")
			(pinfunction "VCCAUX")
			(pintype "passive")
		)
		(pad "P11" smd circle
			(at -2.5 0.499 180)
			(size 0.5 0.5)
			(layers "F.Cu" "F.Mask" "F.Paste")
			(net 1 "GND")
			(pinfunction "VN_0")
			(pintype "bidirectional")
			(die_length 13.84)
		)
		(pad "P12" smd circle
			(at -1.5 0.499 180)
			(size 0.5 0.5)
			(layers "F.Cu" "F.Mask" "F.Paste")
			(net 1 "GND")
			(pinfunction "VREFP_0")
			(pintype "bidirectional")
			(die_length 12.633)
		)
		(pad "P13" smd circle
			(at -0.5 0.499 180)
			(size 0.5 0.5)
			(layers "F.Cu" "F.Mask" "F.Paste")
			(net 1 "GND")
			(pinfunction "GND")
			(pintype "passive")
		)
		(pad "P14" smd circle
			(at 0.499 0.499 180)
			(size 0.5 0.5)
			(layers "F.Cu" "F.Mask" "F.Paste")
			(net 227 "+1V0")
			(pinfunction "VCCINT")
			(pintype "passive")
		)
		(pad "P15" smd circle
			(at 1.499 0.499 180)
			(size 0.5 0.5)
			(layers "F.Cu" "F.Mask" "F.Paste")
			(net 1 "GND")
			(pinfunction "GND")
			(pintype "passive")
		)
		(pad "P16" smd circle
			(at 2.499 0.499 180)
			(size 0.5 0.5)
			(layers "F.Cu" "F.Mask" "F.Paste")
			(net 538 "unconnected-(U4B-IO_L20P_T3_13-PadP16)")
			(pinfunction "IO_L20P_T3_13")
			(pintype "bidirectional+no_connect")
			(die_length 8.016)
		)
		(pad "P17" smd circle
			(at 3.499 0.499 180)
			(size 0.5 0.5)
			(layers "F.Cu" "F.Mask" "F.Paste")
			(net 1 "GND")
			(pinfunction "GND")
			(pintype "passive")
		)
		(pad "P18" smd circle
			(at 4.499 0.499 180)
			(size 0.5 0.5)
			(layers "F.Cu" "F.Mask" "F.Paste")
			(net 539 "unconnected-(U4B-IO_L24N_T3_13-PadP18)")
			(pinfunction "IO_L24N_T3_13")
			(pintype "bidirectional+no_connect")
			(die_length 10.217)
		)
		(pad "P19" smd circle
			(at 5.499 0.499 180)
			(size 0.5 0.5)
			(layers "F.Cu" "F.Mask" "F.Paste")
			(net 540 "unconnected-(U4B-IO_L9P_T1_DQS_13-PadP19)")
			(pinfunction "IO_L9P_T1_DQS_13")
			(pintype "bidirectional+no_connect")
			(die_length 12.118)
		)
		(pad "P20" smd circle
			(at 6.499 0.499 180)
			(size 0.5 0.5)
			(layers "F.Cu" "F.Mask" "F.Paste")
			(net 541 "unconnected-(U4B-IO_L9N_T1_DQS_13-PadP20)")
			(pinfunction "IO_L9N_T1_DQS_13")
			(pintype "bidirectional+no_connect")
			(die_length 12.121)
		)
		(pad "P21" smd circle
			(at 7.499 0.499 180)
			(size 0.5 0.5)
			(layers "F.Cu" "F.Mask" "F.Paste")
			(net 542 "unconnected-(U4B-IO_L13N_T2_MRCC_13-PadP21)")
			(pinfunction "IO_L13N_T2_MRCC_13")
			(pintype "bidirectional+no_connect")
			(die_length 10.375)
		)
		(pad "P22" smd circle
			(at 8.499 0.499 180)
			(size 0.5 0.5)
			(layers "F.Cu" "F.Mask" "F.Paste")
			(net 376 "Net-(R96-Pad2)")
			(pinfunction "VCCO_13")
			(pintype "passive")
		)
		(pad "P23" smd circle
			(at 9.499 0.499 180)
			(size 0.5 0.5)
			(layers "F.Cu" "F.Mask" "F.Paste")
			(net 543 "unconnected-(U4B-IO_L11P_T1_SRCC_13-PadP23)")
			(pinfunction "IO_L11P_T1_SRCC_13")
			(pintype "bidirectional+no_connect")
			(die_length 14.144)
		)
		(pad "P24" smd circle
			(at 10.499 0.499 180)
			(size 0.5 0.5)
			(layers "F.Cu" "F.Mask" "F.Paste")
			(net 544 "unconnected-(U4B-IO_L4P_T0_13-PadP24)")
			(pinfunction "IO_L4P_T0_13")
			(pintype "bidirectional+no_connect")
			(die_length 13.362)
		)
		(pad "P25" smd circle
			(at 11.499 0.499 180)
			(size 0.5 0.5)
			(layers "F.Cu" "F.Mask" "F.Paste")
			(net 545 "unconnected-(U4B-IO_L6N_T0_VREF_13-PadP25)")
			(pinfunction "IO_L6N_T0_VREF_13")
			(pintype "bidirectional+no_connect")
			(die_length 14.662)
		)
		(pad "P26" smd circle
			(at 12.499 0.499 180)
			(size 0.5 0.5)
			(layers "F.Cu" "F.Mask" "F.Paste")
			(net 546 "unconnected-(U4B-IO_L2N_T0_13-PadP26)")
			(pinfunction "IO_L2N_T0_13")
			(pintype "bidirectional+no_connect")
			(die_length 17.56)
		)
		(pad "R1" smd circle
			(at -12.5 1.499 180)
			(size 0.5 0.5)
			(layers "F.Cu" "F.Mask" "F.Paste")
			(net 1 "GND")
			(pinfunction "GND")
			(pintype "passive")
		)
		(pad "R2" smd circle
			(at -11.5 1.499 180)
			(size 0.5 0.5)
			(layers "F.Cu" "F.Mask" "F.Paste")
			(net 1 "GND")
			(pinfunction "GND")
			(pintype "passive")
		)
		(pad "R3" smd circle
			(at -10.5 1.499 180)
			(size 0.5 0.5)
			(layers "F.Cu" "F.Mask" "F.Paste")
			(net 547 "unconnected-(U4I-MGTXRXN0_115-PadR3)")
			(pinfunction "MGTXRXN0_115")
			(pintype "bidirectional+no_connect")
			(die_length 13.691)
		)
		(pad "R4" smd circle
			(at -9.5 1.499 180)
			(size 0.5 0.5)
			(layers "F.Cu" "F.Mask" "F.Paste")
			(net 548 "unconnected-(U4I-MGTXRXP0_115-PadR4)")
			(pinfunction "MGTXRXP0_115")
			(pintype "bidirectional+no_connect")
			(die_length 13.771)
		)
		(pad "R5" smd circle
			(at -8.5 1.499 180)
			(size 0.5 0.5)
			(layers "F.Cu" "F.Mask" "F.Paste")
			(net 1 "GND")
			(pinfunction "GND")
			(pintype "passive")
		)
		(pad "R6" smd circle
			(at -7.5 1.499 180)
			(size 0.5 0.5)
			(layers "F.Cu" "F.Mask" "F.Paste")
			(net 48 "/Debug FTDI/JTAG.TDI")
			(pinfunction "TDI_0")
			(pintype "bidirectional")
			(die_length 16.338)
		)
		(pad "R7" smd circle
			(at -6.5 1.499 180)
			(size 0.5 0.5)
			(layers "F.Cu" "F.Mask" "F.Paste")
			(net 47 "/Debug FTDI/JTAG.TDO")
			(pinfunction "TDO_0")
			(pintype "bidirectional")
			(die_length 15.018)
		)
		(pad "R8" smd circle
			(at -5.5 1.499 180)
			(size 0.5 0.5)
			(layers "F.Cu" "F.Mask" "F.Paste")
			(net 1 "GND")
			(pinfunction "GND")
			(pintype "passive")
		)
		(pad "R9" smd circle
			(at -4.5 1.499 180)
			(size 0.5 0.5)
			(layers "F.Cu" "F.Mask" "F.Paste")
			(net 188 "+1V8")
			(pinfunction "VCCAUX_IO_G0")
			(pintype "passive")
		)
		(pad "R10" smd circle
			(at -3.5 1.499 180)
			(size 0.5 0.5)
			(layers "F.Cu" "F.Mask" "F.Paste")
			(net 1 "GND")
			(pinfunction "GND")
			(pintype "passive")
		)
		(pad "R11" smd circle
			(at -2.5 1.499 180)
			(size 0.5 0.5)
			(layers "F.Cu" "F.Mask" "F.Paste")
			(net 1 "GND")
			(pinfunction "DXN_0")
			(pintype "bidirectional")
			(die_length 14.9)
		)
		(pad "R12" smd circle
			(at -1.5 1.499 180)
			(size 0.5 0.5)
			(layers "F.Cu" "F.Mask" "F.Paste")
			(net 1 "GND")
			(pinfunction "DXP_0")
			(pintype "bidirectional")
			(die_length 12.842)
		)
		(pad "R13" smd circle
			(at -0.5 1.499 180)
			(size 0.5 0.5)
			(layers "F.Cu" "F.Mask" "F.Paste")
			(net 227 "+1V0")
			(pinfunction "VCCBRAM")
			(pintype "passive")
		)
		(pad "R14" smd circle
			(at 0.499 1.499 180)
			(size 0.5 0.5)
			(layers "F.Cu" "F.Mask" "F.Paste")
			(net 1 "GND")
			(pinfunction "GND")
			(pintype "passive")
		)
		(pad "R15" smd circle
			(at 1.499 1.499 180)
			(size 0.5 0.5)
			(layers "F.Cu" "F.Mask" "F.Paste")
			(net 227 "+1V0")
			(pinfunction "VCCINT")
			(pintype "passive")
		)
		(pad "R16" smd circle
			(at 2.499 1.499 180)
			(size 0.5 0.5)
			(layers "F.Cu" "F.Mask" "F.Paste")
			(net 549 "unconnected-(U4B-IO_L21P_T3_DQS_13-PadR16)")
			(pinfunction "IO_L21P_T3_DQS_13")
			(pintype "bidirectional+no_connect")
			(die_length 10.096)
		)
		(pad "R17" smd circle
			(at 3.499 1.499 180)
			(size 0.5 0.5)
			(layers "F.Cu" "F.Mask" "F.Paste")
			(net 550 "unconnected-(U4B-IO_L21N_T3_DQS_13-PadR17)")
			(pinfunction "IO_L21N_T3_DQS_13")
			(pintype "bidirectional+no_connect")
			(die_length 10.012)
		)
		(pad "R18" smd circle
			(at 4.499 1.499 180)
			(size 0.5 0.5)
			(layers "F.Cu" "F.Mask" "F.Paste")
			(net 551 "unconnected-(U4B-IO_L24P_T3_13-PadR18)")
			(pinfunction "IO_L24P_T3_13")
			(pintype "bidirectional+no_connect")
			(die_length 8.982)
		)
		(pad "R19" smd circle
			(at 5.499 1.499 180)
			(size 0.5 0.5)
			(layers "F.Cu" "F.Mask" "F.Paste")
			(net 376 "Net-(R96-Pad2)")
			(pinfunction "VCCO_13")
			(pintype "passive")
		)
		(pad "R20" smd circle
			(at 6.499 1.499 180)
			(size 0.5 0.5)
			(layers "F.Cu" "F.Mask" "F.Paste")
			(net 552 "unconnected-(U4B-IO_L16N_T2_13-PadR20)")
			(pinfunction "IO_L16N_T2_13")
			(pintype "bidirectional+no_connect")
			(die_length 9.979)
		)
		(pad "R21" smd circle
			(at 7.499 1.499 180)
			(size 0.5 0.5)
			(layers "F.Cu" "F.Mask" "F.Paste")
			(net 553 "unconnected-(U4B-IO_L13P_T2_MRCC_13-PadR21)")
			(pinfunction "IO_L13P_T2_MRCC_13")
			(pintype "bidirectional+no_connect")
			(die_length 10.23)
		)
		(pad "R22" smd circle
			(at 8.499 1.499 180)
			(size 0.5 0.5)
			(layers "F.Cu" "F.Mask" "F.Paste")
			(net 554 "unconnected-(U4B-IO_L14P_T2_SRCC_13-PadR22)")
			(pinfunction "IO_L14P_T2_SRCC_13")
			(pintype "bidirectional+no_connect")
			(die_length 11.973)
		)
		(pad "R23" smd circle
			(at 9.499 1.499 180)
			(size 0.5 0.5)
			(layers "F.Cu" "F.Mask" "F.Paste")
			(net 555 "unconnected-(U4B-IO_L14N_T2_SRCC_13-PadR23)")
			(pinfunction "IO_L14N_T2_SRCC_13")
			(pintype "bidirectional+no_connect")
			(die_length 12.182)
		)
		(pad "R24" smd circle
			(at 10.499 1.499 180)
			(size 0.5 0.5)
			(layers "F.Cu" "F.Mask" "F.Paste")
			(net 1 "GND")
			(pinfunction "GND")
			(pintype "passive")
		)
		(pad "R25" smd circle
			(at 11.499 1.499 180)
			(size 0.5 0.5)
			(layers "F.Cu" "F.Mask" "F.Paste")
			(net 556 "unconnected-(U4B-IO_L6P_T0_13-PadR25)")
			(pinfunction "IO_L6P_T0_13")
			(pintype "bidirectional+no_connect")
			(die_length 14.416)
		)
		(pad "R26" smd circle
			(at 12.499 1.499 180)
			(size 0.5 0.5)
			(layers "F.Cu" "F.Mask" "F.Paste")
			(net 557 "unconnected-(U4B-IO_L2P_T0_13-PadR26)")
			(pinfunction "IO_L2P_T0_13")
			(pintype "bidirectional+no_connect")
			(die_length 16.3)
		)
		(pad "T1" smd circle
			(at -12.5 2.499 180)
			(size 0.5 0.5)
			(layers "F.Cu" "F.Mask" "F.Paste")
			(net 1 "GND")
			(pinfunction "GND")
			(pintype "passive")
		)
		(pad "T2" smd circle
			(at -11.5 2.499 180)
			(size 0.5 0.5)
			(layers "F.Cu" "F.Mask" "F.Paste")
			(net 632 "/FPGA Config/MODE1")
			(pinfunction "M1_0")
			(pintype "bidirectional")
			(die_length 22.574)
		)
		(pad "T3" smd circle
			(at -10.5 2.499 180)
			(size 0.5 0.5)
			(layers "F.Cu" "F.Mask" "F.Paste")
			(net 1 "GND")
			(pinfunction "GND")
			(pintype "passive")
		)
		(pad "T4" smd circle
			(at -9.5 2.499 180)
			(size 0.5 0.5)
			(layers "F.Cu" "F.Mask" "F.Paste")
			(net 1 "GND")
			(pinfunction "GND")
			(pintype "passive")
		)
		(pad "T5" smd circle
			(at -8.5 2.499 180)
			(size 0.5 0.5)
			(layers "F.Cu" "F.Mask" "F.Paste")
			(net 633 "/FPGA Config/MODE0")
			(pinfunction "M0_0")
			(pintype "bidirectional")
			(die_length 20.855)
		)
		(pad "T6" smd circle
			(at -7.5 2.499 180)
			(size 0.5 0.5)
			(layers "F.Cu" "F.Mask" "F.Paste")
			(net 200 "+3V3")
			(pinfunction "VCCO_0")
			(pintype "passive")
		)
		(pad "T7" smd circle
			(at -6.5 2.499 180)
			(size 0.5 0.5)
			(layers "F.Cu" "F.Mask" "F.Paste")
			(net 193 "/DDR5 SODIMM/B.CB3")
			(pinfunction "IO_25_VRP_34")
			(pintype "bidirectional")
			(die_length 9.857)
		)
		(pad "T8" smd circle
			(at -5.5 2.499 180)
			(size 0.5 0.5)
			(layers "F.Cu" "F.Mask" "F.Paste")
			(net 188 "+1V8")
			(pinfunction "VCCAUX_IO_G0")
			(pintype "passive")
		)
		(pad "T9" smd circle
			(at -4.5 2.499 180)
			(size 0.5 0.5)
			(layers "F.Cu" "F.Mask" "F.Paste")
			(net 1 "GND")
			(pinfunction "GND")
			(pintype "passive")
		)
		(pad "T10" smd circle
			(at -3.5 2.499 180)
			(size 0.5 0.5)
			(layers "F.Cu" "F.Mask" "F.Paste")
			(net 188 "+1V8")
			(pinfunction "VCCAUX")
			(pintype "passive")
		)
		(pad "T11" smd circle
			(at -2.5 2.499 180)
			(size 0.5 0.5)
			(layers "F.Cu" "F.Mask" "F.Paste")
			(net 1 "GND")
			(pinfunction "GND")
			(pintype "passive")
		)
		(pad "T12" smd circle
			(at -1.5 2.499 180)
			(size 0.5 0.5)
			(layers "F.Cu" "F.Mask" "F.Paste")
			(net 227 "+1V0")
			(pinfunction "VCCBRAM")
			(pintype "passive")
		)
		(pad "T13" smd circle
			(at -0.5 2.499 180)
			(size 0.5 0.5)
			(layers "F.Cu" "F.Mask" "F.Paste")
			(net 1 "GND")
			(pinfunction "GND")
			(pintype "passive")
		)
		(pad "T14" smd circle
			(at 0.499 2.499 180)
			(size 0.5 0.5)
			(layers "F.Cu" "F.Mask" "F.Paste")
			(net 227 "+1V0")
			(pinfunction "VCCINT")
			(pintype "passive")
		)
		(pad "T15" smd circle
			(at 1.499 2.499 180)
			(size 0.5 0.5)
			(layers "F.Cu" "F.Mask" "F.Paste")
			(net 1 "GND")
			(pinfunction "GND")
			(pintype "passive")
		)
		(pad "T16" smd circle
			(at 2.499 2.499 180)
			(size 0.5 0.5)
			(layers "F.Cu" "F.Mask" "F.Paste")
			(net 376 "Net-(R96-Pad2)")
			(pinfunction "VCCO_13")
			(pintype "passive")
		)
		(pad "T17" smd circle
			(at 3.499 2.499 180)
			(size 0.5 0.5)
			(layers "F.Cu" "F.Mask" "F.Paste")
			(net 558 "unconnected-(U4B-IO_L23N_T3_13-PadT17)")
			(pinfunction "IO_L23N_T3_13")
			(pintype "bidirectional+no_connect")
			(die_length 10.353)
		)
		(pad "T18" smd circle
			(at 4.499 2.499 180)
			(size 0.5 0.5)
			(layers "F.Cu" "F.Mask" "F.Paste")
			(net 559 "unconnected-(U4B-IO_L19P_T3_13-PadT18)")
			(pinfunction "IO_L19P_T3_13")
			(pintype "bidirectional+no_connect")
			(die_length 9.92)
		)
		(pad "T19" smd circle
			(at 5.499 2.499 180)
			(size 0.5 0.5)
			(layers "F.Cu" "F.Mask" "F.Paste")
			(net 560 "unconnected-(U4B-IO_L19N_T3_VREF_13-PadT19)")
			(pinfunction "IO_L19N_T3_VREF_13")
			(pintype "bidirectional+no_connect")
			(die_length 9.055)
		)
		(pad "T20" smd circle
			(at 6.499 2.499 180)
			(size 0.5 0.5)
			(layers "F.Cu" "F.Mask" "F.Paste")
			(net 561 "unconnected-(U4B-IO_L16P_T2_13-PadT20)")
			(pinfunction "IO_L16P_T2_13")
			(pintype "bidirectional+no_connect")
			(die_length 9.491)
		)
		(pad "T21" smd circle
			(at 7.499 2.499 180)
			(size 0.5 0.5)
			(layers "F.Cu" "F.Mask" "F.Paste")
			(net 1 "GND")
			(pinfunction "GND")
			(pintype "passive")
		)
		(pad "T22" smd circle
			(at 8.499 2.499 180)
			(size 0.5 0.5)
			(layers "F.Cu" "F.Mask" "F.Paste")
			(net 562 "unconnected-(U4B-IO_L17P_T2_13-PadT22)")
			(pinfunction "IO_L17P_T2_13")
			(pintype "bidirectional+no_connect")
			(die_length 11.169)
		)
		(pad "T23" smd circle
			(at 9.499 2.499 180)
			(size 0.5 0.5)
			(layers "F.Cu" "F.Mask" "F.Paste")
			(net 563 "unconnected-(U4B-IO_L17N_T2_13-PadT23)")
			(pinfunction "IO_L17N_T2_13")
			(pintype "bidirectional+no_connect")
			(die_length 11.495)
		)
		(pad "T24" smd circle
			(at 10.499 2.499 180)
			(size 0.5 0.5)
			(layers "F.Cu" "F.Mask" "F.Paste")
			(net 564 "unconnected-(U4B-IO_L15P_T2_DQS_13-PadT24)")
			(pinfunction "IO_L15P_T2_DQS_13")
			(pintype "bidirectional+no_connect")
			(die_length 13.293)
		)
		(pad "T25" smd circle
			(at 11.499 2.499 180)
			(size 0.5 0.5)
			(layers "F.Cu" "F.Mask" "F.Paste")
			(net 565 "unconnected-(U4B-IO_L15N_T2_DQS_13-PadT25)")
			(pinfunction "IO_L15N_T2_DQS_13")
			(pintype "bidirectional+no_connect")
			(die_length 13.562)
		)
		(pad "T26" smd circle
			(at 12.499 2.499 180)
			(size 0.5 0.5)
			(layers "F.Cu" "F.Mask" "F.Paste")
			(net 376 "Net-(R96-Pad2)")
			(pinfunction "VCCO_13")
			(pintype "passive")
		)
		(pad "U1" smd circle
			(at -12.5 3.499 180)
			(size 0.5 0.5)
			(layers "F.Cu" "F.Mask" "F.Paste")
			(net 284 "/DDR5 SODIMM/B.~{DM3}")
			(pinfunction "IO_L2N_T0_34")
			(pintype "bidirectional")
			(die_length 17.749)
		)
		(pad "U2" smd circle
			(at -11.5 3.499 180)
			(size 0.5 0.5)
			(layers "F.Cu" "F.Mask" "F.Paste")
			(net 275 "/DDR5 SODIMM/B.DQ24")
			(pinfunction "IO_L2P_T0_34")
			(pintype "bidirectional")
			(die_length 16.314)
		)
		(pad "U3" smd circle
			(at -10.5 3.499 180)
			(size 0.5 0.5)
			(layers "F.Cu" "F.Mask" "F.Paste")
			(net 206 "+1V1")
			(pinfunction "VCCO_34")
			(pintype "passive")
		)
		(pad "U4" smd circle
			(at -9.5 3.499 180)
			(size 0.5 0.5)
			(layers "F.Cu" "F.Mask" "F.Paste")
			(net 192 "/DDR5 SODIMM/B.CB1")
			(pinfunction "IO_0_VRN_34")
			(pintype "bidirectional")
			(die_length 17.697)
		)
		(pad "U5" smd circle
			(at -8.5 3.499 180)
			(size 0.5 0.5)
			(layers "F.Cu" "F.Mask" "F.Paste")
			(net 287 "/DDR5 SODIMM/B.DQ29")
			(pinfunction "IO_L1N_T0_34")
			(pintype "bidirectional")
			(die_length 13.682)
		)
		(pad "U6" smd circle
			(at -7.5 3.499 180)
			(size 0.5 0.5)
			(layers "F.Cu" "F.Mask" "F.Paste")
			(net 286 "/DDR5 SODIMM/B.DQ28")
			(pinfunction "IO_L1P_T0_34")
			(pintype "bidirectional")
			(die_length 13.683)
		)
		(pad "U7" smd circle
			(at -6.5 3.499 180)
			(size 0.5 0.5)
			(layers "F.Cu" "F.Mask" "F.Paste")
			(net 289 "/DDR5 SODIMM/B.DQ31")
			(pinfunction "IO_L5P_T0_34")
			(pintype "bidirectional")
			(die_length 12.718)
		)
		(pad "U8" smd circle
			(at -5.5 3.499 180)
			(size 0.5 0.5)
			(layers "F.Cu" "F.Mask" "F.Paste")
			(net 1 "GND")
			(pinfunction "GND")
			(pintype "passive")
		)
		(pad "U9" smd circle
			(at -4.5 3.499 180)
			(size 0.5 0.5)
			(layers "F.Cu" "F.Mask" "F.Paste")
			(net 684 "/FPGA banks HP/VRN")
			(pinfunction "IO_0_VRN_33")
			(pintype "bidirectional")
			(die_length 7.601)
		)
		(pad "U10" smd circle
			(at -3.5 3.499 180)
			(size 0.5 0.5)
			(layers "F.Cu" "F.Mask" "F.Paste")
			(net 1 "GND")
			(pinfunction "GND")
			(pintype "passive")
		)
		(pad "U11" smd circle
			(at -2.5 3.499 180)
			(size 0.5 0.5)
			(layers "F.Cu" "F.Mask" "F.Paste")
			(net 188 "+1V8")
			(pinfunction "VCCAUX")
			(pintype "passive")
		)
		(pad "U12" smd circle
			(at -1.5 3.499 180)
			(size 0.5 0.5)
			(layers "F.Cu" "F.Mask" "F.Paste")
			(net 1 "GND")
			(pinfunction "GND")
			(pintype "passive")
		)
		(pad "U13" smd circle
			(at -0.5 3.499 180)
			(size 0.5 0.5)
			(layers "F.Cu" "F.Mask" "F.Paste")
			(net 227 "+1V0")
			(pinfunction "VCCBRAM")
			(pintype "passive")
		)
		(pad "U14" smd circle
			(at 0.499 3.499 180)
			(size 0.5 0.5)
			(layers "F.Cu" "F.Mask" "F.Paste")
			(net 1 "GND")
			(pinfunction "GND")
			(pintype "passive")
		)
		(pad "U15" smd circle
			(at 1.499 3.499 180)
			(size 0.5 0.5)
			(layers "F.Cu" "F.Mask" "F.Paste")
			(net 227 "+1V0")
			(pinfunction "VCCINT")
			(pintype "passive")
		)
		(pad "U16" smd circle
			(at 2.499 3.499 180)
			(size 0.5 0.5)
			(layers "F.Cu" "F.Mask" "F.Paste")
			(net 566 "unconnected-(U4B-IO_25_13-PadU16)")
			(pinfunction "IO_25_13")
			(pintype "bidirectional+no_connect")
			(die_length 9.654)
		)
		(pad "U17" smd circle
			(at 3.499 3.499 180)
			(size 0.5 0.5)
			(layers "F.Cu" "F.Mask" "F.Paste")
			(net 567 "unconnected-(U4B-IO_L23P_T3_13-PadU17)")
			(pinfunction "IO_L23P_T3_13")
			(pintype "bidirectional+no_connect")
			(die_length 11.04)
		)
		(pad "U18" smd circle
			(at 4.499 3.499 180)
			(size 0.5 0.5)
			(layers "F.Cu" "F.Mask" "F.Paste")
			(net 1 "GND")
			(pinfunction "GND")
			(pintype "passive")
		)
		(pad "U19" smd circle
			(at 5.499 3.499 180)
			(size 0.5 0.5)
			(layers "F.Cu" "F.Mask" "F.Paste")
			(net 568 "unconnected-(U4B-IO_L18P_T2_13-PadU19)")
			(pinfunction "IO_L18P_T2_13")
			(pintype "bidirectional+no_connect")
			(die_length 8.112)
		)
		(pad "U20" smd circle
			(at 6.499 3.499 180)
			(size 0.5 0.5)
			(layers "F.Cu" "F.Mask" "F.Paste")
			(net 569 "unconnected-(U4B-IO_L18N_T2_13-PadU20)")
			(pinfunction "IO_L18N_T2_13")
			(pintype "bidirectional+no_connect")
			(die_length 9.928)
		)
		(pad "U21" smd circle
			(at 7.499 3.499 180)
			(size 0.5 0.5)
			(layers "F.Cu" "F.Mask" "F.Paste")
			(net 570 "unconnected-(U4A-IO_0_12-PadU21)")
			(pinfunction "IO_0_12")
			(pintype "bidirectional+no_connect")
			(die_length 9.631)
		)
		(pad "U22" smd circle
			(at 8.499 3.499 180)
			(size 0.5 0.5)
			(layers "F.Cu" "F.Mask" "F.Paste")
			(net 573 "unconnected-(U4A-IO_L1P_T0_12-PadU22)")
			(pinfunction "IO_L1P_T0_12")
			(pintype "bidirectional+no_connect")
			(die_length 10.705)
		)
		(pad "U23" smd circle
			(at 9.499 3.499 180)
			(size 0.5 0.5)
			(layers "F.Cu" "F.Mask" "F.Paste")
			(net 200 "+3V3")
			(pinfunction "VCCO_12")
			(pintype "passive")
		)
		(pad "U24" smd circle
			(at 10.499 3.499 180)
			(size 0.5 0.5)
			(layers "F.Cu" "F.Mask" "F.Paste")
			(net 574 "unconnected-(U4A-IO_L2P_T0_12-PadU24)")
			(pinfunction "IO_L2P_T0_12")
			(pintype "bidirectional+no_connect")
			(die_length 12.37)
		)
		(pad "U25" smd circle
			(at 11.499 3.499 180)
			(size 0.5 0.5)
			(layers "F.Cu" "F.Mask" "F.Paste")
			(net 676 "/Ethernet/ETH.RXD3")
			(pinfunction "IO_L2N_T0_12")
			(pintype "bidirectional")
			(die_length 14.162)
		)
		(pad "U26" smd circle
			(at 12.499 3.499 180)
			(size 0.5 0.5)
			(layers "F.Cu" "F.Mask" "F.Paste")
			(net 732 "/Ethernet/ETH.TX_CTL")
			(pinfunction "IO_L4P_T0_12")
			(pintype "bidirectional")
			(die_length 15.43)
		)
		(pad "V1" smd circle
			(at -12.5 4.499 180)
			(size 0.5 0.5)
			(layers "F.Cu" "F.Mask" "F.Paste")
			(net 270 "/DDR5 SODIMM/B.DQ22")
			(pinfunction "IO_L8N_T1_34")
			(pintype "bidirectional")
			(die_length 17.73)
		)
		(pad "V2" smd circle
			(at -11.5 4.499 180)
			(size 0.5 0.5)
			(layers "F.Cu" "F.Mask" "F.Paste")
			(net 271 "/DDR5 SODIMM/B.DQ23")
			(pinfunction "IO_L8P_T1_34")
			(pintype "bidirectional")
			(die_length 16.717)
		)
		(pad "V3" smd circle
			(at -10.5 4.499 180)
			(size 0.5 0.5)
			(layers "F.Cu" "F.Mask" "F.Paste")
			(net 278 "/DDR5 SODIMM/B.DQ27")
			(pinfunction "IO_L4P_T0_34")
			(pintype "bidirectional")
			(die_length 16.996)
		)
		(pad "V4" smd circle
			(at -9.5 4.499 180)
			(size 0.5 0.5)
			(layers "F.Cu" "F.Mask" "F.Paste")
			(net 277 "/DDR5 SODIMM/B.DQ26")
			(pinfunction "IO_L6P_T0_34")
			(pintype "bidirectional")
			(die_length 16.475)
		)
		(pad "V5" smd circle
			(at -8.5 4.499 180)
			(size 0.5 0.5)
			(layers "F.Cu" "F.Mask" "F.Paste")
			(net 1 "GND")
			(pinfunction "GND")
			(pintype "passive")
		)
		(pad "V6" smd circle
			(at -7.5 4.499 180)
			(size 0.5 0.5)
			(layers "F.Cu" "F.Mask" "F.Paste")
			(net 288 "/DDR5 SODIMM/B.DQ30")
			(pinfunction "IO_L5N_T0_34")
			(pintype "bidirectional")
			(die_length 13.667)
		)
		(pad "V7" smd circle
			(at -6.5 4.499 180)
			(size 0.5 0.5)
			(layers "F.Cu" "F.Mask" "F.Paste")
			(net 183 "/DDR5 SODIMM/B.CA0")
			(pinfunction "IO_L2N_T0_33")
			(pintype "bidirectional")
			(die_length 12.123)
		)
		(pad "V8" smd circle
			(at -5.5 4.499 180)
			(size 0.5 0.5)
			(layers "F.Cu" "F.Mask" "F.Paste")
			(net 179 "/DDR5 SODIMM/B.CA2")
			(pinfunction "IO_L2P_T0_33")
			(pintype "bidirectional")
			(die_length 11.194)
		)
		(pad "V9" smd circle
			(at -4.5 4.499 180)
			(size 0.5 0.5)
			(layers "F.Cu" "F.Mask" "F.Paste")
			(net 178 "/DDR5 SODIMM/B.CA3")
			(pinfunction "IO_L6P_T0_33")
			(pintype "bidirectional")
			(die_length 10.483)
		)
		(pad "V10" smd circle
			(at -3.5 4.499 180)
			(size 0.5 0.5)
			(layers "F.Cu" "F.Mask" "F.Paste")
			(net 206 "+1V1")
			(pinfunction "VCCO_33")
			(pintype "passive")
		)
		(pad "V11" smd circle
			(at -2.5 4.499 180)
			(size 0.5 0.5)
			(layers "F.Cu" "F.Mask" "F.Paste")
			(net 167 "/DDR5 SODIMM/B.CA10")
			(pinfunction "IO_L1P_T0_33")
			(pintype "bidirectional")
			(die_length 9.051)
		)
		(pad "V12" smd circle
			(at -1.5 4.499 180)
			(size 0.5 0.5)
			(layers "F.Cu" "F.Mask" "F.Paste")
			(net 685 "/FPGA banks HP/VRP")
			(pinfunction "IO_25_VRP_33")
			(pintype "bidirectional")
			(die_length 8.364)
		)
		(pad "V13" smd circle
			(at -0.5 4.499 180)
			(size 0.5 0.5)
			(layers "F.Cu" "F.Mask" "F.Paste")
			(net 119 "/DDR5 SODIMM/A.CB3")
			(pinfunction "IO_0_VRN_32")
			(pintype "bidirectional")
			(die_length 8.061)
		)
		(pad "V14" smd circle
			(at 0.499 4.499 180)
			(size 0.5 0.5)
			(layers "F.Cu" "F.Mask" "F.Paste")
			(net 55 "/DDR5 SODIMM/A.DQ0")
			(pinfunction "IO_L24P_T3_32")
			(pintype "bidirectional")
			(die_length 12.558)
		)
		(pad "V15" smd circle
			(at 1.499 4.499 180)
			(size 0.5 0.5)
			(layers "F.Cu" "F.Mask" "F.Paste")
			(net 1 "GND")
			(pinfunction "GND")
			(pintype "passive")
		)
		(pad "V16" smd circle
			(at 2.499 4.499 180)
			(size 0.5 0.5)
			(layers "F.Cu" "F.Mask" "F.Paste")
			(net 57 "/DDR5 SODIMM/A.DQ1")
			(pinfunction "IO_L20P_T3_32")
			(pintype "bidirectional")
			(die_length 18.47)
		)
		(pad "V17" smd circle
			(at 3.499 4.499 180)
			(size 0.5 0.5)
			(layers "F.Cu" "F.Mask" "F.Paste")
			(net 59 "/DDR5 SODIMM/A.DQ2")
			(pinfunction "IO_L20N_T3_32")
			(pintype "bidirectional")
			(die_length 18.818)
		)
		(pad "V18" smd circle
			(at 4.499 4.499 180)
			(size 0.5 0.5)
			(layers "F.Cu" "F.Mask" "F.Paste")
			(net 61 "/DDR5 SODIMM/A.DQ3")
			(pinfunction "IO_L23P_T3_32")
			(pintype "bidirectional")
			(die_length 17.507)
		)
		(pad "V19" smd circle
			(at 5.499 4.499 180)
			(size 0.5 0.5)
			(layers "F.Cu" "F.Mask" "F.Paste")
			(net 65 "/DDR5 SODIMM/A.~{DM0}")
			(pinfunction "IO_L23N_T3_32")
			(pintype "bidirectional")
			(die_length 18.005)
		)
		(pad "V20" smd circle
			(at 6.499 4.499 180)
			(size 0.5 0.5)
			(layers "F.Cu" "F.Mask" "F.Paste")
			(net 200 "+3V3")
			(pinfunction "VCCO_12")
			(pintype "passive")
		)
		(pad "V21" smd circle
			(at 7.499 4.499 180)
			(size 0.5 0.5)
			(layers "F.Cu" "F.Mask" "F.Paste")
			(net 575 "unconnected-(U4A-IO_L6P_T0_12-PadV21)")
			(pinfunction "IO_L6P_T0_12")
			(pintype "bidirectional+no_connect")
			(die_length 8.805)
		)
		(pad "V22" smd circle
			(at 8.499 4.499 180)
			(size 0.5 0.5)
			(layers "F.Cu" "F.Mask" "F.Paste")
			(net 576 "unconnected-(U4A-IO_L1N_T0_12-PadV22)")
			(pinfunction "IO_L1N_T0_12")
			(pintype "bidirectional+no_connect")
			(die_length 10.787)
		)
		(pad "V23" smd circle
			(at 9.499 4.499 180)
			(size 0.5 0.5)
			(layers "F.Cu" "F.Mask" "F.Paste")
			(net 577 "unconnected-(U4A-IO_L3P_T0_DQS_12-PadV23)")
			(pinfunction "IO_L3P_T0_DQS_12")
			(pintype "bidirectional+no_connect")
			(die_length 12.224)
		)
		(pad "V24" smd circle
			(at 10.499 4.499 180)
			(size 0.5 0.5)
			(layers "F.Cu" "F.Mask" "F.Paste")
			(net 578 "unconnected-(U4A-IO_L3N_T0_DQS_12-PadV24)")
			(pinfunction "IO_L3N_T0_DQS_12")
			(pintype "bidirectional+no_connect")
			(die_length 12.691)
		)
		(pad "V25" smd circle
			(at 11.499 4.499 180)
			(size 0.5 0.5)
			(layers "F.Cu" "F.Mask" "F.Paste")
			(net 1 "GND")
			(pinfunction "GND")
			(pintype "passive")
		)
		(pad "V26" smd circle
			(at 12.499 4.499 180)
			(size 0.5 0.5)
			(layers "F.Cu" "F.Mask" "F.Paste")
			(net 675 "/Ethernet/ETH.RXD2")
			(pinfunction "IO_L4N_T0_12")
			(pintype "bidirectional")
			(die_length 15.219)
		)
		(pad "W1" smd circle
			(at -12.5 5.499 180)
			(size 0.5 0.5)
			(layers "F.Cu" "F.Mask" "F.Paste")
			(net 268 "/DDR5 SODIMM/B.DQ20")
			(pinfunction "IO_L10P_T1_34")
			(pintype "bidirectional")
			(die_length 18.423)
		)
		(pad "W2" smd circle
			(at -11.5 5.499 180)
			(size 0.5 0.5)
			(layers "F.Cu" "F.Mask" "F.Paste")
			(net 1 "GND")
			(pinfunction "GND")
			(pintype "passive")
		)
		(pad "W3" smd circle
			(at -10.5 5.499 180)
			(size 0.5 0.5)
			(layers "F.Cu" "F.Mask" "F.Paste")
			(net 276 "/DDR5 SODIMM/B.DQ25")
			(pinfunction "IO_L4N_T0_34")
			(pintype "bidirectional")
			(die_length 18.698)
		)
		(pad "W4" smd circle
			(at -9.5 5.499 180)
			(size 0.5 0.5)
			(layers "F.Cu" "F.Mask" "F.Paste")
			(net 10 "/FPGA banks HP/VREF")
			(pinfunction "IO_L6N_T0_VREF_34")
			(pintype "bidirectional")
			(die_length 18.8)
		)
		(pad "W5" smd circle
			(at -8.5 5.499 180)
			(size 0.5 0.5)
			(layers "F.Cu" "F.Mask" "F.Paste")
			(net 279 "/DDR5 SODIMM/B.DQS3_N")
			(pinfunction "IO_L3N_T0_DQS_34")
			(pintype "bidirectional")
			(die_length 17.539)
		)
		(pad "W6" smd circle
			(at -7.5 5.499 180)
			(size 0.5 0.5)
			(layers "F.Cu" "F.Mask" "F.Paste")
			(net 283 "/DDR5 SODIMM/B.DQS3_P")
			(pinfunction "IO_L3P_T0_DQS_34")
			(pintype "bidirectional")
			(die_length 17.741)
		)
		(pad "W7" smd circle
			(at -6.5 5.499 180)
			(size 0.5 0.5)
			(layers "F.Cu" "F.Mask" "F.Paste")
			(net 206 "+1V1")
			(pinfunction "VCCO_33")
			(pintype "passive")
		)
		(pad "W8" smd circle
			(at -5.5 5.499 180)
			(size 0.5 0.5)
			(layers "F.Cu" "F.Mask" "F.Paste")
			(net 10 "/FPGA banks HP/VREF")
			(pinfunction "IO_L6N_T0_VREF_33")
			(pintype "bidirectional")
			(die_length 12.359)
		)
		(pad "W9" smd circle
			(at -4.5 5.499 180)
			(size 0.5 0.5)
			(layers "F.Cu" "F.Mask" "F.Paste")
			(net 174 "/DDR5 SODIMM/B.CA6")
			(pinfunction "IO_L3N_T0_DQS_33")
			(pintype "bidirectional")
			(die_length 12.347)
		)
		(pad "W10" smd circle
			(at -3.5 5.499 180)
			(size 0.5 0.5)
			(layers "F.Cu" "F.Mask" "F.Paste")
			(net 166 "/DDR5 SODIMM/B.CA11")
			(pinfunction "IO_L3P_T0_DQS_33")
			(pintype "bidirectional")
			(die_length 12.577)
		)
		(pad "W11" smd circle
			(at -2.5 5.499 180)
			(size 0.5 0.5)
			(layers "F.Cu" "F.Mask" "F.Paste")
			(net 165 "/DDR5 SODIMM/B.CA12")
			(pinfunction "IO_L1N_T0_33")
			(pintype "bidirectional")
			(die_length 9.991)
		)
		(pad "W12" smd circle
			(at -1.5 5.499 180)
			(size 0.5 0.5)
			(layers "F.Cu" "F.Mask" "F.Paste")
			(net 1 "GND")
			(pinfunction "GND")
			(pintype "passive")
		)
		(pad "W13" smd circle
			(at -0.5 5.499 180)
			(size 0.5 0.5)
			(layers "F.Cu" "F.Mask" "F.Paste")
			(net 116 "/DDR5 SODIMM/A.CB2")
			(pinfunction "IO_25_VRP_32")
			(pintype "bidirectional")
			(die_length 8.841)
		)
		(pad "W14" smd circle
			(at 0.499 5.499 180)
			(size 0.5 0.5)
			(layers "F.Cu" "F.Mask" "F.Paste")
			(net 73 "/DDR5 SODIMM/A.DQ7")
			(pinfunction "IO_L24N_T3_32")
			(pintype "bidirectional")
			(die_length 12.441)
		)
		(pad "W15" smd circle
			(at 1.499 5.499 180)
			(size 0.5 0.5)
			(layers "F.Cu" "F.Mask" "F.Paste")
			(net 70 "/DDR5 SODIMM/A.DQ4")
			(pinfunction "IO_L22P_T3_32")
			(pintype "bidirectional")
			(die_length 13.547)
		)
		(pad "W16" smd circle
			(at 2.499 5.499 180)
			(size 0.5 0.5)
			(layers "F.Cu" "F.Mask" "F.Paste")
			(net 71 "/DDR5 SODIMM/A.DQ5")
			(pinfunction "IO_L22N_T3_32")
			(pintype "bidirectional")
			(die_length 15.068)
		)
		(pad "W17" smd circle
			(at 3.499 5.499 180)
			(size 0.5 0.5)
			(layers "F.Cu" "F.Mask" "F.Paste")
			(net 206 "+1V1")
			(pinfunction "VCCO_32")
			(pintype "passive")
		)
		(pad "W18" smd circle
			(at 4.499 5.499 180)
			(size 0.5 0.5)
			(layers "F.Cu" "F.Mask" "F.Paste")
			(net 69 "/DDR5 SODIMM/A.DQS0_P")
			(pinfunction "IO_L21P_T3_DQS_32")
			(pintype "bidirectional")
			(die_length 16.431)
		)
		(pad "W19" smd circle
			(at 5.499 5.499 180)
			(size 0.5 0.5)
			(layers "F.Cu" "F.Mask" "F.Paste")
			(net 68 "/DDR5 SODIMM/A.DQS0_N")
			(pinfunction "IO_L21N_T3_DQS_32")
			(pintype "bidirectional")
			(die_length 16.437)
		)
		(pad "W20" smd circle
			(at 6.499 5.499 180)
			(size 0.5 0.5)
			(layers "F.Cu" "F.Mask" "F.Paste")
			(net 579 "unconnected-(U4A-IO_L15P_T2_DQS_12-PadW20)")
			(pinfunction "IO_L15P_T2_DQS_12")
			(pintype "bidirectional+no_connect")
			(die_length 9.921)
		)
		(pad "W21" smd circle
			(at 7.499 5.499 180)
			(size 0.5 0.5)
			(layers "F.Cu" "F.Mask" "F.Paste")
			(net 580 "unconnected-(U4A-IO_L6N_T0_VREF_12-PadW21)")
			(pinfunction "IO_L6N_T0_VREF_12")
			(pintype "bidirectional+no_connect")
			(die_length 9.947)
		)
		(pad "W22" smd circle
			(at 8.499 5.499 180)
			(size 0.5 0.5)
			(layers "F.Cu" "F.Mask" "F.Paste")
			(net 1 "GND")
			(pinfunction "GND")
			(pintype "passive")
		)
		(pad "W23" smd circle
			(at 9.499 5.499 180)
			(size 0.5 0.5)
			(layers "F.Cu" "F.Mask" "F.Paste")
			(net 581 "unconnected-(U4A-IO_L8P_T1_12-PadW23)")
			(pinfunction "IO_L8P_T1_12")
			(pintype "bidirectional+no_connect")
			(die_length 12.009)
		)
		(pad "W24" smd circle
			(at 10.499 5.499 180)
			(size 0.5 0.5)
			(layers "F.Cu" "F.Mask" "F.Paste")
			(net 733 "/Ethernet/ETH.TXD0")
			(pinfunction "IO_L8N_T1_12")
			(pintype "bidirectional")
			(die_length 13.111)
		)
		(pad "W25" smd circle
			(at 11.499 5.499 180)
			(size 0.5 0.5)
			(layers "F.Cu" "F.Mask" "F.Paste")
			(net 674 "/Ethernet/ETH.RXD1")
			(pinfunction "IO_L5P_T0_12")
			(pintype "bidirectional")
			(die_length 14.107)
		)
		(pad "W26" smd circle
			(at 12.499 5.499 180)
			(size 0.5 0.5)
			(layers "F.Cu" "F.Mask" "F.Paste")
			(net 673 "/Ethernet/ETH.RXD0")
			(pinfunction "IO_L5N_T0_12")
			(pintype "bidirectional")
			(die_length 15.45)
		)
		(pad "Y1" smd circle
			(at -12.5 6.499 180)
			(size 0.5 0.5)
			(layers "F.Cu" "F.Mask" "F.Paste")
			(net 264 "/DDR5 SODIMM/B.~{DM2}")
			(pinfunction "IO_L10N_T1_34")
			(pintype "bidirectional")
			(die_length 20.111)
		)
		(pad "Y2" smd circle
			(at -11.5 6.499 180)
			(size 0.5 0.5)
			(layers "F.Cu" "F.Mask" "F.Paste")
			(net 269 "/DDR5 SODIMM/B.DQ21")
			(pinfunction "IO_L7N_T1_34")
			(pintype "bidirectional")
			(die_length 18.743)
		)
		(pad "Y3" smd circle
			(at -10.5 6.499 180)
			(size 0.5 0.5)
			(layers "F.Cu" "F.Mask" "F.Paste")
			(net 261 "/DDR5 SODIMM/B.DQ18")
			(pinfunction "IO_L7P_T1_34")
			(pintype "bidirectional")
			(die_length 18.285)
		)
		(pad "Y4" smd circle
			(at -9.5 6.499 180)
			(size 0.5 0.5)
			(layers "F.Cu" "F.Mask" "F.Paste")
			(net 206 "+1V1")
			(pinfunction "VCCO_34")
			(pintype "passive")
		)
		(pad "Y5" smd circle
			(at -8.5 6.499 180)
			(size 0.5 0.5)
			(layers "F.Cu" "F.Mask" "F.Paste")
			(net 238 "/DDR5 SODIMM/B.DQ10")
			(pinfunction "IO_L17N_T2_34")
			(pintype "bidirectional")
			(die_length 15.693)
		)
		(pad "Y6" smd circle
			(at -7.5 6.499 180)
			(size 0.5 0.5)
			(layers "F.Cu" "F.Mask" "F.Paste")
			(net 233 "/DDR5 SODIMM/B.DQ9")
			(pinfunction "IO_L17P_T2_34")
			(pintype "bidirectional")
			(die_length 17.912)
		)
		(pad "Y7" smd circle
			(at -6.5 6.499 180)
			(size 0.5 0.5)
			(layers "F.Cu" "F.Mask" "F.Paste")
			(net 181 "/DDR5 SODIMM/B.CA1")
			(pinfunction "IO_L4N_T0_33")
			(pintype "bidirectional")
			(die_length 13.835)
		)
		(pad "Y8" smd circle
			(at -5.5 6.499 180)
			(size 0.5 0.5)
			(layers "F.Cu" "F.Mask" "F.Paste")
			(net 180 "/DDR5 SODIMM/B.~{CS0}")
			(pinfunction "IO_L4P_T0_33")
			(pintype "bidirectional")
			(die_length 13.201)
		)
		(pad "Y9" smd circle
			(at -4.5 6.499 180)
			(size 0.5 0.5)
			(layers "F.Cu" "F.Mask" "F.Paste")
			(net 1 "GND")
			(pinfunction "GND")
			(pintype "passive")
		)
		(pad "Y10" smd circle
			(at -3.5 6.499 180)
			(size 0.5 0.5)
			(layers "F.Cu" "F.Mask" "F.Paste")
			(net 177 "/DDR5 SODIMM/B.CA4")
			(pinfunction "IO_L5N_T0_33")
			(pintype "bidirectional")
			(die_length 14.206)
		)
		(pad "Y11" smd circle
			(at -2.5 6.499 180)
			(size 0.5 0.5)
			(layers "F.Cu" "F.Mask" "F.Paste")
			(net 176 "/DDR5 SODIMM/B.CA5")
			(pinfunction "IO_L5P_T0_33")
			(pintype "bidirectional")
			(die_length 15.036)
		)
		(pad "Y12" smd circle
			(at -1.5 6.499 180)
			(size 0.5 0.5)
			(layers "F.Cu" "F.Mask" "F.Paste")
			(net 168 "/DDR5 SODIMM/B.CA9")
			(pinfunction "IO_L18N_T2_33")
			(pintype "bidirectional")
			(die_length 14.615)
		)
		(pad "Y13" smd circle
			(at -0.5 6.499 180)
			(size 0.5 0.5)
			(layers "F.Cu" "F.Mask" "F.Paste")
			(net 169 "/DDR5 SODIMM/B.CA8")
			(pinfunction "IO_L18P_T2_33")
			(pintype "bidirectional")
			(die_length 15.191)
		)
		(pad "Y14" smd circle
			(at 0.499 6.499 180)
			(size 0.5 0.5)
			(layers "F.Cu" "F.Mask" "F.Paste")
			(net 206 "+1V1")
			(pinfunction "VCCO_32")
			(pintype "passive")
		)
		(pad "Y15" smd circle
			(at 1.499 6.499 180)
			(size 0.5 0.5)
			(layers "F.Cu" "F.Mask" "F.Paste")
			(net 96 "/DDR5 SODIMM/A.DQS2_P")
			(pinfunction "IO_L9P_T1_DQS_32")
			(pintype "bidirectional")
			(die_length 13.423)
		)
		(pad "Y16" smd circle
			(at 2.499 6.499 180)
			(size 0.5 0.5)
			(layers "F.Cu" "F.Mask" "F.Paste")
			(net 95 "/DDR5 SODIMM/A.DQS2_N")
			(pinfunction "IO_L9N_T1_DQS_32")
			(pintype "bidirectional")
			(die_length 13.009)
		)
		(pad "Y17" smd circle
			(at 3.499 6.499 180)
			(size 0.5 0.5)
			(layers "F.Cu" "F.Mask" "F.Paste")
			(net 72 "/DDR5 SODIMM/A.DQ6")
			(pinfunction "IO_L19P_T3_32")
			(pintype "bidirectional")
			(die_length 15.853)
		)
		(pad "Y18" smd circle
			(at 4.499 6.499 180)
			(size 0.5 0.5)
			(layers "F.Cu" "F.Mask" "F.Paste")
			(net 10 "/FPGA banks HP/VREF")
			(pinfunction "IO_L19N_T3_VREF_32")
			(pintype "bidirectional")
			(die_length 15)
		)
		(pad "Y19" smd circle
			(at 5.499 6.499 180)
			(size 0.5 0.5)
			(layers "F.Cu" "F.Mask" "F.Paste")
			(net 1 "GND")
			(pinfunction "GND")
			(pintype "passive")
		)
		(pad "Y20" smd circle
			(at 6.499 6.499 180)
			(size 0.5 0.5)
			(layers "F.Cu" "F.Mask" "F.Paste")
			(net 734 "/Ethernet/ETH.~{INT}")
			(pinfunction "IO_25_12")
			(pintype "bidirectional")
			(die_length 8.585)
		)
		(pad "Y21" smd circle
			(at 7.499 6.499 180)
			(size 0.5 0.5)
			(layers "F.Cu" "F.Mask" "F.Paste")
			(net 735 "/Ethernet/ETH.TXD3")
			(pinfunction "IO_L15N_T2_DQS_12")
			(pintype "bidirectional")
			(die_length 9.864)
		)
		(pad "Y22" smd circle
			(at 8.499 6.499 180)
			(size 0.5 0.5)
			(layers "F.Cu" "F.Mask" "F.Paste")
			(net 736 "/Ethernet/ETH.TXD2")
			(pinfunction "IO_L13P_T2_MRCC_12")
			(pintype "bidirectional")
			(die_length 11.571)
		)
		(pad "Y23" smd circle
			(at 9.499 6.499 180)
			(size 0.5 0.5)
			(layers "F.Cu" "F.Mask" "F.Paste")
			(net 678 "/Ethernet/ETH.RXC")
			(pinfunction "IO_L12P_T1_MRCC_12")
			(pintype "bidirectional")
			(die_length 12.692)
		)
		(pad "Y24" smd circle
			(at 10.499 6.499 180)
			(size 0.5 0.5)
			(layers "F.Cu" "F.Mask" "F.Paste")
			(net 200 "+3V3")
			(pinfunction "VCCO_12")
			(pintype "passive")
		)
		(pad "Y25" smd circle
			(at 11.499 6.499 180)
			(size 0.5 0.5)
			(layers "F.Cu" "F.Mask" "F.Paste")
			(net 677 "/Ethernet/ETH.RX_CTL")
			(pinfunction "IO_L10P_T1_12")
			(pintype "bidirectional")
			(die_length 14.135)
		)
		(pad "Y26" smd circle
			(at 12.499 6.499 180)
			(size 0.5 0.5)
			(layers "F.Cu" "F.Mask" "F.Paste")
			(net 737 "/Ethernet/ETH.TXD1")
			(pinfunction "IO_L10N_T1_12")
			(pintype "bidirectional")
			(die_length 15.98)
		)
	)
	(footprint "antmicro-footprints:R_0402_1005Metric"
		(layer "F.Cu")
		(at 91.2 178)
		(descr "Resistor SMD 0402")
		(tags "resistor SMD 0402")
		(property "Reference" "R43"
			(at -1.122484 -0.772697 0)
			(layer "F.SilkS")
			(hide yes)
			(effects
				(font
					(size 0.7 0.7)
					(thickness 0.15)
				)
				(justify left bottom)
			)
		)
		(property "Value" "R_10k_0402"
			(at -1.011843 1.772047 0)
			(layer "F.Fab")
			(effects
				(font
					(size 0.7 0.7)
					(thickness 0.15)
				)
				(justify left bottom)
			)
		)
		(property "Datasheet" "https://www.bourns.com/docs/product-datasheets/cr.pdf"
			(at 0 0 0)
			(layer "F.Fab")
			(hide yes)
			(effects
				(font
					(size 1.27 1.27)
					(thickness 0.15)
				)
			)
		)
		(property "Author" "Antmicro"
			(at 0 0 0)
			(layer "F.Fab")
			(hide yes)
			(effects
				(font
					(size 1 1)
					(thickness 0.15)
				)
			)
		)
		(property "License" "Apache-2.0"
			(at 0 0 0)
			(layer "F.Fab")
			(hide yes)
			(effects
				(font
					(size 1 1)
					(thickness 0.15)
				)
			)
		)
		(property "MPN" "CR0402-FX-1002GLF"
			(at 0 0 0)
			(layer "F.Fab")
			(hide yes)
			(effects
				(font
					(size 1 1)
					(thickness 0.15)
				)
			)
		)
		(property "Manufacturer" "Bourns"
			(at 0 0 0)
			(layer "F.Fab")
			(hide yes)
			(effects
				(font
					(size 1 1)
					(thickness 0.15)
				)
			)
		)
		(property "Tolerance" "1%"
			(at 0 0 0)
			(layer "F.Fab")
			(hide yes)
			(effects
				(font
					(size 1 1)
					(thickness 0.15)
				)
			)
		)
		(property "Val" "10k"
			(at 0 0 0)
			(layer "F.Fab")
			(hide yes)
			(effects
				(font
					(size 1 1)
					(thickness 0.15)
				)
			)
		)
		(sheetname "/Debug FTDI/")
		(sheetfile "debug-ftdi.kicad_sch")
		(attr smd)
		(fp_rect
			(start -0.93 -0.47)
			(end 0.93 0.47)
			(stroke
				(width 0.05)
				(type solid)
			)
			(fill no)
			(layer "F.CrtYd")
		)
		(fp_rect
			(start -0.5 -0.25)
			(end 0.5 0.25)
			(stroke
				(width 0.15)
				(type solid)
			)
			(fill no)
			(layer "F.Fab")
		)
		(pad "1" smd roundrect
			(at -0.485 0)
			(size 0.59 0.64)
			(layers "F.Cu" "F.Mask" "F.Paste")
			(roundrect_rratio 0.25)
			(net 6 "/Debug FTDI/FTDI_3V3")
			(pintype "passive")
		)
		(pad "2" smd roundrect
			(at 0.485 0)
			(size 0.59 0.64)
			(layers "F.Cu" "F.Mask" "F.Paste")
			(roundrect_rratio 0.25)
			(net 370 "Net-(U6-~{RESET})")
			(pintype "passive")
		)
	)
	(footprint "antmicro-footprints:C_0805_2012Metric"
		(layer "F.Cu")
		(at 172.9195 199.314502)
		(descr "Capacitor SMD 0805")
		(tags "capacitor SMD 0805")
		(property "Reference" "C200"
			(at -2.10551 -1.198678 0)
			(layer "F.SilkS")
			(hide yes)
			(effects
				(font
					(size 0.7 0.7)
					(thickness 0.15)
				)
				(justify left bottom)
			)
		)
		(property "Value" "C_22u_25V_0805"
			(at -2.055717 1.963152 0)
			(layer "F.Fab")
			(effects
				(font
					(size 0.7 0.7)
					(thickness 0.15)
				)
				(justify left bottom)
			)
		)
		(property "Datasheet" "https://product.samsungsem.com/mlcc/CL21A226MAYNNN.do"
			(at 0 0 0)
			(layer "F.Fab")
			(hide yes)
			(effects
				(font
					(size 1.27 1.27)
					(thickness 0.15)
				)
			)
		)
		(property "Author" "Antmicro"
			(at 0 0 0)
			(layer "F.Fab")
			(hide yes)
			(effects
				(font
					(size 1 1)
					(thickness 0.15)
				)
			)
		)
		(property "Dielectric" ""
			(at 0 0 0)
			(layer "F.Fab")
			(hide yes)
			(effects
				(font
					(size 1 1)
					(thickness 0.15)
				)
			)
		)
		(property "License" "Apache-2.0"
			(at 0 0 0)
			(layer "F.Fab")
			(hide yes)
			(effects
				(font
					(size 1 1)
					(thickness 0.15)
				)
			)
		)
		(property "MPN" "CL21A226MAYNNNE"
			(at 0 0 0)
			(layer "F.Fab")
			(hide yes)
			(effects
				(font
					(size 1 1)
					(thickness 0.15)
				)
			)
		)
		(property "Manufacturer" "Samsung Electro-Mechanics"
			(at 0 0 0)
			(layer "F.Fab")
			(hide yes)
			(effects
				(font
					(size 1 1)
					(thickness 0.15)
				)
			)
		)
		(property "Val" "22u_25V"
			(at 0 0 0)
			(layer "F.Fab")
			(hide yes)
			(effects
				(font
					(size 1 1)
					(thickness 0.15)
				)
			)
		)
		(property "Voltage" ""
			(at 0 0 0)
			(layer "F.Fab")
			(hide yes)
			(effects
				(font
					(size 1 1)
					(thickness 0.15)
				)
			)
		)
		(sheetname "/Supply/")
		(sheetfile "supply.kicad_sch")
		(attr smd)
		(fp_line
			(start -0.3 -0.8)
			(end 0.3 -0.8)
			(stroke
				(width 0.15)
				(type solid)
			)
			(layer "F.SilkS")
		)
		(fp_line
			(start -0.3 0.8)
			(end 0.3 0.8)
			(stroke
				(width 0.15)
				(type solid)
			)
			(layer "F.SilkS")
		)
		(fp_rect
			(start -1.9 -0.93)
			(end 1.9 0.93)
			(stroke
				(width 0.05)
				(type solid)
			)
			(fill no)
			(layer "F.CrtYd")
		)
		(fp_rect
			(start -0.95 -0.675)
			(end 0.95 0.675)
			(stroke
				(width 0.15)
				(type solid)
			)
			(fill no)
			(layer "F.Fab")
		)
		(pad "1" smd rect
			(at -1.05 0)
			(size 1.2 1.2)
			(layers "F.Cu" "F.Mask" "F.Paste")
			(net 1 "GND")
			(pintype "passive")
		)
		(pad "2" smd rect
			(at 1.05 0)
			(size 1.2 1.2)
			(layers "F.Cu" "F.Mask" "F.Paste")
			(net 38 "VDC")
			(pintype "passive")
		)
	)
	(footprint "antmicro-footprints:R_0402_1005Metric"
		(layer "F.Cu")
		(at 98.78 136.07 -90)
		(descr "Resistor SMD 0402")
		(tags "resistor SMD 0402")
		(property "Reference" "R124"
			(at -1.122484 -0.772697 270)
			(layer "F.SilkS")
			(hide yes)
			(effects
				(font
					(size 0.7 0.7)
					(thickness 0.15)
				)
				(justify left bottom)
			)
		)
		(property "Value" "R_4k7_0402"
			(at -1.011843 1.772047 270)
			(layer "F.Fab")
			(effects
				(font
					(size 0.7 0.7)
					(thickness 0.15)
				)
				(justify left bottom)
			)
		)
		(property "Datasheet" "https://www.bourns.com/docs/product-datasheets/cr.pdf"
			(at 0 0 270)
			(layer "F.Fab")
			(hide yes)
			(effects
				(font
					(size 1.27 1.27)
					(thickness 0.15)
				)
			)
		)
		(property "Author" "Antmicro"
			(at -37.29 234.85 0)
			(layer "F.Fab")
			(hide yes)
			(effects
				(font
					(size 1 1)
					(thickness 0.15)
				)
			)
		)
		(property "License" "Apache-2.0"
			(at -37.29 234.85 0)
			(layer "F.Fab")
			(hide yes)
			(effects
				(font
					(size 1 1)
					(thickness 0.15)
				)
			)
		)
		(property "MPN" "CR0402-FX-4701GLF"
			(at -37.29 234.85 0)
			(layer "F.Fab")
			(hide yes)
			(effects
				(font
					(size 1 1)
					(thickness 0.15)
				)
			)
		)
		(property "Manufacturer" "Bourns"
			(at -37.29 234.85 0)
			(layer "F.Fab")
			(hide yes)
			(effects
				(font
					(size 1 1)
					(thickness 0.15)
				)
			)
		)
		(property "Tolerance" "1%"
			(at -37.29 234.85 0)
			(layer "F.Fab")
			(hide yes)
			(effects
				(font
					(size 1 1)
					(thickness 0.15)
				)
			)
		)
		(property "Val" "4k7"
			(at -37.29 234.85 0)
			(layer "F.Fab")
			(hide yes)
			(effects
				(font
					(size 1 1)
					(thickness 0.15)
				)
			)
		)
		(sheetname "/I^{2}C/")
		(sheetfile "i2c.kicad_sch")
		(attr smd)
		(fp_rect
			(start -0.93 -0.47)
			(end 0.93 0.47)
			(stroke
				(width 0.05)
				(type solid)
			)
			(fill no)
			(layer "F.CrtYd")
		)
		(fp_rect
			(start -0.5 -0.25)
			(end 0.5 0.25)
			(stroke
				(width 0.15)
				(type solid)
			)
			(fill no)
			(layer "F.Fab")
		)
		(pad "1" smd roundrect
			(at -0.485 0 270)
			(size 0.59 0.64)
			(layers "F.Cu" "F.Mask" "F.Paste")
			(roundrect_rratio 0.25)
			(net 267 "VDDSPD")
			(pintype "passive")
		)
		(pad "2" smd roundrect
			(at 0.485 0 270)
			(size 0.59 0.64)
			(layers "F.Cu" "F.Mask" "F.Paste")
			(roundrect_rratio 0.25)
			(net 54 "/DDR5 SODIMM/DDR.SDA")
			(pintype "passive")
		)
	)
	(footprint "antmicro-footprints:SC70-3"
		(layer "F.Cu")
		(at 97.700501 129.235461 90)
		(property "Reference" "Q1"
			(at 0 -1.6 90)
			(layer "F.SilkS")
			(hide yes)
			(effects
				(font
					(size 0.7 0.7)
					(thickness 0.15)
				)
				(justify left bottom)
			)
		)
		(property "Value" "BSS138PW,115"
			(at 0 2.3 90)
			(layer "F.Fab")
			(effects
				(font
					(size 0.7 0.7)
					(thickness 0.15)
				)
				(justify left bottom)
			)
		)
		(property "Datasheet" "https://assets.nexperia.com/documents/data-sheet/BSS138PW.pdf"
			(at 0 0 90)
			(layer "F.Fab")
			(hide yes)
			(effects
				(font
					(size 1.27 1.27)
					(thickness 0.15)
				)
			)
		)
		(property "Description" "Power MOSFET, N Channel, 60 V, 320 mA, 0.9 ohm, SOT-323, Surface Mount"
			(at 0 0 90)
			(layer "F.Fab")
			(hide yes)
			(effects
				(font
					(size 1.27 1.27)
					(thickness 0.15)
				)
			)
		)
		(property "Author" "Antmicro"
			(at 226.935962 31.53496 0)
			(layer "F.Fab")
			(hide yes)
			(effects
				(font
					(size 1 1)
					(thickness 0.15)
				)
			)
		)
		(property "License" "Apache-2.0"
			(at 226.935962 31.53496 0)
			(layer "F.Fab")
			(hide yes)
			(effects
				(font
					(size 1 1)
					(thickness 0.15)
				)
			)
		)
		(property "MPN" "BSS138PW,115"
			(at 226.935962 31.53496 0)
			(layer "F.Fab")
			(hide yes)
			(effects
				(font
					(size 1 1)
					(thickness 0.15)
				)
			)
		)
		(property "Manufacturer" "Nexperia"
			(at 226.935962 31.53496 0)
			(layer "F.Fab")
			(hide yes)
			(effects
				(font
					(size 1 1)
					(thickness 0.15)
				)
			)
		)
		(sheetname "/FPGA Config/")
		(sheetfile "fpga-config.kicad_sch")
		(attr smd)
		(fp_line
			(start -0.3 -1)
			(end 0.627 -0.999)
			(stroke
				(width 0.15)
				(type solid)
			)
			(layer "F.SilkS")
		)
		(fp_line
			(start 0.627 -0.6)
			(end 0.627 -0.999)
			(stroke
				(width 0.15)
				(type solid)
			)
			(layer "F.SilkS")
		)
		(fp_line
			(start 0.627 0.6)
			(end 0.627 1.001)
			(stroke
				(width 0.15)
				(type solid)
			)
			(layer "F.SilkS")
		)
		(fp_line
			(start -0.3 1)
			(end 0.627 1.001)
			(stroke
				(width 0.15)
				(type solid)
			)
			(layer "F.SilkS")
		)
		(fp_line
			(start 0.9 -1.3)
			(end 0.9 -0.4)
			(stroke
				(width 0.05)
				(type solid)
			)
			(layer "F.CrtYd")
		)
		(fp_line
			(start -0.9 -1.3)
			(end 0.9 -1.3)
			(stroke
				(width 0.05)
				(type solid)
			)
			(layer "F.CrtYd")
		)
		(fp_line
			(start -0.9 -1.3)
			(end -0.9 -1)
			(stroke
				(width 0.05)
				(type solid)
			)
			(layer "F.CrtYd")
		)
		(fp_line
			(start -0.9 -1)
			(end -1.4 -1)
			(stroke
				(width 0.05)
				(type solid)
			)
			(layer "F.CrtYd")
		)
		(fp_line
			(start 1.4 -0.4)
			(end 1.4 0.4)
			(stroke
				(width 0.05)
				(type solid)
			)
			(layer "F.CrtYd")
		)
		(fp_line
			(start 0.9 -0.4)
			(end 1.4 -0.4)
			(stroke
				(width 0.05)
				(type solid)
			)
			(layer "F.CrtYd")
		)
		(fp_line
			(start 1.4 0.4)
			(end 0.9 0.4)
			(stroke
				(width 0.05)
				(type solid)
			)
			(layer "F.CrtYd")
		)
		(fp_line
			(start 0.9 0.4)
			(end 0.9 1.3)
			(stroke
				(width 0.05)
				(type solid)
			)
			(layer "F.CrtYd")
		)
		(fp_line
			(start -0.9 1)
			(end -1.4 1)
			(stroke
				(width 0.05)
				(type solid)
			)
			(layer "F.CrtYd")
		)
		(fp_line
			(start -1.4 1)
			(end -1.4 -1)
			(stroke
				(width 0.05)
				(type solid)
			)
			(layer "F.CrtYd")
		)
		(fp_line
			(start 0.9 1.3)
			(end -0.9 1.3)
			(stroke
				(width 0.05)
				(type solid)
			)
			(layer "F.CrtYd")
		)
		(fp_line
			(start -0.9 1.3)
			(end -0.9 1)
			(stroke
				(width 0.05)
				(type solid)
			)
			(layer "F.CrtYd")
		)
		(fp_rect
			(start -0.623 -0.999)
			(end 0.627 1.001)
			(stroke
				(width 0.15)
				(type solid)
			)
			(fill no)
			(layer "F.Fab")
		)
		(pad "1" smd rect
			(at -1.051 -0.65 180)
			(size 0.6 0.6)
			(layers "F.Cu" "F.Mask" "F.Paste")
			(net 240 "POWER")
			(pinfunction "G")
			(pintype "input")
		)
		(pad "2" smd rect
			(at -1.051 0.65 180)
			(size 0.6 0.6)
			(layers "F.Cu" "F.Mask" "F.Paste")
			(net 1 "GND")
			(pinfunction "S")
			(pintype "passive")
		)
		(pad "3" smd rect
			(at 1.05 0 180)
			(size 0.6 0.6)
			(layers "F.Cu" "F.Mask" "F.Paste")
			(net 347 "Net-(Q1-D)")
			(pinfunction "D")
			(pintype "passive")
		)
	)
	(footprint "antmicro-footprints:TP_SMD_1mm"
		(layer "F.Cu")
		(at 186.5 137)
		(property "Reference" "TP16"
			(at 0 -0.731898 0)
			(layer "F.SilkS")
			(hide yes)
			(effects
				(font
					(size 0.7 0.7)
					(thickness 0.15)
				)
				(justify left bottom)
			)
		)
		(property "Value" "TP_1mm_SMD"
			(at 0 1.4 0)
			(layer "F.Fab")
			(effects
				(font
					(size 0.7 0.7)
					(thickness 0.15)
				)
				(justify left bottom)
			)
		)
		(property "Author" "Antmicro"
			(at 0 0 0)
			(layer "F.Fab")
			(hide yes)
			(effects
				(font
					(size 1 1)
					(thickness 0.15)
				)
			)
		)
		(property "License" "Apache-2.0"
			(at 0 0 0)
			(layer "F.Fab")
			(hide yes)
			(effects
				(font
					(size 1 1)
					(thickness 0.15)
				)
			)
		)
		(property "MPN" ""
			(at 0 0 0)
			(layer "F.Fab")
			(hide yes)
			(effects
				(font
					(size 1 1)
					(thickness 0.15)
				)
			)
		)
		(property "Manufacturer" ""
			(at 0 0 0)
			(layer "F.Fab")
			(hide yes)
			(effects
				(font
					(size 1 1)
					(thickness 0.15)
				)
			)
		)
		(sheetname "/Supply/")
		(sheetfile "supply.kicad_sch")
		(attr exclude_from_pos_files)
		(pad "1" smd circle
			(at 0 0)
			(size 1 1)
			(layers "F.Cu" "F.Mask")
			(net 38 "VDC")
			(pinfunction "1")
			(pintype "passive")
		)
	)
	(footprint "antmicro-footprints:R_1206_3216Metric"
		(layer "F.Cu")
		(at 199.5 177.173 180)
		(property "Reference" "R143"
			(at 0.45 1.223 180)
			(layer "F.SilkS")
			(effects
				(font
					(size 0.7 0.7)
					(thickness 0.15)
				)
				(justify left bottom)
			)
		)
		(property "Value" "R_0R01_1206"
			(at -2.422356 2.103591 180)
			(layer "F.Fab")
			(effects
				(font
					(size 0.7 0.7)
					(thickness 0.15)
				)
				(justify left bottom)
			)
		)
		(property "Datasheet" "https://www.yageo.com/upload/media/product/productsearch/datasheet/rchip/PYu-RL_Group_521_RoHS_L_2.pdf"
			(at 0 0 180)
			(layer "F.Fab")
			(hide yes)
			(effects
				(font
					(size 1.27 1.27)
					(thickness 0.15)
				)
			)
		)
		(property "Author" "Antmicro"
			(at 399 354.346 0)
			(layer "F.Fab")
			(hide yes)
			(effects
				(font
					(size 1 1)
					(thickness 0.15)
				)
			)
		)
		(property "License" "Apache-2.0"
			(at 399 354.346 0)
			(layer "F.Fab")
			(hide yes)
			(effects
				(font
					(size 1 1)
					(thickness 0.15)
				)
			)
		)
		(property "MPN" "RL1206FR-7W0R01L"
			(at 399 354.346 0)
			(layer "F.Fab")
			(hide yes)
			(effects
				(font
					(size 1 1)
					(thickness 0.15)
				)
			)
		)
		(property "Manufacturer" "YAGEO"
			(at 399 354.346 0)
			(layer "F.Fab")
			(hide yes)
			(effects
				(font
					(size 1 1)
					(thickness 0.15)
				)
			)
		)
		(property "Tolerance" "1%"
			(at 399 354.346 0)
			(layer "F.Fab")
			(hide yes)
			(effects
				(font
					(size 1 1)
					(thickness 0.15)
				)
			)
		)
		(property "Val" "0R01"
			(at 399 354.346 0)
			(layer "F.Fab")
			(hide yes)
			(effects
				(font
					(size 1 1)
					(thickness 0.15)
				)
			)
		)
		(sheetname "/Supply/")
		(sheetfile "supply.kicad_sch")
		(attr smd)
		(fp_line
			(start 0 0.9)
			(end 0.498 0.9)
			(stroke
				(width 0.15)
				(type solid)
			)
			(layer "F.SilkS")
		)
		(fp_line
			(start 0 0.9)
			(end -0.5 0.9)
			(stroke
				(width 0.15)
				(type solid)
			)
			(layer "F.SilkS")
		)
		(fp_line
			(start 0 -0.902)
			(end 0.498 -0.902)
			(stroke
				(width 0.15)
				(type solid)
			)
			(layer "F.SilkS")
		)
		(fp_line
			(start 0 -0.902)
			(end -0.5 -0.902)
			(stroke
				(width 0.15)
				(type solid)
			)
			(layer "F.SilkS")
		)
		(fp_rect
			(start -2.25 -1.05)
			(end 2.25 1.05)
			(stroke
				(width 0.05)
				(type solid)
			)
			(fill no)
			(layer "F.CrtYd")
		)
		(fp_line
			(start 1.6 -0.802)
			(end 1.6 0.8)
			(stroke
				(width 0.15)
				(type solid)
			)
			(layer "F.Fab")
		)
		(fp_line
			(start -1.601 0.8)
			(end 1.6 0.8)
			(stroke
				(width 0.15)
				(type solid)
			)
			(layer "F.Fab")
		)
		(fp_line
			(start -1.601 -0.802)
			(end 1.6 -0.802)
			(stroke
				(width 0.15)
				(type solid)
			)
			(layer "F.Fab")
		)
		(fp_line
			(start -1.601 -0.802)
			(end -1.601 0.8)
			(stroke
				(width 0.15)
				(type solid)
			)
			(layer "F.Fab")
		)
		(pad "1" smd roundrect
			(at -1.5 0 180)
			(size 1.2 1.8)
			(layers "F.Cu" "F.Mask" "F.Paste")
			(roundrect_rratio 0.15)
			(net 35 "/Supply/spare_local")
			(pintype "passive")
		)
		(pad "2" smd roundrect
			(at 1.499 0 180)
			(size 1.2 1.8)
			(layers "F.Cu" "F.Mask" "F.Paste")
			(roundrect_rratio 0.15)
			(net 239 "/Supply/spare")
			(pintype "passive")
		)
	)
	(footprint "antmicro-footprints:C_0603_1608Metric"
		(layer "F.Cu")
		(at 199.5 189.475)
		(descr "Capacitor SMD 0603")
		(tags "capacitor 0603")
		(property "Reference" "C189"
			(at -1.42757 -1.000252 0)
			(layer "F.SilkS")
			(hide yes)
			(effects
				(font
					(size 0.7 0.7)
					(thickness 0.15)
				)
				(justify left bottom)
			)
		)
		(property "Value" "C_22u_0603"
			(at -1.42757 1.770288 0)
			(layer "F.Fab")
			(effects
				(font
					(size 0.7 0.7)
					(thickness 0.15)
				)
				(justify left bottom)
			)
		)
		(property "Datasheet" "https://www.murata.com/products/productdetail?partno=GRM188R60J226MEA0%23"
			(at 0 0 0)
			(layer "F.Fab")
			(hide yes)
			(effects
				(font
					(size 1.27 1.27)
					(thickness 0.15)
				)
			)
		)
		(property "Author" "Antmicro"
			(at 0 0 0)
			(layer "F.Fab")
			(hide yes)
			(effects
				(font
					(size 1 1)
					(thickness 0.15)
				)
			)
		)
		(property "Dielectric" ""
			(at 0 0 0)
			(layer "F.Fab")
			(hide yes)
			(effects
				(font
					(size 1 1)
					(thickness 0.15)
				)
			)
		)
		(property "License" "Apache-2.0"
			(at 0 0 0)
			(layer "F.Fab")
			(hide yes)
			(effects
				(font
					(size 1 1)
					(thickness 0.15)
				)
			)
		)
		(property "MPN" "GRM188R60J226MEA0D"
			(at 0 0 0)
			(layer "F.Fab")
			(hide yes)
			(effects
				(font
					(size 1 1)
					(thickness 0.15)
				)
			)
		)
		(property "Manufacturer" "Murata"
			(at 0 0 0)
			(layer "F.Fab")
			(hide yes)
			(effects
				(font
					(size 1 1)
					(thickness 0.15)
				)
			)
		)
		(property "Val" "22u"
			(at 0 0 0)
			(layer "F.Fab")
			(hide yes)
			(effects
				(font
					(size 1 1)
					(thickness 0.15)
				)
			)
		)
		(property "Voltage" ""
			(at 0 0 0)
			(layer "F.Fab")
			(hide yes)
			(effects
				(font
					(size 1 1)
					(thickness 0.15)
				)
			)
		)
		(sheetname "/Supply/")
		(sheetfile "supply.kicad_sch")
		(attr smd)
		(fp_line
			(start -0.3 -0.3)
			(end 0.3 -0.3)
			(stroke
				(width 0.15)
				(type solid)
			)
			(layer "F.SilkS")
		)
		(fp_line
			(start -0.3 0.3)
			(end 0.3 0.3)
			(stroke
				(width 0.15)
				(type solid)
			)
			(layer "F.SilkS")
		)
		(fp_rect
			(start -1.24 -0.7)
			(end 1.24 0.7)
			(stroke
				(width 0.05)
				(type solid)
			)
			(fill no)
			(layer "F.CrtYd")
		)
		(fp_rect
			(start -0.8 -0.4)
			(end 0.8 0.4)
			(stroke
				(width 0.15)
				(type solid)
			)
			(fill no)
			(layer "F.Fab")
		)
		(pad "1" smd roundrect
			(at -0.7 0)
			(size 0.6 0.8)
			(layers "F.Cu" "F.Mask" "F.Paste")
			(roundrect_rratio 0.2)
			(net 1 "GND")
			(pintype "passive")
		)
		(pad "2" smd roundrect
			(at 0.7 0)
			(size 0.6 0.8)
			(layers "F.Cu" "F.Mask" "F.Paste")
			(roundrect_rratio 0.2)
			(net 58 "/Supply/1V7_local")
			(pintype "passive")
		)
	)
	(footprint "antmicro-footprints:LED_0603_1608Metric_G"
		(layer "F.Cu")
		(at 97.9 197.1 -90)
		(descr "LED SMD 0603 Green")
		(tags "LED SMD 0603 Green")
		(property "Reference" "D13"
			(at -0.001 -0.901 270)
			(layer "F.SilkS")
			(hide yes)
			(effects
				(font
					(size 0.7 0.7)
					(thickness 0.15)
				)
				(justify left bottom)
			)
		)
		(property "Value" "LED_G_0603_KP-1608CGCK"
			(at -0.001 1.599 270)
			(layer "F.Fab")
			(effects
				(font
					(size 0.7 0.7)
					(thickness 0.15)
				)
				(justify left bottom)
			)
		)
		(property "Datasheet" "http://www.farnell.com/datasheets/2045956.pdf"
			(at 0 0 270)
			(layer "F.Fab")
			(hide yes)
			(effects
				(font
					(size 1.27 1.27)
					(thickness 0.15)
				)
			)
		)
		(property "Author" "Antmicro"
			(at -99.2 295 0)
			(layer "F.Fab")
			(hide yes)
			(effects
				(font
					(size 1 1)
					(thickness 0.15)
				)
			)
		)
		(property "License" "Apache-2.0"
			(at -99.2 295 0)
			(layer "F.Fab")
			(hide yes)
			(effects
				(font
					(size 1 1)
					(thickness 0.15)
				)
			)
		)
		(property "MPN" "KP-1608CGCK"
			(at -99.2 295 0)
			(layer "F.Fab")
			(hide yes)
			(effects
				(font
					(size 1 1)
					(thickness 0.15)
				)
			)
		)
		(property "Manufacturer" "Kingbright"
			(at -99.2 295 0)
			(layer "F.Fab")
			(hide yes)
			(effects
				(font
					(size 1 1)
					(thickness 0.15)
				)
			)
		)
		(sheetname "/Debug FTDI/")
		(sheetfile "debug-ftdi.kicad_sch")
		(attr smd)
		(fp_line
			(start -0.271 0.348)
			(end 0.269 0.348)
			(stroke
				(width 0.15)
				(type solid)
			)
			(layer "F.SilkS")
		)
		(fp_line
			(start 1.249 0.319)
			(end 1.249 -0.321)
			(stroke
				(width 0.15)
				(type solid)
			)
			(layer "F.SilkS")
		)
		(fp_line
			(start -0.107 -0.001)
			(end -0.291 -0.001)
			(stroke
				(width 0.1)
				(type solid)
			)
			(layer "F.SilkS")
		)
		(fp_line
			(start 0.092 -0.001)
			(end -0.107 0.198)
			(stroke
				(width 0.1)
				(type solid)
			)
			(layer "F.SilkS")
		)
		(fp_line
			(start 0.092 -0.001)
			(end 0.292 -0.001)
			(stroke
				(width 0.1)
				(type solid)
			)
			(layer "F.SilkS")
		)
		(fp_line
			(start -0.107 -0.201)
			(end -0.107 0.198)
			(stroke
				(width 0.1)
				(type solid)
			)
			(layer "F.SilkS")
		)
		(fp_line
			(start -0.107 -0.201)
			(end 0.092 -0.001)
			(stroke
				(width 0.1)
				(type solid)
			)
			(layer "F.SilkS")
		)
		(fp_line
			(start 0.092 -0.201)
			(end 0.092 0.198)
			(stroke
				(width 0.1)
				(type solid)
			)
			(layer "F.SilkS")
		)
		(fp_line
			(start -0.271 -0.349)
			(end 0.269 -0.349)
			(stroke
				(width 0.15)
				(type solid)
			)
			(layer "F.SilkS")
		)
		(fp_rect
			(start -1.2192 -0.6096)
			(end 1.27 0.6016)
			(stroke
				(width 0.05)
				(type solid)
			)
			(fill no)
			(layer "F.CrtYd")
		)
		(fp_line
			(start -0.202 0.201)
			(end 0.1 -0.001)
			(stroke
				(width 0.15)
				(type solid)
			)
			(layer "F.Fab")
		)
		(fp_line
			(start 0.198 0.201)
			(end 0.198 -0.101)
			(stroke
				(width 0.15)
				(type solid)
			)
			(layer "F.Fab")
		)
		(fp_line
			(start -0.849 0.025)
			(end -0.442 0.381)
			(stroke
				(width 0.15)
				(type solid)
			)
			(layer "F.Fab")
		)
		(fp_line
			(start -0.6 -0.001)
			(end -0.202 -0.001)
			(stroke
				(width 0.15)
				(type solid)
			)
			(layer "F.Fab")
		)
		(fp_line
			(start -0.202 -0.001)
			(end -0.202 0.201)
			(stroke
				(width 0.15)
				(type solid)
			)
			(layer "F.Fab")
		)
		(fp_line
			(start 0.1 -0.001)
			(end -0.202 -0.201)
			(stroke
				(width 0.15)
				(type solid)
			)
			(layer "F.Fab")
		)
		(fp_line
			(start 0.198 -0.001)
			(end 0.596 -0.001)
			(stroke
				(width 0.15)
				(type solid)
			)
			(layer "F.Fab")
		)
		(fp_line
			(start -0.202 -0.201)
			(end -0.202 -0.001)
			(stroke
				(width 0.15)
				(type solid)
			)
			(layer "F.Fab")
		)
		(fp_line
			(start 0.198 -0.201)
			(end 0.198 -0.101)
			(stroke
				(width 0.15)
				(type solid)
			)
			(layer "F.Fab")
		)
		(fp_rect
			(start -0.849 -0.401)
			(end 0.849 0.401)
			(stroke
				(width 0.15)
				(type solid)
			)
			(fill no)
			(layer "F.Fab")
		)
		(pad "1" smd rect
			(at -0.751 -0.001 90)
			(size 0.8 0.8)
			(layers "F.Cu" "F.Mask" "F.Paste")
			(net 318 "Net-(D13-Pad1)")
			(pinfunction "1")
			(pintype "passive")
		)
		(pad "2" smd rect
			(at 0.749 -0.001 90)
			(size 0.8 0.8)
			(layers "F.Cu" "F.Mask" "F.Paste")
			(net 1 "GND")
			(pinfunction "2")
			(pintype "passive")
		)
	)
	(footprint "antmicro-footprints:LED_0603_1608Metric_G"
		(layer "F.Cu")
		(at 91.750501 116.426 -90)
		(descr "LED SMD 0603 Green")
		(tags "LED SMD 0603 Green")
		(property "Reference" "D7"
			(at -0.001 -0.901 270)
			(layer "F.SilkS")
			(hide yes)
			(effects
				(font
					(size 0.7 0.7)
					(thickness 0.15)
				)
				(justify left bottom)
			)
		)
		(property "Value" "LED_G_0603_KP-1608CGCK"
			(at -0.001 1.599 270)
			(layer "F.Fab")
			(effects
				(font
					(size 0.7 0.7)
					(thickness 0.15)
				)
				(justify left bottom)
			)
		)
		(property "Datasheet" "http://www.farnell.com/datasheets/2045956.pdf"
			(at 0 0 270)
			(layer "F.Fab")
			(hide yes)
			(effects
				(font
					(size 1.27 1.27)
					(thickness 0.15)
				)
			)
		)
		(property "Author" "Antmicro"
			(at -24.675499 208.176501 0)
			(layer "F.Fab")
			(hide yes)
			(effects
				(font
					(size 1 1)
					(thickness 0.15)
				)
			)
		)
		(property "License" "Apache-2.0"
			(at -24.675499 208.176501 0)
			(layer "F.Fab")
			(hide yes)
			(effects
				(font
					(size 1 1)
					(thickness 0.15)
				)
			)
		)
		(property "MPN" "KP-1608CGCK"
			(at -24.675499 208.176501 0)
			(layer "F.Fab")
			(hide yes)
			(effects
				(font
					(size 1 1)
					(thickness 0.15)
				)
			)
		)
		(property "Manufacturer" "Kingbright"
			(at -24.675499 208.176501 0)
			(layer "F.Fab")
			(hide yes)
			(effects
				(font
					(size 1 1)
					(thickness 0.15)
				)
			)
		)
		(sheetname "/FPGA bank 14/")
		(sheetfile "fpga-bank-14.kicad_sch")
		(attr smd)
		(fp_line
			(start -0.271 0.348)
			(end 0.269 0.348)
			(stroke
				(width 0.15)
				(type solid)
			)
			(layer "F.SilkS")
		)
		(fp_line
			(start 1.249 0.319)
			(end 1.249 -0.321)
			(stroke
				(width 0.15)
				(type solid)
			)
			(layer "F.SilkS")
		)
		(fp_line
			(start -0.107 -0.001)
			(end -0.291 -0.001)
			(stroke
				(width 0.1)
				(type solid)
			)
			(layer "F.SilkS")
		)
		(fp_line
			(start 0.092 -0.001)
			(end -0.107 0.198)
			(stroke
				(width 0.1)
				(type solid)
			)
			(layer "F.SilkS")
		)
		(fp_line
			(start 0.092 -0.001)
			(end 0.292 -0.001)
			(stroke
				(width 0.1)
				(type solid)
			)
			(layer "F.SilkS")
		)
		(fp_line
			(start -0.107 -0.201)
			(end -0.107 0.198)
			(stroke
				(width 0.1)
				(type solid)
			)
			(layer "F.SilkS")
		)
		(fp_line
			(start -0.107 -0.201)
			(end 0.092 -0.001)
			(stroke
				(width 0.1)
				(type solid)
			)
			(layer "F.SilkS")
		)
		(fp_line
			(start 0.092 -0.201)
			(end 0.092 0.198)
			(stroke
				(width 0.1)
				(type solid)
			)
			(layer "F.SilkS")
		)
		(fp_line
			(start -0.271 -0.349)
			(end 0.269 -0.349)
			(stroke
				(width 0.15)
				(type solid)
			)
			(layer "F.SilkS")
		)
		(fp_rect
			(start -1.2192 -0.6096)
			(end 1.27 0.6016)
			(stroke
				(width 0.05)
				(type solid)
			)
			(fill no)
			(layer "F.CrtYd")
		)
		(fp_line
			(start -0.202 0.201)
			(end 0.1 -0.001)
			(stroke
				(width 0.15)
				(type solid)
			)
			(layer "F.Fab")
		)
		(fp_line
			(start 0.198 0.201)
			(end 0.198 -0.101)
			(stroke
				(width 0.15)
				(type solid)
			)
			(layer "F.Fab")
		)
		(fp_line
			(start -0.849 0.025)
			(end -0.442 0.381)
			(stroke
				(width 0.15)
				(type solid)
			)
			(layer "F.Fab")
		)
		(fp_line
			(start -0.6 -0.001)
			(end -0.202 -0.001)
			(stroke
				(width 0.15)
				(type solid)
			)
			(layer "F.Fab")
		)
		(fp_line
			(start -0.202 -0.001)
			(end -0.202 0.201)
			(stroke
				(width 0.15)
				(type solid)
			)
			(layer "F.Fab")
		)
		(fp_line
			(start 0.1 -0.001)
			(end -0.202 -0.201)
			(stroke
				(width 0.15)
				(type solid)
			)
			(layer "F.Fab")
		)
		(fp_line
			(start 0.198 -0.001)
			(end 0.596 -0.001)
			(stroke
				(width 0.15)
				(type solid)
			)
			(layer "F.Fab")
		)
		(fp_line
			(start -0.202 -0.201)
			(end -0.202 -0.001)
			(stroke
				(width 0.15)
				(type solid)
			)
			(layer "F.Fab")
		)
		(fp_line
			(start 0.198 -0.201)
			(end 0.198 -0.101)
			(stroke
				(width 0.15)
				(type solid)
			)
			(layer "F.Fab")
		)
		(fp_rect
			(start -0.849 -0.401)
			(end 0.849 0.401)
			(stroke
				(width 0.15)
				(type solid)
			)
			(fill no)
			(layer "F.Fab")
		)
		(pad "1" smd rect
			(at -0.751 -0.001 90)
			(size 0.8 0.8)
			(layers "F.Cu" "F.Mask" "F.Paste")
			(net 200 "+3V3")
			(pinfunction "1")
			(pintype "passive")
		)
		(pad "2" smd rect
			(at 0.749 -0.001 90)
			(size 0.8 0.8)
			(layers "F.Cu" "F.Mask" "F.Paste")
			(net 310 "Net-(D7-Pad2)")
			(pinfunction "2")
			(pintype "passive")
		)
	)
	(footprint "antmicro-footprints:C_0603_1608Metric"
		(layer "F.Cu")
		(at 192.745501 182.923 90)
		(descr "Capacitor SMD 0603")
		(tags "capacitor 0603")
		(property "Reference" "C183"
			(at -1.42757 -1.000252 90)
			(layer "F.SilkS")
			(hide yes)
			(effects
				(font
					(size 0.7 0.7)
					(thickness 0.15)
				)
				(justify left bottom)
			)
		)
		(property "Value" "C_22u_0603"
			(at -1.42757 1.770288 90)
			(layer "F.Fab")
			(effects
				(font
					(size 0.7 0.7)
					(thickness 0.15)
				)
				(justify left bottom)
			)
		)
		(property "Datasheet" "https://www.murata.com/products/productdetail?partno=GRM188R60J226MEA0%23"
			(at 0 0 90)
			(layer "F.Fab")
			(hide yes)
			(effects
				(font
					(size 1.27 1.27)
					(thickness 0.15)
				)
			)
		)
		(property "Author" "Antmicro"
			(at 375.668501 -9.822501 0)
			(layer "F.Fab")
			(hide yes)
			(effects
				(font
					(size 1 1)
					(thickness 0.15)
				)
			)
		)
		(property "Dielectric" ""
			(at 375.668501 -9.822501 0)
			(layer "F.Fab")
			(hide yes)
			(effects
				(font
					(size 1 1)
					(thickness 0.15)
				)
			)
		)
		(property "License" "Apache-2.0"
			(at 375.668501 -9.822501 0)
			(layer "F.Fab")
			(hide yes)
			(effects
				(font
					(size 1 1)
					(thickness 0.15)
				)
			)
		)
		(property "MPN" "GRM188R60J226MEA0D"
			(at 375.668501 -9.822501 0)
			(layer "F.Fab")
			(hide yes)
			(effects
				(font
					(size 1 1)
					(thickness 0.15)
				)
			)
		)
		(property "Manufacturer" "Murata"
			(at 375.668501 -9.822501 0)
			(layer "F.Fab")
			(hide yes)
			(effects
				(font
					(size 1 1)
					(thickness 0.15)
				)
			)
		)
		(property "Val" "22u"
			(at 375.668501 -9.822501 0)
			(layer "F.Fab")
			(hide yes)
			(effects
				(font
					(size 1 1)
					(thickness 0.15)
				)
			)
		)
		(property "Voltage" ""
			(at 375.668501 -9.822501 0)
			(layer "F.Fab")
			(hide yes)
			(effects
				(font
					(size 1 1)
					(thickness 0.15)
				)
			)
		)
		(sheetname "/Supply/")
		(sheetfile "supply.kicad_sch")
		(attr smd)
		(fp_line
			(start -0.3 -0.3)
			(end 0.3 -0.3)
			(stroke
				(width 0.15)
				(type solid)
			)
			(layer "F.SilkS")
		)
		(fp_line
			(start -0.3 0.3)
			(end 0.3 0.3)
			(stroke
				(width 0.15)
				(type solid)
			)
			(layer "F.SilkS")
		)
		(fp_rect
			(start -1.24 -0.7)
			(end 1.24 0.7)
			(stroke
				(width 0.05)
				(type solid)
			)
			(fill no)
			(layer "F.CrtYd")
		)
		(fp_rect
			(start -0.8 -0.4)
			(end 0.8 0.4)
			(stroke
				(width 0.15)
				(type solid)
			)
			(fill no)
			(layer "F.Fab")
		)
		(pad "1" smd roundrect
			(at -0.7 0 90)
			(size 0.6 0.8)
			(layers "F.Cu" "F.Mask" "F.Paste")
			(roundrect_rratio 0.2)
			(net 1 "GND")
			(pintype "passive")
		)
		(pad "2" smd roundrect
			(at 0.7 0 90)
			(size 0.6 0.8)
			(layers "F.Cu" "F.Mask" "F.Paste")
			(roundrect_rratio 0.2)
			(net 51 "/Supply/1V8_local")
			(pintype "passive")
		)
	)
	(footprint "antmicro-footprints:C_0402_1005Metric"
		(layer "F.Cu")
		(at 93 190 90)
		(descr "Capacitor SMD 0402")
		(tags "capacitor SMD 0402")
		(property "Reference" "C128"
			(at 0 -0.699 90)
			(layer "F.SilkS")
			(hide yes)
			(effects
				(font
					(size 0.7 0.7)
					(thickness 0.15)
				)
				(justify left bottom)
			)
		)
		(property "Value" "C_100n_0402"
			(at -1.022927 2.155213 90)
			(layer "F.Fab")
			(effects
				(font
					(size 0.7 0.7)
					(thickness 0.15)
				)
				(justify left bottom)
			)
		)
		(property "Datasheet" "https://www.murata.com/products/productdetail?partno=GRM155R61H104KE14%23"
			(at 0 0 90)
			(layer "F.Fab")
			(hide yes)
			(effects
				(font
					(size 1.27 1.27)
					(thickness 0.15)
				)
			)
		)
		(property "Author" "Antmicro"
			(at 283 97 0)
			(layer "F.Fab")
			(hide yes)
			(effects
				(font
					(size 1 1)
					(thickness 0.15)
				)
			)
		)
		(property "Dielectric" "X5R"
			(at 283 97 0)
			(layer "F.Fab")
			(hide yes)
			(effects
				(font
					(size 1 1)
					(thickness 0.15)
				)
			)
		)
		(property "License" "Apache-2.0"
			(at 283 97 0)
			(layer "F.Fab")
			(hide yes)
			(effects
				(font
					(size 1 1)
					(thickness 0.15)
				)
			)
		)
		(property "MPN" "GRM155R61H104KE14D"
			(at 283 97 0)
			(layer "F.Fab")
			(hide yes)
			(effects
				(font
					(size 1 1)
					(thickness 0.15)
				)
			)
		)
		(property "Manufacturer" "Murata"
			(at 283 97 0)
			(layer "F.Fab")
			(hide yes)
			(effects
				(font
					(size 1 1)
					(thickness 0.15)
				)
			)
		)
		(property "Val" "100n"
			(at 283 97 0)
			(layer "F.Fab")
			(hide yes)
			(effects
				(font
					(size 1 1)
					(thickness 0.15)
				)
			)
		)
		(property "Voltage" "50V"
			(at 283 97 0)
			(layer "F.Fab")
			(hide yes)
			(effects
				(font
					(size 1 1)
					(thickness 0.15)
				)
			)
		)
		(sheetname "/Debug FTDI/")
		(sheetfile "debug-ftdi.kicad_sch")
		(attr smd)
		(fp_rect
			(start -0.9659 -0.481258)
			(end 0.9649 0.458742)
			(stroke
				(width 0.05)
				(type solid)
			)
			(fill no)
			(layer "F.CrtYd")
		)
		(fp_line
			(start 0.499 -0.25)
			(end 0.499 0.248)
			(stroke
				(width 0.15)
				(type solid)
			)
			(layer "F.Fab")
		)
		(fp_line
			(start -0.499 -0.25)
			(end 0.499 -0.25)
			(stroke
				(width 0.15)
				(type solid)
			)
			(layer "F.Fab")
		)
		(fp_line
			(start 0.499 0.248)
			(end -0.499 0.248)
			(stroke
				(width 0.15)
				(type solid)
			)
			(layer "F.Fab")
		)
		(fp_line
			(start -0.499 0.248)
			(end -0.499 -0.25)
			(stroke
				(width 0.15)
				(type solid)
			)
			(layer "F.Fab")
		)
		(pad "1" smd roundrect
			(at -0.484 0 90)
			(size 0.59 0.64)
			(layers "F.Cu" "F.Mask" "F.Paste")
			(roundrect_rratio 0.25)
			(net 1 "GND")
			(pintype "passive")
		)
		(pad "2" smd roundrect
			(at 0.484 0 90)
			(size 0.59 0.64)
			(layers "F.Cu" "F.Mask" "F.Paste")
			(roundrect_rratio 0.25)
			(net 6 "/Debug FTDI/FTDI_3V3")
			(pintype "passive")
		)
	)
	(footprint "antmicro-footprints:C_0603_1608Metric"
		(layer "F.Cu")
		(at 199.525 161.722)
		(descr "Capacitor SMD 0603")
		(tags "capacitor 0603")
		(property "Reference" "C192"
			(at -1.42757 -1.000252 0)
			(layer "F.SilkS")
			(hide yes)
			(effects
				(font
					(size 0.7 0.7)
					(thickness 0.15)
				)
				(justify left bottom)
			)
		)
		(property "Value" "C_22u_0603"
			(at -1.42757 1.770288 0)
			(layer "F.Fab")
			(effects
				(font
					(size 0.7 0.7)
					(thickness 0.15)
				)
				(justify left bottom)
			)
		)
		(property "Datasheet" "https://www.murata.com/products/productdetail?partno=GRM188R60J226MEA0%23"
			(at 0 0 0)
			(layer "F.Fab")
			(hide yes)
			(effects
				(font
					(size 1.27 1.27)
					(thickness 0.15)
				)
			)
		)
		(property "Author" "Antmicro"
			(at 0 0 0)
			(layer "F.Fab")
			(hide yes)
			(effects
				(font
					(size 1 1)
					(thickness 0.15)
				)
			)
		)
		(property "Dielectric" ""
			(at 0 0 0)
			(layer "F.Fab")
			(hide yes)
			(effects
				(font
					(size 1 1)
					(thickness 0.15)
				)
			)
		)
		(property "License" "Apache-2.0"
			(at 0 0 0)
			(layer "F.Fab")
			(hide yes)
			(effects
				(font
					(size 1 1)
					(thickness 0.15)
				)
			)
		)
		(property "MPN" "GRM188R60J226MEA0D"
			(at 0 0 0)
			(layer "F.Fab")
			(hide yes)
			(effects
				(font
					(size 1 1)
					(thickness 0.15)
				)
			)
		)
		(property "Manufacturer" "Murata"
			(at 0 0 0)
			(layer "F.Fab")
			(hide yes)
			(effects
				(font
					(size 1 1)
					(thickness 0.15)
				)
			)
		)
		(property "Val" "22u"
			(at 0 0 0)
			(layer "F.Fab")
			(hide yes)
			(effects
				(font
					(size 1 1)
					(thickness 0.15)
				)
			)
		)
		(property "Voltage" ""
			(at 0 0 0)
			(layer "F.Fab")
			(hide yes)
			(effects
				(font
					(size 1 1)
					(thickness 0.15)
				)
			)
		)
		(sheetname "/Supply/")
		(sheetfile "supply.kicad_sch")
		(attr smd)
		(fp_line
			(start -0.3 -0.3)
			(end 0.3 -0.3)
			(stroke
				(width 0.15)
				(type solid)
			)
			(layer "F.SilkS")
		)
		(fp_line
			(start -0.3 0.3)
			(end 0.3 0.3)
			(stroke
				(width 0.15)
				(type solid)
			)
			(layer "F.SilkS")
		)
		(fp_rect
			(start -1.24 -0.7)
			(end 1.24 0.7)
			(stroke
				(width 0.05)
				(type solid)
			)
			(fill no)
			(layer "F.CrtYd")
		)
		(fp_rect
			(start -0.8 -0.4)
			(end 0.8 0.4)
			(stroke
				(width 0.15)
				(type solid)
			)
			(fill no)
			(layer "F.Fab")
		)
		(pad "1" smd roundrect
			(at -0.7 0)
			(size 0.6 0.8)
			(layers "F.Cu" "F.Mask" "F.Paste")
			(roundrect_rratio 0.2)
			(net 1 "GND")
			(pintype "passive")
		)
		(pad "2" smd roundrect
			(at 0.7 0)
			(size 0.6 0.8)
			(layers "F.Cu" "F.Mask" "F.Paste")
			(roundrect_rratio 0.2)
			(net 53 "/Supply/1V1_local")
			(pintype "passive")
		)
	)
	(footprint "antmicro-footprints:SC70-3"
		(layer "F.Cu")
		(at 102.100501 115.476 180)
		(property "Reference" "Q9"
			(at 0 -1.6 180)
			(layer "F.SilkS")
			(hide yes)
			(effects
				(font
					(size 0.7 0.7)
					(thickness 0.15)
				)
				(justify left bottom)
			)
		)
		(property "Value" "BSS138PW,115"
			(at 0 2.3 180)
			(layer "F.Fab")
			(effects
				(font
					(size 0.7 0.7)
					(thickness 0.15)
				)
				(justify left bottom)
			)
		)
		(property "Datasheet" "https://assets.nexperia.com/documents/data-sheet/BSS138PW.pdf"
			(at 0 0 180)
			(layer "F.Fab")
			(hide yes)
			(effects
				(font
					(size 1.27 1.27)
					(thickness 0.15)
				)
			)
		)
		(property "Description" "Power MOSFET, N Channel, 60 V, 320 mA, 0.9 ohm, SOT-323, Surface Mount"
			(at 0 0 180)
			(layer "F.Fab")
			(hide yes)
			(effects
				(font
					(size 1.27 1.27)
					(thickness 0.15)
				)
			)
		)
		(property "Author" "Antmicro"
			(at 204.201002 230.952 0)
			(layer "F.Fab")
			(hide yes)
			(effects
				(font
					(size 1 1)
					(thickness 0.15)
				)
			)
		)
		(property "License" "Apache-2.0"
			(at 204.201002 230.952 0)
			(layer "F.Fab")
			(hide yes)
			(effects
				(font
					(size 1 1)
					(thickness 0.15)
				)
			)
		)
		(property "MPN" "BSS138PW,115"
			(at 204.201002 230.952 0)
			(layer "F.Fab")
			(hide yes)
			(effects
				(font
					(size 1 1)
					(thickness 0.15)
				)
			)
		)
		(property "Manufacturer" "Nexperia"
			(at 204.201002 230.952 0)
			(layer "F.Fab")
			(hide yes)
			(effects
				(font
					(size 1 1)
					(thickness 0.15)
				)
			)
		)
		(sheetname "/DDR5 SODIMM/")
		(sheetfile "ddr5-sodimm.kicad_sch")
		(attr smd)
		(fp_line
			(start 0.627 0.6)
			(end 0.627 1.001)
			(stroke
				(width 0.15)
				(type solid)
			)
			(layer "F.SilkS")
		)
		(fp_line
			(start 0.627 -0.6)
			(end 0.627 -0.999)
			(stroke
				(width 0.15)
				(type solid)
			)
			(layer "F.SilkS")
		)
		(fp_line
			(start -0.3 1)
			(end 0.627 1.001)
			(stroke
				(width 0.15)
				(type solid)
			)
			(layer "F.SilkS")
		)
		(fp_line
			(start -0.3 -1)
			(end 0.627 -0.999)
			(stroke
				(width 0.15)
				(type solid)
			)
			(layer "F.SilkS")
		)
		(fp_line
			(start 1.4 0.4)
			(end 0.9 0.4)
			(stroke
				(width 0.05)
				(type solid)
			)
			(layer "F.CrtYd")
		)
		(fp_line
			(start 1.4 -0.4)
			(end 1.4 0.4)
			(stroke
				(width 0.05)
				(type solid)
			)
			(layer "F.CrtYd")
		)
		(fp_line
			(start 0.9 1.3)
			(end -0.9 1.3)
			(stroke
				(width 0.05)
				(type solid)
			)
			(layer "F.CrtYd")
		)
		(fp_line
			(start 0.9 0.4)
			(end 0.9 1.3)
			(stroke
				(width 0.05)
				(type solid)
			)
			(layer "F.CrtYd")
		)
		(fp_line
			(start 0.9 -0.4)
			(end 1.4 -0.4)
			(stroke
				(width 0.05)
				(type solid)
			)
			(layer "F.CrtYd")
		)
		(fp_line
			(start 0.9 -1.3)
			(end 0.9 -0.4)
			(stroke
				(width 0.05)
				(type solid)
			)
			(layer "F.CrtYd")
		)
		(fp_line
			(start -0.9 1.3)
			(end -0.9 1)
			(stroke
				(width 0.05)
				(type solid)
			)
			(layer "F.CrtYd")
		)
		(fp_line
			(start -0.9 1)
			(end -1.4 1)
			(stroke
				(width 0.05)
				(type solid)
			)
			(layer "F.CrtYd")
		)
		(fp_line
			(start -0.9 -1)
			(end -1.4 -1)
			(stroke
				(width 0.05)
				(type solid)
			)
			(layer "F.CrtYd")
		)
		(fp_line
			(start -0.9 -1.3)
			(end 0.9 -1.3)
			(stroke
				(width 0.05)
				(type solid)
			)
			(layer "F.CrtYd")
		)
		(fp_line
			(start -0.9 -1.3)
			(end -0.9 -1)
			(stroke
				(width 0.05)
				(type solid)
			)
			(layer "F.CrtYd")
		)
		(fp_line
			(start -1.4 1)
			(end -1.4 -1)
			(stroke
				(width 0.05)
				(type solid)
			)
			(layer "F.CrtYd")
		)
		(fp_rect
			(start -0.623 -0.999)
			(end 0.627 1.001)
			(stroke
				(width 0.15)
				(type solid)
			)
			(fill no)
			(layer "F.Fab")
		)
		(pad "1" smd rect
			(at -1.051 -0.65 270)
			(size 0.6 0.6)
			(layers "F.Cu" "F.Mask" "F.Paste")
			(net 234 "HOT_SWAP_YELLOW")
			(pinfunction "G")
			(pintype "input")
		)
		(pad "2" smd rect
			(at -1.051 0.65 270)
			(size 0.6 0.6)
			(layers "F.Cu" "F.Mask" "F.Paste")
			(net 1 "GND")
			(pinfunction "S")
			(pintype "passive")
		)
		(pad "3" smd rect
			(at 1.05 0 270)
			(size 0.6 0.6)
			(layers "F.Cu" "F.Mask" "F.Paste")
			(net 358 "Net-(Q9-D)")
			(pinfunction "D")
			(pintype "passive")
		)
	)
	(footprint "antmicro-footprints:C_0402_1005Metric"
		(layer "F.Cu")
		(at 193.15 193.05 180)
		(descr "Capacitor SMD 0402")
		(tags "capacitor SMD 0402")
		(property "Reference" "C211"
			(at 0 -0.699 180)
			(layer "F.SilkS")
			(hide yes)
			(effects
				(font
					(size 0.7 0.7)
					(thickness 0.15)
				)
				(justify left bottom)
			)
		)
		(property "Value" "C_10u_6.3V_0402"
			(at -1.022927 2.155213 180)
			(layer "F.Fab")
			(effects
				(font
					(size 0.7 0.7)
					(thickness 0.15)
				)
				(justify left bottom)
			)
		)
		(property "Datasheet" "https://www.murata.com/products/productdetail?partno=GRM155R60J106ME15%23"
			(at 0 0 180)
			(layer "F.Fab")
			(hide yes)
			(effects
				(font
					(size 1.27 1.27)
					(thickness 0.15)
				)
			)
		)
		(property "Author" "Antmicro"
			(at 386.3 386.1 0)
			(layer "F.Fab")
			(hide yes)
			(effects
				(font
					(size 1 1)
					(thickness 0.15)
				)
			)
		)
		(property "Dielectric" "X5R"
			(at 386.3 386.1 0)
			(layer "F.Fab")
			(hide yes)
			(effects
				(font
					(size 1 1)
					(thickness 0.15)
				)
			)
		)
		(property "License" "Apache-2.0"
			(at 386.3 386.1 0)
			(layer "F.Fab")
			(hide yes)
			(effects
				(font
					(size 1 1)
					(thickness 0.15)
				)
			)
		)
		(property "MPN" "GRM155R60J106ME15D"
			(at 386.3 386.1 0)
			(layer "F.Fab")
			(hide yes)
			(effects
				(font
					(size 1 1)
					(thickness 0.15)
				)
			)
		)
		(property "Manufacturer" "Murata"
			(at 386.3 386.1 0)
			(layer "F.Fab")
			(hide yes)
			(effects
				(font
					(size 1 1)
					(thickness 0.15)
				)
			)
		)
		(property "Val" "10u"
			(at 386.3 386.1 0)
			(layer "F.Fab")
			(hide yes)
			(effects
				(font
					(size 1 1)
					(thickness 0.15)
				)
			)
		)
		(property "Voltage" "6.3V"
			(at 386.3 386.1 0)
			(layer "F.Fab")
			(hide yes)
			(effects
				(font
					(size 1 1)
					(thickness 0.15)
				)
			)
		)
		(sheetname "/Supply/")
		(sheetfile "supply.kicad_sch")
		(attr smd)
		(fp_rect
			(start -0.9659 -0.481258)
			(end 0.9649 0.458742)
			(stroke
				(width 0.05)
				(type solid)
			)
			(fill no)
			(layer "F.CrtYd")
		)
		(fp_line
			(start 0.499 0.248)
			(end -0.499 0.248)
			(stroke
				(width 0.15)
				(type solid)
			)
			(layer "F.Fab")
		)
		(fp_line
			(start 0.499 -0.25)
			(end 0.499 0.248)
			(stroke
				(width 0.15)
				(type solid)
			)
			(layer "F.Fab")
		)
		(fp_line
			(start -0.499 0.248)
			(end -0.499 -0.25)
			(stroke
				(width 0.15)
				(type solid)
			)
			(layer "F.Fab")
		)
		(fp_line
			(start -0.499 -0.25)
			(end 0.499 -0.25)
			(stroke
				(width 0.15)
				(type solid)
			)
			(layer "F.Fab")
		)
		(pad "1" smd roundrect
			(at -0.484 0 180)
			(size 0.59 0.64)
			(layers "F.Cu" "F.Mask" "F.Paste")
			(roundrect_rratio 0.25)
			(net 1 "GND")
			(pintype "passive")
		)
		(pad "2" smd roundrect
			(at 0.484 0 180)
			(size 0.59 0.64)
			(layers "F.Cu" "F.Mask" "F.Paste")
			(roundrect_rratio 0.25)
			(net 76 "/Supply/MGTAVTT_OUT")
			(pintype "passive")
		)
	)
	(footprint "antmicro-footprints:R_0402_1005Metric"
		(layer "F.Cu")
		(at 100.6 181.45 90)
		(descr "Resistor SMD 0402")
		(tags "resistor SMD 0402")
		(property "Reference" "R88"
			(at -1.122484 -0.772697 90)
			(layer "F.SilkS")
			(hide yes)
			(effects
				(font
					(size 0.7 0.7)
					(thickness 0.15)
				)
				(justify left bottom)
			)
		)
		(property "Value" "R_0R_0402"
			(at -1.011843 1.772047 90)
			(layer "F.Fab")
			(effects
				(font
					(size 0.7 0.7)
					(thickness 0.15)
				)
				(justify left bottom)
			)
		)
		(property "Datasheet" "https://industrial.panasonic.com/cdbs/www-data/pdf/RDA0000/AOA0000C301.pdf"
			(at 0 0 90)
			(layer "F.Fab")
			(hide yes)
			(effects
				(font
					(size 1.27 1.27)
					(thickness 0.15)
				)
			)
		)
		(property "Author" "Antmicro"
			(at 282.05 80.85 0)
			(layer "F.Fab")
			(hide yes)
			(effects
				(font
					(size 1 1)
					(thickness 0.15)
				)
			)
		)
		(property "Current" "1A"
			(at 282.05 80.85 0)
			(layer "F.Fab")
			(hide yes)
			(effects
				(font
					(size 1 1)
					(thickness 0.15)
				)
			)
		)
		(property "License" "Apache-2.0"
			(at 282.05 80.85 0)
			(layer "F.Fab")
			(hide yes)
			(effects
				(font
					(size 1 1)
					(thickness 0.15)
				)
			)
		)
		(property "MPN" "ERJ2GE0R00X"
			(at 282.05 80.85 0)
			(layer "F.Fab")
			(hide yes)
			(effects
				(font
					(size 1 1)
					(thickness 0.15)
				)
			)
		)
		(property "Manufacturer" "Panasonic"
			(at 282.05 80.85 0)
			(layer "F.Fab")
			(hide yes)
			(effects
				(font
					(size 1 1)
					(thickness 0.15)
				)
			)
		)
		(property "Tolerance" ""
			(at 282.05 80.85 0)
			(layer "F.Fab")
			(hide yes)
			(effects
				(font
					(size 1 1)
					(thickness 0.15)
				)
			)
		)
		(property "Val" "0R"
			(at 282.05 80.85 0)
			(layer "F.Fab")
			(hide yes)
			(effects
				(font
					(size 1 1)
					(thickness 0.15)
				)
			)
		)
		(sheetname "/Debug FTDI/")
		(sheetfile "debug-ftdi.kicad_sch")
		(attr smd)
		(fp_rect
			(start -0.93 -0.47)
			(end 0.93 0.47)
			(stroke
				(width 0.05)
				(type solid)
			)
			(fill no)
			(layer "F.CrtYd")
		)
		(fp_rect
			(start -0.5 -0.25)
			(end 0.5 0.25)
			(stroke
				(width 0.15)
				(type solid)
			)
			(fill no)
			(layer "F.Fab")
		)
		(pad "1" smd roundrect
			(at -0.485 0 90)
			(size 0.59 0.64)
			(layers "F.Cu" "F.Mask" "F.Paste")
			(roundrect_rratio 0.25)
			(net 383 "Net-(U13-OE)")
			(pintype "passive")
		)
		(pad "2" smd roundrect
			(at 0.485 0 90)
			(size 0.59 0.64)
			(layers "F.Cu" "F.Mask" "F.Paste")
			(roundrect_rratio 0.25)
			(net 652 "/Debug FTDI/BDBUS3")
			(pintype "passive")
		)
	)
	(footprint "antmicro-footprints:R_0402_1005Metric"
		(layer "F.Cu")
		(at 195.881001 161.922 180)
		(descr "Resistor SMD 0402")
		(tags "resistor SMD 0402")
		(property "Reference" "R157"
			(at 3.881001 -0.328 180)
			(layer "F.SilkS")
			(effects
				(font
					(size 0.7 0.7)
					(thickness 0.15)
				)
				(justify left bottom)
			)
		)
		(property "Value" "R_0R_0402"
			(at -1.011843 1.772047 180)
			(layer "F.Fab")
			(effects
				(font
					(size 0.7 0.7)
					(thickness 0.15)
				)
				(justify left bottom)
			)
		)
		(property "Datasheet" "https://industrial.panasonic.com/cdbs/www-data/pdf/RDA0000/AOA0000C301.pdf"
			(at 0 0 180)
			(layer "F.Fab")
			(hide yes)
			(effects
				(font
					(size 1.27 1.27)
					(thickness 0.15)
				)
			)
		)
		(property "Author" "Antmicro"
			(at 391.762002 323.844 0)
			(layer "F.Fab")
			(hide yes)
			(effects
				(font
					(size 1 1)
					(thickness 0.15)
				)
			)
		)
		(property "Current" "1A"
			(at 391.762002 323.844 0)
			(layer "F.Fab")
			(hide yes)
			(effects
				(font
					(size 1 1)
					(thickness 0.15)
				)
			)
		)
		(property "License" "Apache-2.0"
			(at 391.762002 323.844 0)
			(layer "F.Fab")
			(hide yes)
			(effects
				(font
					(size 1 1)
					(thickness 0.15)
				)
			)
		)
		(property "MPN" "ERJ2GE0R00X"
			(at 391.762002 323.844 0)
			(layer "F.Fab")
			(hide yes)
			(effects
				(font
					(size 1 1)
					(thickness 0.15)
				)
			)
		)
		(property "Manufacturer" "Panasonic"
			(at 391.762002 323.844 0)
			(layer "F.Fab")
			(hide yes)
			(effects
				(font
					(size 1 1)
					(thickness 0.15)
				)
			)
		)
		(property "Tolerance" ""
			(at 391.762002 323.844 0)
			(layer "F.Fab")
			(hide yes)
			(effects
				(font
					(size 1 1)
					(thickness 0.15)
				)
			)
		)
		(property "Val" "0R"
			(at 391.762002 323.844 0)
			(layer "F.Fab")
			(hide yes)
			(effects
				(font
					(size 1 1)
					(thickness 0.15)
				)
			)
		)
		(sheetname "/Supply/")
		(sheetfile "supply.kicad_sch")
		(attr smd)
		(fp_rect
			(start -0.93 -0.47)
			(end 0.93 0.47)
			(stroke
				(width 0.05)
				(type solid)
			)
			(fill no)
			(layer "F.CrtYd")
		)
		(fp_rect
			(start -0.5 -0.25)
			(end 0.5 0.25)
			(stroke
				(width 0.15)
				(type solid)
			)
			(fill no)
			(layer "F.Fab")
		)
		(pad "1" smd roundrect
			(at -0.485 0 180)
			(size 0.59 0.64)
			(layers "F.Cu" "F.Mask" "F.Paste")
			(roundrect_rratio 0.25)
			(net 208 "/Supply/FB6")
			(pintype "passive")
		)
		(pad "2" smd roundrect
			(at 0.485 0 180)
			(size 0.59 0.64)
			(layers "F.Cu" "F.Mask" "F.Paste")
			(roundrect_rratio 0.25)
			(net 60 "/Supply/5V_local")
			(pintype "passive")
		)
	)
	(footprint "antmicro-footprints:R_0402_1005Metric"
		(layer "F.Cu")
		(at 102 184.8 -90)
		(descr "Resistor SMD 0402")
		(tags "resistor SMD 0402")
		(property "Reference" "R95"
			(at -1.122484 -0.772697 270)
			(layer "F.SilkS")
			(hide yes)
			(effects
				(font
					(size 0.7 0.7)
					(thickness 0.15)
				)
				(justify left bottom)
			)
		)
		(property "Value" "R_4k7_0402"
			(at -1.011843 1.772047 270)
			(layer "F.Fab")
			(effects
				(font
					(size 0.7 0.7)
					(thickness 0.15)
				)
				(justify left bottom)
			)
		)
		(property "Datasheet" "https://www.bourns.com/docs/product-datasheets/cr.pdf"
			(at 0 0 270)
			(layer "F.Fab")
			(hide yes)
			(effects
				(font
					(size 1.27 1.27)
					(thickness 0.15)
				)
			)
		)
		(property "Author" "Antmicro"
			(at -82.8 286.8 0)
			(layer "F.Fab")
			(hide yes)
			(effects
				(font
					(size 1 1)
					(thickness 0.15)
				)
			)
		)
		(property "License" "Apache-2.0"
			(at -82.8 286.8 0)
			(layer "F.Fab")
			(hide yes)
			(effects
				(font
					(size 1 1)
					(thickness 0.15)
				)
			)
		)
		(property "MPN" "CR0402-FX-4701GLF"
			(at -82.8 286.8 0)
			(layer "F.Fab")
			(hide yes)
			(effects
				(font
					(size 1 1)
					(thickness 0.15)
				)
			)
		)
		(property "Manufacturer" "Bourns"
			(at -82.8 286.8 0)
			(layer "F.Fab")
			(hide yes)
			(effects
				(font
					(size 1 1)
					(thickness 0.15)
				)
			)
		)
		(property "Tolerance" "1%"
			(at -82.8 286.8 0)
			(layer "F.Fab")
			(hide yes)
			(effects
				(font
					(size 1 1)
					(thickness 0.15)
				)
			)
		)
		(property "Val" "4k7"
			(at -82.8 286.8 0)
			(layer "F.Fab")
			(hide yes)
			(effects
				(font
					(size 1 1)
					(thickness 0.15)
				)
			)
		)
		(sheetname "/Debug FTDI/")
		(sheetfile "debug-ftdi.kicad_sch")
		(attr smd)
		(fp_rect
			(start -0.93 -0.47)
			(end 0.93 0.47)
			(stroke
				(width 0.05)
				(type solid)
			)
			(fill no)
			(layer "F.CrtYd")
		)
		(fp_rect
			(start -0.5 -0.25)
			(end 0.5 0.25)
			(stroke
				(width 0.15)
				(type solid)
			)
			(fill no)
			(layer "F.Fab")
		)
		(pad "1" smd roundrect
			(at -0.485 0 270)
			(size 0.59 0.64)
			(layers "F.Cu" "F.Mask" "F.Paste")
			(roundrect_rratio 0.25)
			(net 41 "+3V3_AON")
			(pintype "passive")
		)
		(pad "2" smd roundrect
			(at 0.485 0 270)
			(size 0.59 0.64)
			(layers "F.Cu" "F.Mask" "F.Paste")
			(roundrect_rratio 0.25)
			(net 672 "/Debug FTDI/FTDI.SDA")
			(pintype "passive")
		)
	)
	(footprint "antmicro-footprints:NetTie-2_SMD_Pad0.127mm"
		(layer "F.Cu")
		(at 189.5 171.701)
		(descr "Net tie, 2 pin, 0.127mm  SMD pads")
		(tags "net tie")
		(property "Reference" "NT5"
			(at -0.128 -1.345 0)
			(layer "F.SilkS")
			(hide yes)
			(effects
				(font
					(size 0.7 0.7)
					(thickness 0.15)
				)
				(justify left bottom)
			)
		)
		(property "Value" "Net-Tie_P0.127mm"
			(at 0 1.199 0)
			(layer "F.Fab")
			(effects
				(font
					(size 0.7 0.7)
					(thickness 0.15)
				)
				(justify left bottom)
			)
		)
		(property "Author" "Antmicro"
			(at 0 0 0)
			(layer "F.Fab")
			(hide yes)
			(effects
				(font
					(size 1 1)
					(thickness 0.15)
				)
			)
		)
		(property "License" "Apache-2.0"
			(at 0 0 0)
			(layer "F.Fab")
			(hide yes)
			(effects
				(font
					(size 1 1)
					(thickness 0.15)
				)
			)
		)
		(property "MPN" ""
			(at 0 0 0)
			(layer "F.Fab")
			(hide yes)
			(effects
				(font
					(size 1 1)
					(thickness 0.15)
				)
			)
		)
		(property "Manufacturer" ""
			(at 0 0 0)
			(layer "F.Fab")
			(hide yes)
			(effects
				(font
					(size 1 1)
					(thickness 0.15)
				)
			)
		)
		(property ki_fp_filters "Net*Tie*")
		(sheetname "/Supply/")
		(sheetfile "supply.kicad_sch")
		(attr smd exclude_from_pos_files exclude_from_bom)
		(net_tie_pad_groups "1, 2")
		(fp_poly
			(pts
				(xy -0.0635 -0.0635) (xy 0.0625 -0.0635) (xy 0.0625 0.0635) (xy -0.0635 0.0635)
			)
			(stroke
				(width 0)
				(type solid)
			)
			(fill yes)
			(layer "F.Cu")
		)
		(pad "1" smd roundrect
			(at -0.127 0 180)
			(size 0.127 0.127)
			(layers "F.Cu")
			(roundrect_rratio 0.5)
			(chamfer_ratio 0)
			(chamfer top_left bottom_left)
			(net 243 "/Supply/3V3_SEN_+")
			(pinfunction "1")
			(pintype "passive")
		)
		(pad "2" smd roundrect
			(at 0.126 0)
			(size 0.127 0.127)
			(layers "F.Cu")
			(roundrect_rratio 0.5)
			(chamfer_ratio 0)
			(chamfer top_left bottom_left)
			(net 52 "/Supply/3V3_local")
			(pinfunction "2")
			(pintype "passive")
		)
	)
	(footprint "antmicro-footprints:C_0603_1608Metric"
		(layer "F.Cu")
		(at 191.168501 165.472 90)
		(descr "Capacitor SMD 0603")
		(tags "capacitor 0603")
		(property "Reference" "C191"
			(at -1.42757 -1.000252 90)
			(layer "F.SilkS")
			(hide yes)
			(effects
				(font
					(size 0.7 0.7)
					(thickness 0.15)
				)
				(justify left bottom)
			)
		)
		(property "Value" "C_22u_0603"
			(at -1.42757 1.770288 90)
			(layer "F.Fab")
			(effects
				(font
					(size 0.7 0.7)
					(thickness 0.15)
				)
				(justify left bottom)
			)
		)
		(property "Datasheet" "https://www.murata.com/products/productdetail?partno=GRM188R60J226MEA0%23"
			(at 0 0 90)
			(layer "F.Fab")
			(hide yes)
			(effects
				(font
					(size 1.27 1.27)
					(thickness 0.15)
				)
			)
		)
		(property "Author" "Antmicro"
			(at 356.640501 -25.696501 0)
			(layer "F.Fab")
			(hide yes)
			(effects
				(font
					(size 1 1)
					(thickness 0.15)
				)
			)
		)
		(property "Dielectric" ""
			(at 356.640501 -25.696501 0)
			(layer "F.Fab")
			(hide yes)
			(effects
				(font
					(size 1 1)
					(thickness 0.15)
				)
			)
		)
		(property "License" "Apache-2.0"
			(at 356.640501 -25.696501 0)
			(layer "F.Fab")
			(hide yes)
			(effects
				(font
					(size 1 1)
					(thickness 0.15)
				)
			)
		)
		(property "MPN" "GRM188R60J226MEA0D"
			(at 356.640501 -25.696501 0)
			(layer "F.Fab")
			(hide yes)
			(effects
				(font
					(size 1 1)
					(thickness 0.15)
				)
			)
		)
		(property "Manufacturer" "Murata"
			(at 356.640501 -25.696501 0)
			(layer "F.Fab")
			(hide yes)
			(effects
				(font
					(size 1 1)
					(thickness 0.15)
				)
			)
		)
		(property "Val" "22u"
			(at 356.640501 -25.696501 0)
			(layer "F.Fab")
			(hide yes)
			(effects
				(font
					(size 1 1)
					(thickness 0.15)
				)
			)
		)
		(property "Voltage" ""
			(at 356.640501 -25.696501 0)
			(layer "F.Fab")
			(hide yes)
			(effects
				(font
					(size 1 1)
					(thickness 0.15)
				)
			)
		)
		(sheetname "/Supply/")
		(sheetfile "supply.kicad_sch")
		(attr smd)
		(fp_line
			(start -0.3 -0.3)
			(end 0.3 -0.3)
			(stroke
				(width 0.15)
				(type solid)
			)
			(layer "F.SilkS")
		)
		(fp_line
			(start -0.3 0.3)
			(end 0.3 0.3)
			(stroke
				(width 0.15)
				(type solid)
			)
			(layer "F.SilkS")
		)
		(fp_rect
			(start -1.24 -0.7)
			(end 1.24 0.7)
			(stroke
				(width 0.05)
				(type solid)
			)
			(fill no)
			(layer "F.CrtYd")
		)
		(fp_rect
			(start -0.8 -0.4)
			(end 0.8 0.4)
			(stroke
				(width 0.15)
				(type solid)
			)
			(fill no)
			(layer "F.Fab")
		)
		(pad "1" smd roundrect
			(at -0.7 0 90)
			(size 0.6 0.8)
			(layers "F.Cu" "F.Mask" "F.Paste")
			(roundrect_rratio 0.2)
			(net 1 "GND")
			(pintype "passive")
		)
		(pad "2" smd roundrect
			(at 0.7 0 90)
			(size 0.6 0.8)
			(layers "F.Cu" "F.Mask" "F.Paste")
			(roundrect_rratio 0.2)
			(net 60 "/Supply/5V_local")
			(pintype "passive")
		)
	)
	(footprint "antmicro-footprints:C_0603_1608Metric"
		(layer "F.Cu")
		(at 168.655501 194.114502 180)
		(descr "Capacitor SMD 0603")
		(tags "capacitor 0603")
		(property "Reference" "C213"
			(at -1.42757 -1.000252 180)
			(layer "F.SilkS")
			(hide yes)
			(effects
				(font
					(size 0.7 0.7)
					(thickness 0.15)
				)
				(justify left bottom)
			)
		)
		(property "Value" "C_22u_0603"
			(at -1.42757 1.770288 180)
			(layer "F.Fab")
			(effects
				(font
					(size 0.7 0.7)
					(thickness 0.15)
				)
				(justify left bottom)
			)
		)
		(property "Datasheet" "https://www.murata.com/products/productdetail?partno=GRM188R60J226MEA0%23"
			(at 0 0 180)
			(layer "F.Fab")
			(hide yes)
			(effects
				(font
					(size 1.27 1.27)
					(thickness 0.15)
				)
			)
		)
		(property "Author" "Antmicro"
			(at 337.311002 388.229004 0)
			(layer "F.Fab")
			(hide yes)
			(effects
				(font
					(size 1 1)
					(thickness 0.15)
				)
			)
		)
		(property "Dielectric" ""
			(at 337.311002 388.229004 0)
			(layer "F.Fab")
			(hide yes)
			(effects
				(font
					(size 1 1)
					(thickness 0.15)
				)
			)
		)
		(property "License" "Apache-2.0"
			(at 337.311002 388.229004 0)
			(layer "F.Fab")
			(hide yes)
			(effects
				(font
					(size 1 1)
					(thickness 0.15)
				)
			)
		)
		(property "MPN" "GRM188R60J226MEA0D"
			(at 337.311002 388.229004 0)
			(layer "F.Fab")
			(hide yes)
			(effects
				(font
					(size 1 1)
					(thickness 0.15)
				)
			)
		)
		(property "Manufacturer" "Murata"
			(at 337.311002 388.229004 0)
			(layer "F.Fab")
			(hide yes)
			(effects
				(font
					(size 1 1)
					(thickness 0.15)
				)
			)
		)
		(property "Val" "22u"
			(at 337.311002 388.229004 0)
			(layer "F.Fab")
			(hide yes)
			(effects
				(font
					(size 1 1)
					(thickness 0.15)
				)
			)
		)
		(property "Voltage" ""
			(at 337.311002 388.229004 0)
			(layer "F.Fab")
			(hide yes)
			(effects
				(font
					(size 1 1)
					(thickness 0.15)
				)
			)
		)
		(sheetname "/Supply/")
		(sheetfile "supply.kicad_sch")
		(attr smd)
		(fp_line
			(start -0.3 0.3)
			(end 0.3 0.3)
			(stroke
				(width 0.15)
				(type solid)
			)
			(layer "F.SilkS")
		)
		(fp_line
			(start -0.3 -0.3)
			(end 0.3 -0.3)
			(stroke
				(width 0.15)
				(type solid)
			)
			(layer "F.SilkS")
		)
		(fp_rect
			(start -1.24 -0.7)
			(end 1.24 0.7)
			(stroke
				(width 0.05)
				(type solid)
			)
			(fill no)
			(layer "F.CrtYd")
		)
		(fp_rect
			(start -0.8 -0.4)
			(end 0.8 0.4)
			(stroke
				(width 0.15)
				(type solid)
			)
			(fill no)
			(layer "F.Fab")
		)
		(pad "1" smd roundrect
			(at -0.7 0 180)
			(size 0.6 0.8)
			(layers "F.Cu" "F.Mask" "F.Paste")
			(roundrect_rratio 0.2)
			(net 1 "GND")
			(pintype "passive")
		)
		(pad "2" smd roundrect
			(at 0.7 0 180)
			(size 0.6 0.8)
			(layers "F.Cu" "F.Mask" "F.Paste")
			(roundrect_rratio 0.2)
			(net 78 "/Supply/1V0_REG")
			(pintype "passive")
		)
	)
	(footprint "antmicro-footprints:R_0402_1005Metric"
		(layer "F.Cu")
		(at 90.748501 126.731921 -90)
		(descr "Resistor SMD 0402")
		(tags "resistor SMD 0402")
		(property "Reference" "R16"
			(at -1.122484 -0.772697 270)
			(layer "F.SilkS")
			(hide yes)
			(effects
				(font
					(size 0.7 0.7)
					(thickness 0.15)
				)
				(justify left bottom)
			)
		)
		(property "Value" "R_4k7_0402"
			(at -1.011843 1.772047 270)
			(layer "F.Fab")
			(effects
				(font
					(size 0.7 0.7)
					(thickness 0.15)
				)
				(justify left bottom)
			)
		)
		(property "Datasheet" "https://www.bourns.com/docs/product-datasheets/cr.pdf"
			(at 0 0 270)
			(layer "F.Fab")
			(hide yes)
			(effects
				(font
					(size 1.27 1.27)
					(thickness 0.15)
				)
			)
		)
		(property "Author" "Antmicro"
			(at -35.98342 217.480422 0)
			(layer "F.Fab")
			(hide yes)
			(effects
				(font
					(size 1 1)
					(thickness 0.15)
				)
			)
		)
		(property "License" "Apache-2.0"
			(at -35.98342 217.480422 0)
			(layer "F.Fab")
			(hide yes)
			(effects
				(font
					(size 1 1)
					(thickness 0.15)
				)
			)
		)
		(property "MPN" "CR0402-FX-4701GLF"
			(at -35.98342 217.480422 0)
			(layer "F.Fab")
			(hide yes)
			(effects
				(font
					(size 1 1)
					(thickness 0.15)
				)
			)
		)
		(property "Manufacturer" "Bourns"
			(at -35.98342 217.480422 0)
			(layer "F.Fab")
			(hide yes)
			(effects
				(font
					(size 1 1)
					(thickness 0.15)
				)
			)
		)
		(property "Tolerance" "1%"
			(at -35.98342 217.480422 0)
			(layer "F.Fab")
			(hide yes)
			(effects
				(font
					(size 1 1)
					(thickness 0.15)
				)
			)
		)
		(property "Val" "4k7"
			(at -35.98342 217.480422 0)
			(layer "F.Fab")
			(hide yes)
			(effects
				(font
					(size 1 1)
					(thickness 0.15)
				)
			)
		)
		(sheetname "/FPGA Config/")
		(sheetfile "fpga-config.kicad_sch")
		(attr smd)
		(fp_rect
			(start -0.93 -0.47)
			(end 0.93 0.47)
			(stroke
				(width 0.05)
				(type solid)
			)
			(fill no)
			(layer "F.CrtYd")
		)
		(fp_rect
			(start -0.5 -0.25)
			(end 0.5 0.25)
			(stroke
				(width 0.15)
				(type solid)
			)
			(fill no)
			(layer "F.Fab")
		)
		(pad "1" smd roundrect
			(at -0.485 0 270)
			(size 0.59 0.64)
			(layers "F.Cu" "F.Mask" "F.Paste")
			(roundrect_rratio 0.25)
			(net 200 "+3V3")
			(pintype "passive")
		)
		(pad "2" smd roundrect
			(at 0.485 0 270)
			(size 0.59 0.64)
			(layers "F.Cu" "F.Mask" "F.Paste")
			(roundrect_rratio 0.25)
			(net 614 "/FPGA Config/INIT_B")
			(pintype "passive")
		)
	)
	(footprint "antmicro-footprints:C_0402_1005Metric"
		(layer "F.Cu")
		(at 183.115 128.2)
		(descr "Capacitor SMD 0402")
		(tags "capacitor SMD 0402")
		(property "Reference" "C127"
			(at 0 -0.699 0)
			(layer "F.SilkS")
			(hide yes)
			(effects
				(font
					(size 0.7 0.7)
					(thickness 0.15)
				)
				(justify left bottom)
			)
		)
		(property "Value" "C_1u_0402"
			(at -1.022927 2.155213 0)
			(layer "F.Fab")
			(effects
				(font
					(size 0.7 0.7)
					(thickness 0.15)
				)
				(justify left bottom)
			)
		)
		(property "Datasheet" "https://product.tdk.com/en/search/capacitor/ceramic/mlcc/info?part_no=C1005X6S1A105K050BC"
			(at 0 0 0)
			(layer "F.Fab")
			(hide yes)
			(effects
				(font
					(size 1.27 1.27)
					(thickness 0.15)
				)
			)
		)
		(property "Author" "Antmicro"
			(at 0 0 0)
			(layer "F.Fab")
			(hide yes)
			(effects
				(font
					(size 1 1)
					(thickness 0.15)
				)
			)
		)
		(property "Dielectric" ""
			(at 0 0 0)
			(layer "F.Fab")
			(hide yes)
			(effects
				(font
					(size 1 1)
					(thickness 0.15)
				)
			)
		)
		(property "License" "Apache-2.0"
			(at 0 0 0)
			(layer "F.Fab")
			(hide yes)
			(effects
				(font
					(size 1 1)
					(thickness 0.15)
				)
			)
		)
		(property "MPN" "C1005X6S1A105K050BC"
			(at 0 0 0)
			(layer "F.Fab")
			(hide yes)
			(effects
				(font
					(size 1 1)
					(thickness 0.15)
				)
			)
		)
		(property "Manufacturer" "TDK"
			(at 0 0 0)
			(layer "F.Fab")
			(hide yes)
			(effects
				(font
					(size 1 1)
					(thickness 0.15)
				)
			)
		)
		(property "Val" "1u"
			(at 0 0 0)
			(layer "F.Fab")
			(hide yes)
			(effects
				(font
					(size 1 1)
					(thickness 0.15)
				)
			)
		)
		(property "Voltage" ""
			(at 0 0 0)
			(layer "F.Fab")
			(hide yes)
			(effects
				(font
					(size 1 1)
					(thickness 0.15)
				)
			)
		)
		(sheetname "/DDR5 SODIMM/")
		(sheetfile "ddr5-sodimm.kicad_sch")
		(attr exclude_from_pos_files exclude_from_bom dnp)
		(fp_rect
			(start -0.9659 -0.481258)
			(end 0.9649 0.458742)
			(stroke
				(width 0.05)
				(type solid)
			)
			(fill no)
			(layer "F.CrtYd")
		)
		(fp_line
			(start -0.499 -0.25)
			(end 0.499 -0.25)
			(stroke
				(width 0.15)
				(type solid)
			)
			(layer "F.Fab")
		)
		(fp_line
			(start -0.499 0.248)
			(end -0.499 -0.25)
			(stroke
				(width 0.15)
				(type solid)
			)
			(layer "F.Fab")
		)
		(fp_line
			(start 0.499 -0.25)
			(end 0.499 0.248)
			(stroke
				(width 0.15)
				(type solid)
			)
			(layer "F.Fab")
		)
		(fp_line
			(start 0.499 0.248)
			(end -0.499 0.248)
			(stroke
				(width 0.15)
				(type solid)
			)
			(layer "F.Fab")
		)
		(pad "1" smd roundrect
			(at -0.484 0)
			(size 0.59 0.64)
			(layers "F.Cu" "F.Mask" "F.Paste")
			(roundrect_rratio 0.25)
			(net 106 "HOT_SWAP_BUTTON")
			(pintype "passive")
		)
		(pad "2" smd roundrect
			(at 0.484 0)
			(size 0.59 0.64)
			(layers "F.Cu" "F.Mask" "F.Paste")
			(roundrect_rratio 0.25)
			(net 1 "GND")
			(pintype "passive")
		)
	)
	(footprint "antmicro-footprints:F_1206_3216Metric"
		(layer "F.Cu")
		(at 188.15 128.6 -90)
		(property "Reference" "F1"
			(at -0.6 -2.25 270)
			(layer "F.SilkS")
			(effects
				(font
					(size 0.7 0.7)
					(thickness 0.15)
				)
				(justify left bottom)
			)
		)
		(property "Value" "F_4A_1206"
			(at 0 2 270)
			(layer "F.Fab")
			(effects
				(font
					(size 0.7 0.7)
					(thickness 0.15)
				)
				(justify left bottom)
			)
		)
		(property "Datasheet" "https://www.littelfuse.com/media?resourcetype=datasheets&itemid=dbe9bcd7-6072-4adf-bf5b-d33e52a6b90f&filename=littelfuse-fuse-466-datasheet"
			(at 0 0 270)
			(layer "F.Fab")
			(hide yes)
			(effects
				(font
					(size 1.27 1.27)
					(thickness 0.15)
				)
			)
		)
		(property "Author" "Antmicro"
			(at 59.55 316.75 0)
			(layer "F.Fab")
			(hide yes)
			(effects
				(font
					(size 1 1)
					(thickness 0.15)
				)
			)
		)
		(property "License" "Apache-2.0"
			(at 59.55 316.75 0)
			(layer "F.Fab")
			(hide yes)
			(effects
				(font
					(size 1 1)
					(thickness 0.15)
				)
			)
		)
		(property "MPN" "0466004.NR "
			(at 59.55 316.75 0)
			(layer "F.Fab")
			(hide yes)
			(effects
				(font
					(size 1 1)
					(thickness 0.15)
				)
			)
		)
		(property "Manufacturer" "Littelfuse"
			(at 59.55 316.75 0)
			(layer "F.Fab")
			(hide yes)
			(effects
				(font
					(size 1 1)
					(thickness 0.15)
				)
			)
		)
		(sheetname "/Supply/")
		(sheetfile "supply.kicad_sch")
		(attr smd)
		(fp_line
			(start -0.413 0.792)
			(end 0.36 0.792)
			(stroke
				(width 0.15)
				(type solid)
			)
			(layer "F.SilkS")
		)
		(fp_line
			(start -0.413 -0.861)
			(end 0.36 -0.861)
			(stroke
				(width 0.15)
				(type solid)
			)
			(layer "F.SilkS")
		)
		(fp_rect
			(start -1.95 -1)
			(end 1.95 1)
			(stroke
				(width 0.05)
				(type solid)
			)
			(fill no)
			(layer "F.CrtYd")
		)
		(fp_line
			(start -1.677 0.792)
			(end -1.677 -0.861)
			(stroke
				(width 0.15)
				(type solid)
			)
			(layer "F.Fab")
		)
		(fp_line
			(start 1.624 0.792)
			(end -1.677 0.792)
			(stroke
				(width 0.15)
				(type solid)
			)
			(layer "F.Fab")
		)
		(fp_line
			(start -1.677 -0.861)
			(end 1.624 -0.861)
			(stroke
				(width 0.15)
				(type solid)
			)
			(layer "F.Fab")
		)
		(fp_line
			(start 1.624 -0.861)
			(end 1.624 0.792)
			(stroke
				(width 0.15)
				(type solid)
			)
			(layer "F.Fab")
		)
		(pad "1" smd rect
			(at -1.35 0 270)
			(size 1.143 2.032)
			(layers "F.Cu" "F.Mask" "F.Paste")
			(net 597 "/Supply/12V_aux")
			(pintype "passive")
		)
		(pad "2" smd rect
			(at 1.35 0 270)
			(size 1.143 2.032)
			(layers "F.Cu" "F.Mask" "F.Paste")
			(net 595 "/Supply/12V_aux_fused")
			(pintype "passive")
		)
	)
	(footprint "antmicro-footprints:C_0402_1005Metric"
		(layer "F.Cu")
		(at 184.991759 130.907099)
		(descr "Capacitor SMD 0402")
		(tags "capacitor SMD 0402")
		(property "Reference" "C175"
			(at 0 -0.699 0)
			(layer "F.SilkS")
			(hide yes)
			(effects
				(font
					(size 0.7 0.7)
					(thickness 0.15)
				)
				(justify left bottom)
			)
		)
		(property "Value" "C_100n_0402"
			(at -1.022927 2.155213 0)
			(layer "F.Fab")
			(effects
				(font
					(size 0.7 0.7)
					(thickness 0.15)
				)
				(justify left bottom)
			)
		)
		(property "Datasheet" "https://www.murata.com/products/productdetail?partno=GRM155R61H104KE14%23"
			(at 0 0 0)
			(layer "F.Fab")
			(hide yes)
			(effects
				(font
					(size 1.27 1.27)
					(thickness 0.15)
				)
			)
		)
		(property "Author" "Antmicro"
			(at 0 0 0)
			(layer "F.Fab")
			(hide yes)
			(effects
				(font
					(size 1 1)
					(thickness 0.15)
				)
			)
		)
		(property "Dielectric" "X5R"
			(at 0 0 0)
			(layer "F.Fab")
			(hide yes)
			(effects
				(font
					(size 1 1)
					(thickness 0.15)
				)
			)
		)
		(property "License" "Apache-2.0"
			(at 0 0 0)
			(layer "F.Fab")
			(hide yes)
			(effects
				(font
					(size 1 1)
					(thickness 0.15)
				)
			)
		)
		(property "MPN" "GRM155R61H104KE14D"
			(at 0 0 0)
			(layer "F.Fab")
			(hide yes)
			(effects
				(font
					(size 1 1)
					(thickness 0.15)
				)
			)
		)
		(property "Manufacturer" "Murata"
			(at 0 0 0)
			(layer "F.Fab")
			(hide yes)
			(effects
				(font
					(size 1 1)
					(thickness 0.15)
				)
			)
		)
		(property "Val" "100n"
			(at 0 0 0)
			(layer "F.Fab")
			(hide yes)
			(effects
				(font
					(size 1 1)
					(thickness 0.15)
				)
			)
		)
		(property "Voltage" "50V"
			(at 0 0 0)
			(layer "F.Fab")
			(hide yes)
			(effects
				(font
					(size 1 1)
					(thickness 0.15)
				)
			)
		)
		(sheetname "/Supply/")
		(sheetfile "supply.kicad_sch")
		(attr smd)
		(fp_rect
			(start -0.9659 -0.481258)
			(end 0.9649 0.458742)
			(stroke
				(width 0.05)
				(type solid)
			)
			(fill no)
			(layer "F.CrtYd")
		)
		(fp_line
			(start -0.499 -0.25)
			(end 0.499 -0.25)
			(stroke
				(width 0.15)
				(type solid)
			)
			(layer "F.Fab")
		)
		(fp_line
			(start -0.499 0.248)
			(end -0.499 -0.25)
			(stroke
				(width 0.15)
				(type solid)
			)
			(layer "F.Fab")
		)
		(fp_line
			(start 0.499 -0.25)
			(end 0.499 0.248)
			(stroke
				(width 0.15)
				(type solid)
			)
			(layer "F.Fab")
		)
		(fp_line
			(start 0.499 0.248)
			(end -0.499 0.248)
			(stroke
				(width 0.15)
				(type solid)
			)
			(layer "F.Fab")
		)
		(pad "1" smd roundrect
			(at -0.484 0)
			(size 0.59 0.64)
			(layers "F.Cu" "F.Mask" "F.Paste")
			(roundrect_rratio 0.25)
			(net 1 "GND")
			(pintype "passive")
		)
		(pad "2" smd roundrect
			(at 0.484 0)
			(size 0.59 0.64)
			(layers "F.Cu" "F.Mask" "F.Paste")
			(roundrect_rratio 0.25)
			(net 595 "/Supply/12V_aux_fused")
			(pintype "passive")
		)
	)
	(footprint "antmicro-footprints:C_0603_1608Metric"
		(layer "F.Cu")
		(at 199.995501 179.073)
		(descr "Capacitor SMD 0603")
		(tags "capacitor 0603")
		(property "Reference" "C188"
			(at -1.42757 -1.000252 0)
			(layer "F.SilkS")
			(hide yes)
			(effects
				(font
					(size 0.7 0.7)
					(thickness 0.15)
				)
				(justify left bottom)
			)
		)
		(property "Value" "C_22u_0603"
			(at -1.42757 1.770288 0)
			(layer "F.Fab")
			(effects
				(font
					(size 0.7 0.7)
					(thickness 0.15)
				)
				(justify left bottom)
			)
		)
		(property "Datasheet" "https://www.murata.com/products/productdetail?partno=GRM188R60J226MEA0%23"
			(at 0 0 0)
			(layer "F.Fab")
			(hide yes)
			(effects
				(font
					(size 1.27 1.27)
					(thickness 0.15)
				)
			)
		)
		(property "Author" "Antmicro"
			(at 0 0 0)
			(layer "F.Fab")
			(hide yes)
			(effects
				(font
					(size 1 1)
					(thickness 0.15)
				)
			)
		)
		(property "Dielectric" ""
			(at 0 0 0)
			(layer "F.Fab")
			(hide yes)
			(effects
				(font
					(size 1 1)
					(thickness 0.15)
				)
			)
		)
		(property "License" "Apache-2.0"
			(at 0 0 0)
			(layer "F.Fab")
			(hide yes)
			(effects
				(font
					(size 1 1)
					(thickness 0.15)
				)
			)
		)
		(property "MPN" "GRM188R60J226MEA0D"
			(at 0 0 0)
			(layer "F.Fab")
			(hide yes)
			(effects
				(font
					(size 1 1)
					(thickness 0.15)
				)
			)
		)
		(property "Manufacturer" "Murata"
			(at 0 0 0)
			(layer "F.Fab")
			(hide yes)
			(effects
				(font
					(size 1 1)
					(thickness 0.15)
				)
			)
		)
		(property "Val" "22u"
			(at 0 0 0)
			(layer "F.Fab")
			(hide yes)
			(effects
				(font
					(size 1 1)
					(thickness 0.15)
				)
			)
		)
		(property "Voltage" ""
			(at 0 0 0)
			(layer "F.Fab")
			(hide yes)
			(effects
				(font
					(size 1 1)
					(thickness 0.15)
				)
			)
		)
		(sheetname "/Supply/")
		(sheetfile "supply.kicad_sch")
		(attr smd)
		(fp_line
			(start -0.3 -0.3)
			(end 0.3 -0.3)
			(stroke
				(width 0.15)
				(type solid)
			)
			(layer "F.SilkS")
		)
		(fp_line
			(start -0.3 0.3)
			(end 0.3 0.3)
			(stroke
				(width 0.15)
				(type solid)
			)
			(layer "F.SilkS")
		)
		(fp_rect
			(start -1.24 -0.7)
			(end 1.24 0.7)
			(stroke
				(width 0.05)
				(type solid)
			)
			(fill no)
			(layer "F.CrtYd")
		)
		(fp_rect
			(start -0.8 -0.4)
			(end 0.8 0.4)
			(stroke
				(width 0.15)
				(type solid)
			)
			(fill no)
			(layer "F.Fab")
		)
		(pad "1" smd roundrect
			(at -0.7 0)
			(size 0.6 0.8)
			(layers "F.Cu" "F.Mask" "F.Paste")
			(roundrect_rratio 0.2)
			(net 1 "GND")
			(pintype "passive")
		)
		(pad "2" smd roundrect
			(at 0.7 0)
			(size 0.6 0.8)
			(layers "F.Cu" "F.Mask" "F.Paste")
			(roundrect_rratio 0.2)
			(net 35 "/Supply/spare_local")
			(pintype "passive")
		)
	)
	(footprint "antmicro-footprints:TP_SMD_1mm"
		(layer "F.Cu")
		(at 186.4 167.45)
		(property "Reference" "TP11"
			(at 0 -0.731898 0)
			(layer "F.SilkS")
			(hide yes)
			(effects
				(font
					(size 0.7 0.7)
					(thickness 0.15)
				)
				(justify left bottom)
			)
		)
		(property "Value" "TP_1mm_SMD"
			(at 0 1.4 0)
			(layer "F.Fab")
			(effects
				(font
					(size 0.7 0.7)
					(thickness 0.15)
				)
				(justify left bottom)
			)
		)
		(property "Author" "Antmicro"
			(at 0 0 0)
			(layer "F.Fab")
			(hide yes)
			(effects
				(font
					(size 1 1)
					(thickness 0.15)
				)
			)
		)
		(property "License" "Apache-2.0"
			(at 0 0 0)
			(layer "F.Fab")
			(hide yes)
			(effects
				(font
					(size 1 1)
					(thickness 0.15)
				)
			)
		)
		(property "MPN" ""
			(at 0 0 0)
			(layer "F.Fab")
			(hide yes)
			(effects
				(font
					(size 1 1)
					(thickness 0.15)
				)
			)
		)
		(property "Manufacturer" ""
			(at 0 0 0)
			(layer "F.Fab")
			(hide yes)
			(effects
				(font
					(size 1 1)
					(thickness 0.15)
				)
			)
		)
		(sheetname "/Supply/")
		(sheetfile "supply.kicad_sch")
		(attr exclude_from_pos_files)
		(pad "1" smd circle
			(at 0 0)
			(size 1 1)
			(layers "F.Cu" "F.Mask")
			(net 200 "+3V3")
			(pinfunction "1")
			(pintype "passive")
		)
	)
	(footprint "antmicro-footprints:R_0402_1005Metric"
		(layer "F.Cu")
		(at 86.350501 119.926 -90)
		(descr "Resistor SMD 0402")
		(tags "resistor SMD 0402")
		(property "Reference" "R42"
			(at -1.122484 -0.772697 270)
			(layer "F.SilkS")
			(hide yes)
			(effects
				(font
					(size 0.7 0.7)
					(thickness 0.15)
				)
				(justify left bottom)
			)
		)
		(property "Value" "R_330R_0402"
			(at -1.011843 1.772047 270)
			(layer "F.Fab")
			(effects
				(font
					(size 0.7 0.7)
					(thickness 0.15)
				)
				(justify left bottom)
			)
		)
		(property "Datasheet" "https://www.bourns.com/docs/product-datasheets/cr.pdf"
			(at 0 0 270)
			(layer "F.Fab")
			(hide yes)
			(effects
				(font
					(size 1.27 1.27)
					(thickness 0.15)
				)
			)
		)
		(property "Author" "Antmicro"
			(at -33.575499 206.276501 0)
			(layer "F.Fab")
			(hide yes)
			(effects
				(font
					(size 1 1)
					(thickness 0.15)
				)
			)
		)
		(property "License" "Apache-2.0"
			(at -33.575499 206.276501 0)
			(layer "F.Fab")
			(hide yes)
			(effects
				(font
					(size 1 1)
					(thickness 0.15)
				)
			)
		)
		(property "MPN" "CR0402-FX-3300GLF"
			(at -33.575499 206.276501 0)
			(layer "F.Fab")
			(hide yes)
			(effects
				(font
					(size 1 1)
					(thickness 0.15)
				)
			)
		)
		(property "Manufacturer" "Bourns"
			(at -33.575499 206.276501 0)
			(layer "F.Fab")
			(hide yes)
			(effects
				(font
					(size 1 1)
					(thickness 0.15)
				)
			)
		)
		(property "Tolerance" "1%"
			(at -33.575499 206.276501 0)
			(layer "F.Fab")
			(hide yes)
			(effects
				(font
					(size 1 1)
					(thickness 0.15)
				)
			)
		)
		(property "Val" "330R"
			(at -33.575499 206.276501 0)
			(layer "F.Fab")
			(hide yes)
			(effects
				(font
					(size 1 1)
					(thickness 0.15)
				)
			)
		)
		(sheetname "/FPGA bank 14/")
		(sheetfile "fpga-bank-14.kicad_sch")
		(attr smd)
		(fp_rect
			(start -0.93 -0.47)
			(end 0.93 0.47)
			(stroke
				(width 0.05)
				(type solid)
			)
			(fill no)
			(layer "F.CrtYd")
		)
		(fp_rect
			(start -0.5 -0.25)
			(end 0.5 0.25)
			(stroke
				(width 0.15)
				(type solid)
			)
			(fill no)
			(layer "F.Fab")
		)
		(pad "1" smd roundrect
			(at -0.485 0 270)
			(size 0.59 0.64)
			(layers "F.Cu" "F.Mask" "F.Paste")
			(roundrect_rratio 0.25)
			(net 309 "Net-(D6-Pad2)")
			(pintype "passive")
		)
		(pad "2" smd roundrect
			(at 0.485 0 270)
			(size 0.59 0.64)
			(layers "F.Cu" "F.Mask" "F.Paste")
			(roundrect_rratio 0.25)
			(net 355 "Net-(Q6-D)")
			(pintype "passive")
		)
	)
	(footprint "antmicro-footprints:R_1206_3216Metric"
		(layer "F.Cu")
		(at 199 191.325 180)
		(property "Reference" "R144"
			(at 0.8 -2.025 180)
			(layer "F.SilkS")
			(effects
				(font
					(size 0.7 0.7)
					(thickness 0.15)
				)
				(justify left bottom)
			)
		)
		(property "Value" "R_0R01_1206"
			(at -2.422356 2.103591 180)
			(layer "F.Fab")
			(effects
				(font
					(size 0.7 0.7)
					(thickness 0.15)
				)
				(justify left bottom)
			)
		)
		(property "Datasheet" "https://www.yageo.com/upload/media/product/productsearch/datasheet/rchip/PYu-RL_Group_521_RoHS_L_2.pdf"
			(at 0 0 180)
			(layer "F.Fab")
			(hide yes)
			(effects
				(font
					(size 1.27 1.27)
					(thickness 0.15)
				)
			)
		)
		(property "Author" "Antmicro"
			(at 398 382.65 0)
			(layer "F.Fab")
			(hide yes)
			(effects
				(font
					(size 1 1)
					(thickness 0.15)
				)
			)
		)
		(property "License" "Apache-2.0"
			(at 398 382.65 0)
			(layer "F.Fab")
			(hide yes)
			(effects
				(font
					(size 1 1)
					(thickness 0.15)
				)
			)
		)
		(property "MPN" "RL1206FR-7W0R01L"
			(at 398 382.65 0)
			(layer "F.Fab")
			(hide yes)
			(effects
				(font
					(size 1 1)
					(thickness 0.15)
				)
			)
		)
		(property "Manufacturer" "YAGEO"
			(at 398 382.65 0)
			(layer "F.Fab")
			(hide yes)
			(effects
				(font
					(size 1 1)
					(thickness 0.15)
				)
			)
		)
		(property "Tolerance" "1%"
			(at 398 382.65 0)
			(layer "F.Fab")
			(hide yes)
			(effects
				(font
					(size 1 1)
					(thickness 0.15)
				)
			)
		)
		(property "Val" "0R01"
			(at 398 382.65 0)
			(layer "F.Fab")
			(hide yes)
			(effects
				(font
					(size 1 1)
					(thickness 0.15)
				)
			)
		)
		(sheetname "/Supply/")
		(sheetfile "supply.kicad_sch")
		(attr smd)
		(fp_line
			(start 0 0.9)
			(end 0.498 0.9)
			(stroke
				(width 0.15)
				(type solid)
			)
			(layer "F.SilkS")
		)
		(fp_line
			(start 0 0.9)
			(end -0.5 0.9)
			(stroke
				(width 0.15)
				(type solid)
			)
			(layer "F.SilkS")
		)
		(fp_line
			(start 0 -0.902)
			(end 0.498 -0.902)
			(stroke
				(width 0.15)
				(type solid)
			)
			(layer "F.SilkS")
		)
		(fp_line
			(start 0 -0.902)
			(end -0.5 -0.902)
			(stroke
				(width 0.15)
				(type solid)
			)
			(layer "F.SilkS")
		)
		(fp_rect
			(start -2.25 -1.05)
			(end 2.25 1.05)
			(stroke
				(width 0.05)
				(type solid)
			)
			(fill no)
			(layer "F.CrtYd")
		)
		(fp_line
			(start 1.6 -0.802)
			(end 1.6 0.8)
			(stroke
				(width 0.15)
				(type solid)
			)
			(layer "F.Fab")
		)
		(fp_line
			(start -1.601 0.8)
			(end 1.6 0.8)
			(stroke
				(width 0.15)
				(type solid)
			)
			(layer "F.Fab")
		)
		(fp_line
			(start -1.601 -0.802)
			(end 1.6 -0.802)
			(stroke
				(width 0.15)
				(type solid)
			)
			(layer "F.Fab")
		)
		(fp_line
			(start -1.601 -0.802)
			(end -1.601 0.8)
			(stroke
				(width 0.15)
				(type solid)
			)
			(layer "F.Fab")
		)
		(pad "1" smd roundrect
			(at -1.5 0 180)
			(size 1.2 1.8)
			(layers "F.Cu" "F.Mask" "F.Paste")
			(roundrect_rratio 0.15)
			(net 58 "/Supply/1V7_local")
			(pintype "passive")
		)
		(pad "2" smd roundrect
			(at 1.499 0 180)
			(size 1.2 1.8)
			(layers "F.Cu" "F.Mask" "F.Paste")
			(roundrect_rratio 0.15)
			(net 64 "/Supply/1V7")
			(pintype "passive")
		)
	)
	(footprint "antmicro-footprints:SW_KMR211NGLFS_SMD"
		(layer "F.Cu")
		(at 202.95 137.6 -90)
		(property "Reference" "SW5"
			(at 1.1 2.05 270)
			(layer "F.SilkS")
			(effects
				(font
					(size 0.7 0.7)
					(thickness 0.15)
				)
				(justify left bottom)
			)
		)
		(property "Value" "SW_KMR211NGLFS_SMD"
			(at 0 2.8 270)
			(layer "F.Fab")
			(effects
				(font
					(size 0.7 0.7)
					(thickness 0.15)
				)
				(justify left bottom)
			)
		)
		(property "Datasheet" "http://www.farnell.com/datasheets/2631211.pdf"
			(at 0 0 270)
			(layer "F.Fab")
			(hide yes)
			(effects
				(font
					(size 1.27 1.27)
					(thickness 0.15)
				)
			)
		)
		(property "Author" "Antmicro"
			(at 65.35 340.55 0)
			(layer "F.Fab")
			(hide yes)
			(effects
				(font
					(size 1 1)
					(thickness 0.15)
				)
			)
		)
		(property "License" "Apache-2.0"
			(at 65.35 340.55 0)
			(layer "F.Fab")
			(hide yes)
			(effects
				(font
					(size 1 1)
					(thickness 0.15)
				)
			)
		)
		(property "MPN" "KMR211NGLFS"
			(at 65.35 340.55 0)
			(layer "F.Fab")
			(hide yes)
			(effects
				(font
					(size 1 1)
					(thickness 0.15)
				)
			)
		)
		(property "Manufacturer" "C&K"
			(at 65.35 340.55 0)
			(layer "F.Fab")
			(hide yes)
			(effects
				(font
					(size 1 1)
					(thickness 0.15)
				)
			)
		)
		(sheetname "/Supply/")
		(sheetfile "supply.kicad_sch")
		(attr smd)
		(fp_line
			(start -2.1 1.601)
			(end -2.1 1.48)
			(stroke
				(width 0.15)
				(type solid)
			)
			(layer "F.SilkS")
		)
		(fp_line
			(start 2.101 1.601)
			(end -2.1 1.601)
			(stroke
				(width 0.15)
				(type solid)
			)
			(layer "F.SilkS")
		)
		(fp_line
			(start 2.101 1.601)
			(end 2.101 1.48)
			(stroke
				(width 0.15)
				(type solid)
			)
			(layer "F.SilkS")
		)
		(fp_line
			(start 2.101 -1.58)
			(end 2.101 -1.459)
			(stroke
				(width 0.15)
				(type solid)
			)
			(layer "F.SilkS")
		)
		(fp_line
			(start -2.1 -1.6)
			(end -2.1 -1.499)
			(stroke
				(width 0.15)
				(type solid)
			)
			(layer "F.SilkS")
		)
		(fp_line
			(start 2.101 -1.6)
			(end -2.1 -1.6)
			(stroke
				(width 0.15)
				(type solid)
			)
			(layer "F.SilkS")
		)
		(fp_rect
			(start 2.751 1.75)
			(end -2.748 -1.749)
			(stroke
				(width 0.05)
				(type solid)
			)
			(fill no)
			(layer "F.CrtYd")
		)
		(fp_line
			(start -2.1 1.601)
			(end 2.101 1.601)
			(stroke
				(width 0.15)
				(type solid)
			)
			(layer "F.Fab")
		)
		(fp_line
			(start 2.101 1.601)
			(end 2.101 -1.6)
			(stroke
				(width 0.15)
				(type solid)
			)
			(layer "F.Fab")
		)
		(fp_line
			(start 0.25 0.802)
			(end -0.248 0.802)
			(stroke
				(width 0.15)
				(type solid)
			)
			(layer "F.Fab")
		)
		(fp_line
			(start -0.248 -0.8)
			(end 0.25 -0.8)
			(stroke
				(width 0.15)
				(type solid)
			)
			(layer "F.Fab")
		)
		(fp_line
			(start -2.1 -1.6)
			(end -2.1 1.601)
			(stroke
				(width 0.15)
				(type solid)
			)
			(layer "F.Fab")
		)
		(fp_line
			(start 2.101 -1.6)
			(end -2.1 -1.6)
			(stroke
				(width 0.15)
				(type solid)
			)
			(layer "F.Fab")
		)
		(fp_arc
			(start -0.248 0.802)
			(mid -1.050001 0.001)
			(end -0.248 -0.8)
			(stroke
				(width 0.15)
				(type solid)
			)
			(layer "F.Fab")
		)
		(fp_arc
			(start 0.25 -0.8)
			(mid 1.051001 0.001)
			(end 0.25 0.802)
			(stroke
				(width 0.15)
				(type solid)
			)
			(layer "F.Fab")
		)
		(pad "1" smd rect
			(at -2.048 -0.8 90)
			(size 0.9 1)
			(layers "F.Cu" "F.Mask" "F.Paste")
			(net 1 "GND")
			(pinfunction "1")
			(pintype "passive")
		)
		(pad "2" smd rect
			(at 2.05 -0.8 90)
			(size 0.9 1)
			(layers "F.Cu" "F.Mask" "F.Paste")
			(net 1 "GND")
			(pinfunction "2")
			(pintype "passive")
		)
		(pad "3" smd rect
			(at -2.048 0.802 90)
			(size 0.9 1)
			(layers "F.Cu" "F.Mask" "F.Paste")
			(net 252 "/Supply/~{PB_CTRL_IN}")
			(pinfunction "3")
			(pintype "passive")
		)
		(pad "4" smd rect
			(at 2.05 0.802 90)
			(size 0.9 1)
			(layers "F.Cu" "F.Mask" "F.Paste")
			(net 252 "/Supply/~{PB_CTRL_IN}")
			(pinfunction "4")
			(pintype "passive")
		)
	)
	(footprint "antmicro-footprints:R_1206_3216Metric"
		(layer "F.Cu")
		(at 199.5 173.975 180)
		(property "Reference" "R148"
			(at 5.05 0.125 180)
			(layer "F.SilkS")
			(effects
				(font
					(size 0.7 0.7)
					(thickness 0.15)
				)
				(justify left bottom)
			)
		)
		(property "Value" "R_0R01_1206"
			(at -2.422356 2.103591 180)
			(layer "F.Fab")
			(effects
				(font
					(size 0.7 0.7)
					(thickness 0.15)
				)
				(justify left bottom)
			)
		)
		(property "Datasheet" "https://www.yageo.com/upload/media/product/productsearch/datasheet/rchip/PYu-RL_Group_521_RoHS_L_2.pdf"
			(at 0 0 180)
			(layer "F.Fab")
			(hide yes)
			(effects
				(font
					(size 1.27 1.27)
					(thickness 0.15)
				)
			)
		)
		(property "Author" "Antmicro"
			(at 399 347.95 0)
			(layer "F.Fab")
			(hide yes)
			(effects
				(font
					(size 1 1)
					(thickness 0.15)
				)
			)
		)
		(property "License" "Apache-2.0"
			(at 399 347.95 0)
			(layer "F.Fab")
			(hide yes)
			(effects
				(font
					(size 1 1)
					(thickness 0.15)
				)
			)
		)
		(property "MPN" "RL1206FR-7W0R01L"
			(at 399 347.95 0)
			(layer "F.Fab")
			(hide yes)
			(effects
				(font
					(size 1 1)
					(thickness 0.15)
				)
			)
		)
		(property "Manufacturer" "YAGEO"
			(at 399 347.95 0)
			(layer "F.Fab")
			(hide yes)
			(effects
				(font
					(size 1 1)
					(thickness 0.15)
				)
			)
		)
		(property "Tolerance" "1%"
			(at 399 347.95 0)
			(layer "F.Fab")
			(hide yes)
			(effects
				(font
					(size 1 1)
					(thickness 0.15)
				)
			)
		)
		(property "Val" "0R01"
			(at 399 347.95 0)
			(layer "F.Fab")
			(hide yes)
			(effects
				(font
					(size 1 1)
					(thickness 0.15)
				)
			)
		)
		(sheetname "/Supply/")
		(sheetfile "supply.kicad_sch")
		(attr smd)
		(fp_line
			(start 0 0.9)
			(end 0.498 0.9)
			(stroke
				(width 0.15)
				(type solid)
			)
			(layer "F.SilkS")
		)
		(fp_line
			(start 0 0.9)
			(end -0.5 0.9)
			(stroke
				(width 0.15)
				(type solid)
			)
			(layer "F.SilkS")
		)
		(fp_line
			(start 0 -0.902)
			(end 0.498 -0.902)
			(stroke
				(width 0.15)
				(type solid)
			)
			(layer "F.SilkS")
		)
		(fp_line
			(start 0 -0.902)
			(end -0.5 -0.902)
			(stroke
				(width 0.15)
				(type solid)
			)
			(layer "F.SilkS")
		)
		(fp_rect
			(start -2.25 -1.05)
			(end 2.25 1.05)
			(stroke
				(width 0.05)
				(type solid)
			)
			(fill no)
			(layer "F.CrtYd")
		)
		(fp_line
			(start 1.6 -0.802)
			(end 1.6 0.8)
			(stroke
				(width 0.15)
				(type solid)
			)
			(layer "F.Fab")
		)
		(fp_line
			(start -1.601 0.8)
			(end 1.6 0.8)
			(stroke
				(width 0.15)
				(type solid)
			)
			(layer "F.Fab")
		)
		(fp_line
			(start -1.601 -0.802)
			(end 1.6 -0.802)
			(stroke
				(width 0.15)
				(type solid)
			)
			(layer "F.Fab")
		)
		(fp_line
			(start -1.601 -0.802)
			(end -1.601 0.8)
			(stroke
				(width 0.15)
				(type solid)
			)
			(layer "F.Fab")
		)
		(pad "1" smd roundrect
			(at -1.5 0 180)
			(size 1.2 1.8)
			(layers "F.Cu" "F.Mask" "F.Paste")
			(roundrect_rratio 0.15)
			(net 56 "/Supply/1V2_local")
			(pintype "passive")
		)
		(pad "2" smd roundrect
			(at 1.499 0 180)
			(size 1.2 1.8)
			(layers "F.Cu" "F.Mask" "F.Paste")
			(roundrect_rratio 0.15)
			(net 199 "+1V2")
			(pintype "passive")
		)
	)
	(footprint "antmicro-footprints:NetTie-2_SMD_Pad0.127mm"
		(layer "F.Cu")
		(at 187.85 171.701 180)
		(descr "Net tie, 2 pin, 0.127mm  SMD pads")
		(tags "net tie")
		(property "Reference" "NT13"
			(at -0.128 -1.345 180)
			(layer "F.SilkS")
			(hide yes)
			(effects
				(font
					(size 0.7 0.7)
					(thickness 0.15)
				)
				(justify left bottom)
			)
		)
		(property "Value" "Net-Tie_P0.127mm"
			(at 0 1.199 180)
			(layer "F.Fab")
			(effects
				(font
					(size 0.7 0.7)
					(thickness 0.15)
				)
				(justify left bottom)
			)
		)
		(property "Author" "Antmicro"
			(at 375.7 343.402 0)
			(layer "F.Fab")
			(hide yes)
			(effects
				(font
					(size 1 1)
					(thickness 0.15)
				)
			)
		)
		(property "License" "Apache-2.0"
			(at 375.7 343.402 0)
			(layer "F.Fab")
			(hide yes)
			(effects
				(font
					(size 1 1)
					(thickness 0.15)
				)
			)
		)
		(property "MPN" ""
			(at 375.7 343.402 0)
			(layer "F.Fab")
			(hide yes)
			(effects
				(font
					(size 1 1)
					(thickness 0.15)
				)
			)
		)
		(property "Manufacturer" ""
			(at 375.7 343.402 0)
			(layer "F.Fab")
			(hide yes)
			(effects
				(font
					(size 1 1)
					(thickness 0.15)
				)
			)
		)
		(property ki_fp_filters "Net*Tie*")
		(sheetname "/Supply/")
		(sheetfile "supply.kicad_sch")
		(attr smd exclude_from_pos_files exclude_from_bom)
		(net_tie_pad_groups "1, 2")
		(fp_poly
			(pts
				(xy -0.0635 -0.0635) (xy 0.0625 -0.0635) (xy 0.0625 0.0635) (xy -0.0635 0.0635)
			)
			(stroke
				(width 0)
				(type solid)
			)
			(fill yes)
			(layer "F.Cu")
		)
		(pad "1" smd roundrect
			(at -0.127 0)
			(size 0.127 0.127)
			(layers "F.Cu")
			(roundrect_rratio 0.5)
			(chamfer_ratio 0)
			(chamfer top_left bottom_left)
			(net 245 "/Supply/3V3_SEN_-")
			(pinfunction "1")
			(pintype "passive")
		)
		(pad "2" smd roundrect
			(at 0.126 0 180)
			(size 0.127 0.127)
			(layers "F.Cu")
			(roundrect_rratio 0.5)
			(chamfer_ratio 0)
			(chamfer top_left bottom_left)
			(net 200 "+3V3")
			(pinfunction "2")
			(pintype "passive")
		)
	)
	(footprint "antmicro-footprints:C_0805_2012Metric"
		(layer "F.Cu")
		(at 172.919503 197.376)
		(descr "Capacitor SMD 0805")
		(tags "capacitor SMD 0805")
		(property "Reference" "C202"
			(at -2.10551 -1.198678 0)
			(layer "F.SilkS")
			(hide yes)
			(effects
				(font
					(size 0.7 0.7)
					(thickness 0.15)
				)
				(justify left bottom)
			)
		)
		(property "Value" "C_22u_25V_0805"
			(at -2.055717 1.963152 0)
			(layer "F.Fab")
			(effects
				(font
					(size 0.7 0.7)
					(thickness 0.15)
				)
				(justify left bottom)
			)
		)
		(property "Datasheet" "https://product.samsungsem.com/mlcc/CL21A226MAYNNN.do"
			(at 0 0 0)
			(layer "F.Fab")
			(hide yes)
			(effects
				(font
					(size 1.27 1.27)
					(thickness 0.15)
				)
			)
		)
		(property "Author" "Antmicro"
			(at 0 0 0)
			(layer "F.Fab")
			(hide yes)
			(effects
				(font
					(size 1 1)
					(thickness 0.15)
				)
			)
		)
		(property "Dielectric" ""
			(at 0 0 0)
			(layer "F.Fab")
			(hide yes)
			(effects
				(font
					(size 1 1)
					(thickness 0.15)
				)
			)
		)
		(property "License" "Apache-2.0"
			(at 0 0 0)
			(layer "F.Fab")
			(hide yes)
			(effects
				(font
					(size 1 1)
					(thickness 0.15)
				)
			)
		)
		(property "MPN" "CL21A226MAYNNNE"
			(at 0 0 0)
			(layer "F.Fab")
			(hide yes)
			(effects
				(font
					(size 1 1)
					(thickness 0.15)
				)
			)
		)
		(property "Manufacturer" "Samsung Electro-Mechanics"
			(at 0 0 0)
			(layer "F.Fab")
			(hide yes)
			(effects
				(font
					(size 1 1)
					(thickness 0.15)
				)
			)
		)
		(property "Val" "22u_25V"
			(at 0 0 0)
			(layer "F.Fab")
			(hide yes)
			(effects
				(font
					(size 1 1)
					(thickness 0.15)
				)
			)
		)
		(property "Voltage" ""
			(at 0 0 0)
			(layer "F.Fab")
			(hide yes)
			(effects
				(font
					(size 1 1)
					(thickness 0.15)
				)
			)
		)
		(sheetname "/Supply/")
		(sheetfile "supply.kicad_sch")
		(attr smd)
		(fp_line
			(start -0.3 -0.8)
			(end 0.3 -0.8)
			(stroke
				(width 0.15)
				(type solid)
			)
			(layer "F.SilkS")
		)
		(fp_line
			(start -0.3 0.8)
			(end 0.3 0.8)
			(stroke
				(width 0.15)
				(type solid)
			)
			(layer "F.SilkS")
		)
		(fp_rect
			(start -1.9 -0.93)
			(end 1.9 0.93)
			(stroke
				(width 0.05)
				(type solid)
			)
			(fill no)
			(layer "F.CrtYd")
		)
		(fp_rect
			(start -0.95 -0.675)
			(end 0.95 0.675)
			(stroke
				(width 0.15)
				(type solid)
			)
			(fill no)
			(layer "F.Fab")
		)
		(pad "1" smd rect
			(at -1.05 0)
			(size 1.2 1.2)
			(layers "F.Cu" "F.Mask" "F.Paste")
			(net 1 "GND")
			(pintype "passive")
		)
		(pad "2" smd rect
			(at 1.05 0)
			(size 1.2 1.2)
			(layers "F.Cu" "F.Mask" "F.Paste")
			(net 38 "VDC")
			(pintype "passive")
		)
	)
	(footprint "antmicro-footprints:R_1206_3216Metric"
		(layer "F.Cu")
		(at 188.6555 162.001 180)
		(property "Reference" "R146"
			(at 0.5055 -1.949 180)
			(layer "F.SilkS")
			(effects
				(font
					(size 0.7 0.7)
					(thickness 0.15)
				)
				(justify left bottom)
			)
		)
		(property "Value" "R_0R01_1206"
			(at -2.422356 2.103591 180)
			(layer "F.Fab")
			(effects
				(font
					(size 0.7 0.7)
					(thickness 0.15)
				)
				(justify left bottom)
			)
		)
		(property "Datasheet" "https://www.yageo.com/upload/media/product/productsearch/datasheet/rchip/PYu-RL_Group_521_RoHS_L_2.pdf"
			(at 0 0 180)
			(layer "F.Fab")
			(hide yes)
			(effects
				(font
					(size 1.27 1.27)
					(thickness 0.15)
				)
			)
		)
		(property "Author" "Antmicro"
			(at 377.311 324.002 0)
			(layer "F.Fab")
			(hide yes)
			(effects
				(font
					(size 1 1)
					(thickness 0.15)
				)
			)
		)
		(property "License" "Apache-2.0"
			(at 377.311 324.002 0)
			(layer "F.Fab")
			(hide yes)
			(effects
				(font
					(size 1 1)
					(thickness 0.15)
				)
			)
		)
		(property "MPN" "RL1206FR-7W0R01L"
			(at 377.311 324.002 0)
			(layer "F.Fab")
			(hide yes)
			(effects
				(font
					(size 1 1)
					(thickness 0.15)
				)
			)
		)
		(property "Manufacturer" "YAGEO"
			(at 377.311 324.002 0)
			(layer "F.Fab")
			(hide yes)
			(effects
				(font
					(size 1 1)
					(thickness 0.15)
				)
			)
		)
		(property "Tolerance" "1%"
			(at 377.311 324.002 0)
			(layer "F.Fab")
			(hide yes)
			(effects
				(font
					(size 1 1)
					(thickness 0.15)
				)
			)
		)
		(property "Val" "0R01"
			(at 377.311 324.002 0)
			(layer "F.Fab")
			(hide yes)
			(effects
				(font
					(size 1 1)
					(thickness 0.15)
				)
			)
		)
		(sheetname "/Supply/")
		(sheetfile "supply.kicad_sch")
		(attr smd)
		(fp_line
			(start 0 0.9)
			(end 0.498 0.9)
			(stroke
				(width 0.15)
				(type solid)
			)
			(layer "F.SilkS")
		)
		(fp_line
			(start 0 0.9)
			(end -0.5 0.9)
			(stroke
				(width 0.15)
				(type solid)
			)
			(layer "F.SilkS")
		)
		(fp_line
			(start 0 -0.902)
			(end 0.498 -0.902)
			(stroke
				(width 0.15)
				(type solid)
			)
			(layer "F.SilkS")
		)
		(fp_line
			(start 0 -0.902)
			(end -0.5 -0.902)
			(stroke
				(width 0.15)
				(type solid)
			)
			(layer "F.SilkS")
		)
		(fp_rect
			(start -2.25 -1.05)
			(end 2.25 1.05)
			(stroke
				(width 0.05)
				(type solid)
			)
			(fill no)
			(layer "F.CrtYd")
		)
		(fp_line
			(start 1.6 -0.802)
			(end 1.6 0.8)
			(stroke
				(width 0.15)
				(type solid)
			)
			(layer "F.Fab")
		)
		(fp_line
			(start -1.601 0.8)
			(end 1.6 0.8)
			(stroke
				(width 0.15)
				(type solid)
			)
			(layer "F.Fab")
		)
		(fp_line
			(start -1.601 -0.802)
			(end 1.6 -0.802)
			(stroke
				(width 0.15)
				(type solid)
			)
			(layer "F.Fab")
		)
		(fp_line
			(start -1.601 -0.802)
			(end -1.601 0.8)
			(stroke
				(width 0.15)
				(type solid)
			)
			(layer "F.Fab")
		)
		(pad "1" smd roundrect
			(at -1.5 0 180)
			(size 1.2 1.8)
			(layers "F.Cu" "F.Mask" "F.Paste")
			(roundrect_rratio 0.15)
			(net 60 "/Supply/5V_local")
			(pintype "passive")
		)
		(pad "2" smd roundrect
			(at 1.499 0 180)
			(size 1.2 1.8)
			(layers "F.Cu" "F.Mask" "F.Paste")
			(roundrect_rratio 0.15)
			(net 201 "+5V")
			(pintype "passive")
		)
	)
	(footprint "antmicro-footprints:NetTie-2_SMD_Pad0.127mm"
		(layer "F.Cu")
		(at 189.5 179.5)
		(descr "Net tie, 2 pin, 0.127mm  SMD pads")
		(tags "net tie")
		(property "Reference" "NT2"
			(at -0.128 -1.345 0)
			(layer "F.SilkS")
			(hide yes)
			(effects
				(font
					(size 0.7 0.7)
					(thickness 0.15)
				)
				(justify left bottom)
			)
		)
		(property "Value" "Net-Tie_P0.127mm"
			(at 0 1.199 0)
			(layer "F.Fab")
			(effects
				(font
					(size 0.7 0.7)
					(thickness 0.15)
				)
				(justify left bottom)
			)
		)
		(property "Author" "Antmicro"
			(at 0 0 0)
			(layer "F.Fab")
			(hide yes)
			(effects
				(font
					(size 1 1)
					(thickness 0.15)
				)
			)
		)
		(property "License" "Apache-2.0"
			(at 0 0 0)
			(layer "F.Fab")
			(hide yes)
			(effects
				(font
					(size 1 1)
					(thickness 0.15)
				)
			)
		)
		(property "MPN" ""
			(at 0 0 0)
			(layer "F.Fab")
			(hide yes)
			(effects
				(font
					(size 1 1)
					(thickness 0.15)
				)
			)
		)
		(property "Manufacturer" ""
			(at 0 0 0)
			(layer "F.Fab")
			(hide yes)
			(effects
				(font
					(size 1 1)
					(thickness 0.15)
				)
			)
		)
		(property ki_fp_filters "Net*Tie*")
		(sheetname "/Supply/")
		(sheetfile "supply.kicad_sch")
		(attr smd exclude_from_pos_files exclude_from_bom)
		(net_tie_pad_groups "1, 2")
		(fp_poly
			(pts
				(xy -0.0635 -0.0635) (xy 0.0625 -0.0635) (xy 0.0625 0.0635) (xy -0.0635 0.0635)
			)
			(stroke
				(width 0)
				(type solid)
			)
			(fill yes)
			(layer "F.Cu")
		)
		(pad "1" smd roundrect
			(at -0.127 0 180)
			(size 0.127 0.127)
			(layers "F.Cu")
			(roundrect_rratio 0.5)
			(chamfer_ratio 0)
			(chamfer top_left bottom_left)
			(net 244 "/Supply/1V8_SEN_+")
			(pinfunction "1")
			(pintype "passive")
		)
		(pad "2" smd roundrect
			(at 0.126 0)
			(size 0.127 0.127)
			(layers "F.Cu")
			(roundrect_rratio 0.5)
			(chamfer_ratio 0)
			(chamfer top_left bottom_left)
			(net 51 "/Supply/1V8_local")
			(pinfunction "2")
			(pintype "passive")
		)
	)
	(footprint "antmicro-footprints:C_0603_1608Metric"
		(layer "F.Cu")
		(at 199.981001 172.122)
		(descr "Capacitor SMD 0603")
		(tags "capacitor 0603")
		(property "Reference" "C193"
			(at -1.42757 -1.000252 0)
			(layer "F.SilkS")
			(hide yes)
			(effects
				(font
					(size 0.7 0.7)
					(thickness 0.15)
				)
				(justify left bottom)
			)
		)
		(property "Value" "C_22u_0603"
			(at -1.42757 1.770288 0)
			(layer "F.Fab")
			(effects
				(font
					(size 0.7 0.7)
					(thickness 0.15)
				)
				(justify left bottom)
			)
		)
		(property "Datasheet" "https://www.murata.com/products/productdetail?partno=GRM188R60J226MEA0%23"
			(at 0 0 0)
			(layer "F.Fab")
			(hide yes)
			(effects
				(font
					(size 1.27 1.27)
					(thickness 0.15)
				)
			)
		)
		(property "Author" "Antmicro"
			(at 0 0 0)
			(layer "F.Fab")
			(hide yes)
			(effects
				(font
					(size 1 1)
					(thickness 0.15)
				)
			)
		)
		(property "Dielectric" ""
			(at 0 0 0)
			(layer "F.Fab")
			(hide yes)
			(effects
				(font
					(size 1 1)
					(thickness 0.15)
				)
			)
		)
		(property "License" "Apache-2.0"
			(at 0 0 0)
			(layer "F.Fab")
			(hide yes)
			(effects
				(font
					(size 1 1)
					(thickness 0.15)
				)
			)
		)
		(property "MPN" "GRM188R60J226MEA0D"
			(at 0 0 0)
			(layer "F.Fab")
			(hide yes)
			(effects
				(font
					(size 1 1)
					(thickness 0.15)
				)
			)
		)
		(property "Manufacturer" "Murata"
			(at 0 0 0)
			(layer "F.Fab")
			(hide yes)
			(effects
				(font
					(size 1 1)
					(thickness 0.15)
				)
			)
		)
		(property "Val" "22u"
			(at 0 0 0)
			(layer "F.Fab")
			(hide yes)
			(effects
				(font
					(size 1 1)
					(thickness 0.15)
				)
			)
		)
		(property "Voltage" ""
			(at 0 0 0)
			(layer "F.Fab")
			(hide yes)
			(effects
				(font
					(size 1 1)
					(thickness 0.15)
				)
			)
		)
		(sheetname "/Supply/")
		(sheetfile "supply.kicad_sch")
		(fp_line
			(start -0.3 -0.3)
			(end 0.3 -0.3)
			(stroke
				(width 0.15)
				(type solid)
			)
			(layer "F.SilkS")
		)
		(fp_line
			(start -0.3 0.3)
			(end 0.3 0.3)
			(stroke
				(width 0.15)
				(type solid)
			)
			(layer "F.SilkS")
		)
		(fp_rect
			(start -1.24 -0.7)
			(end 1.24 0.7)
			(stroke
				(width 0.05)
				(type solid)
			)
			(fill no)
			(layer "F.CrtYd")
		)
		(fp_rect
			(start -0.8 -0.4)
			(end 0.8 0.4)
			(stroke
				(width 0.15)
				(type solid)
			)
			(fill no)
			(layer "F.Fab")
		)
		(pad "1" smd roundrect
			(at -0.7 0)
			(size 0.6 0.8)
			(layers "F.Cu" "F.Mask" "F.Paste")
			(roundrect_rratio 0.2)
			(net 1 "GND")
			(pintype "passive")
		)
		(pad "2" smd roundrect
			(at 0.7 0)
			(size 0.6 0.8)
			(layers "F.Cu" "F.Mask" "F.Paste")
			(roundrect_rratio 0.2)
			(net 56 "/Supply/1V2_local")
			(pintype "passive")
		)
	)
	(footprint "antmicro-footprints:C_0603_1608Metric"
		(layer "F.Cu")
		(at 191.168501 168.072 -90)
		(descr "Capacitor SMD 0603")
		(tags "capacitor 0603")
		(property "Reference" "C184"
			(at -1.42757 -1.000252 270)
			(layer "F.SilkS")
			(hide yes)
			(effects
				(font
					(size 0.7 0.7)
					(thickness 0.15)
				)
				(justify left bottom)
			)
		)
		(property "Value" "C_22u_0603"
			(at -1.42757 1.770288 270)
			(layer "F.Fab")
			(effects
				(font
					(size 0.7 0.7)
					(thickness 0.15)
				)
				(justify left bottom)
			)
		)
		(property "Datasheet" "https://www.murata.com/products/productdetail?partno=GRM188R60J226MEA0%23"
			(at 0 0 270)
			(layer "F.Fab")
			(hide yes)
			(effects
				(font
					(size 1.27 1.27)
					(thickness 0.15)
				)
			)
		)
		(property "Author" "Antmicro"
			(at 23.096501 359.240501 0)
			(layer "F.Fab")
			(hide yes)
			(effects
				(font
					(size 1 1)
					(thickness 0.15)
				)
			)
		)
		(property "Dielectric" ""
			(at 23.096501 359.240501 0)
			(layer "F.Fab")
			(hide yes)
			(effects
				(font
					(size 1 1)
					(thickness 0.15)
				)
			)
		)
		(property "License" "Apache-2.0"
			(at 23.096501 359.240501 0)
			(layer "F.Fab")
			(hide yes)
			(effects
				(font
					(size 1 1)
					(thickness 0.15)
				)
			)
		)
		(property "MPN" "GRM188R60J226MEA0D"
			(at 23.096501 359.240501 0)
			(layer "F.Fab")
			(hide yes)
			(effects
				(font
					(size 1 1)
					(thickness 0.15)
				)
			)
		)
		(property "Manufacturer" "Murata"
			(at 23.096501 359.240501 0)
			(layer "F.Fab")
			(hide yes)
			(effects
				(font
					(size 1 1)
					(thickness 0.15)
				)
			)
		)
		(property "Val" "22u"
			(at 23.096501 359.240501 0)
			(layer "F.Fab")
			(hide yes)
			(effects
				(font
					(size 1 1)
					(thickness 0.15)
				)
			)
		)
		(property "Voltage" ""
			(at 23.096501 359.240501 0)
			(layer "F.Fab")
			(hide yes)
			(effects
				(font
					(size 1 1)
					(thickness 0.15)
				)
			)
		)
		(sheetname "/Supply/")
		(sheetfile "supply.kicad_sch")
		(attr smd)
		(fp_line
			(start -0.3 0.3)
			(end 0.3 0.3)
			(stroke
				(width 0.15)
				(type solid)
			)
			(layer "F.SilkS")
		)
		(fp_line
			(start -0.3 -0.3)
			(end 0.3 -0.3)
			(stroke
				(width 0.15)
				(type solid)
			)
			(layer "F.SilkS")
		)
		(fp_rect
			(start -1.24 -0.7)
			(end 1.24 0.7)
			(stroke
				(width 0.05)
				(type solid)
			)
			(fill no)
			(layer "F.CrtYd")
		)
		(fp_rect
			(start -0.8 -0.4)
			(end 0.8 0.4)
			(stroke
				(width 0.15)
				(type solid)
			)
			(fill no)
			(layer "F.Fab")
		)
		(pad "1" smd roundrect
			(at -0.7 0 270)
			(size 0.6 0.8)
			(layers "F.Cu" "F.Mask" "F.Paste")
			(roundrect_rratio 0.2)
			(net 1 "GND")
			(pintype "passive")
		)
		(pad "2" smd roundrect
			(at 0.7 0 270)
			(size 0.6 0.8)
			(layers "F.Cu" "F.Mask" "F.Paste")
			(roundrect_rratio 0.2)
			(net 52 "/Supply/3V3_local")
			(pintype "passive")
		)
	)
	(footprint "antmicro-footprints:SW_DIP_SPSTx03_Slide_Copal_CVS-03xB_W5.9mm_P1mm"
		(layer "F.Cu")
		(at 162.250501 180.675)
		(descr "SMD 3x-dip-switch SPST Copal_CVS-03xB, Slide, row spacing 5.9 mm (232 mils), body size  (see http://www.nidec-copal-electronics.com/e/catalog/switch/cvs.pdf)")
		(tags "SMD DIP Switch SPST Slide")
		(property "Reference" "SW1"
			(at -4.150501 3.825 0)
			(layer "F.SilkS")
			(effects
				(font
					(size 0.7 0.7)
					(thickness 0.15)
				)
				(justify left bottom)
			)
		)
		(property "Value" "CVS-03B"
			(at 0.248 4.799 0)
			(layer "F.Fab")
			(effects
				(font
					(size 0.7 0.7)
					(thickness 0.15)
				)
				(justify left bottom)
			)
		)
		(property "Datasheet" "https://www.mouser.com/datasheet/2/972/cvs-1827291.pdf"
			(at 0 0 0)
			(layer "F.Fab")
			(hide yes)
			(effects
				(font
					(size 1.27 1.27)
					(thickness 0.15)
				)
			)
		)
		(property "Author" "Antmicro"
			(at 0 0 0)
			(layer "F.Fab")
			(hide yes)
			(effects
				(font
					(size 1 1)
					(thickness 0.15)
				)
			)
		)
		(property "License" "Apache-2.0"
			(at 0 0 0)
			(layer "F.Fab")
			(hide yes)
			(effects
				(font
					(size 1 1)
					(thickness 0.15)
				)
			)
		)
		(property "MPN" "CVS-03B"
			(at 0 0 0)
			(layer "F.Fab")
			(hide yes)
			(effects
				(font
					(size 1 1)
					(thickness 0.15)
				)
			)
		)
		(property "Manufacturer" "Nidec Components"
			(at 0 0 0)
			(layer "F.Fab")
			(hide yes)
			(effects
				(font
					(size 1 1)
					(thickness 0.15)
				)
			)
		)
		(property ki_fp_filters "SW?DIP?x2*")
		(sheetname "/FPGA Config/")
		(sheetfile "fpga-config.kicad_sch")
		(attr smd)
		(fp_line
			(start -1.51 -2.411)
			(end 1.61 -2.411)
			(stroke
				(width 0.15)
				(type solid)
			)
			(layer "F.SilkS")
		)
		(fp_line
			(start -1.51 2.41)
			(end 1.61 2.41)
			(stroke
				(width 0.15)
				(type solid)
			)
			(layer "F.SilkS")
		)
		(fp_circle
			(center -3.33 -1.641)
			(end -3.281 -1.641)
			(stroke
				(width 0.15)
				(type solid)
			)
			(fill yes)
			(layer "F.SilkS")
		)
		(fp_rect
			(start -3.56 -2.5)
			(end 3.66 2.49)
			(stroke
				(width 0.05)
				(type solid)
			)
			(fill no)
			(layer "F.CrtYd")
		)
		(fp_line
			(start -2.301 -1)
			(end -1.301 -2)
			(stroke
				(width 0.15)
				(type solid)
			)
			(layer "F.Fab")
		)
		(fp_line
			(start -2.301 1.999)
			(end -2.301 -1)
			(stroke
				(width 0.15)
				(type solid)
			)
			(layer "F.Fab")
		)
		(fp_line
			(start -1.301 -2)
			(end 2.398 -2)
			(stroke
				(width 0.15)
				(type solid)
			)
			(layer "F.Fab")
		)
		(fp_line
			(start -0.951 -1.25)
			(end -0.951 -0.75)
			(stroke
				(width 0.15)
				(type solid)
			)
			(layer "F.Fab")
		)
		(fp_line
			(start -0.951 -1.151)
			(end -0.285 -1.151)
			(stroke
				(width 0.15)
				(type solid)
			)
			(layer "F.Fab")
		)
		(fp_line
			(start -0.951 -1.051)
			(end -0.285 -1.051)
			(stroke
				(width 0.15)
				(type solid)
			)
			(layer "F.Fab")
		)
		(fp_line
			(start -0.951 -0.952)
			(end -0.285 -0.952)
			(stroke
				(width 0.15)
				(type solid)
			)
			(layer "F.Fab")
		)
		(fp_line
			(start -0.951 -0.85)
			(end -0.285 -0.85)
			(stroke
				(width 0.15)
				(type solid)
			)
			(layer "F.Fab")
		)
		(fp_line
			(start -0.951 -0.75)
			(end 1.05 -0.75)
			(stroke
				(width 0.15)
				(type solid)
			)
			(layer "F.Fab")
		)
		(fp_line
			(start -0.951 -0.25)
			(end -0.951 0.247)
			(stroke
				(width 0.15)
				(type solid)
			)
			(layer "F.Fab")
		)
		(fp_line
			(start -0.951 -0.15)
			(end -0.285 -0.15)
			(stroke
				(width 0.15)
				(type solid)
			)
			(layer "F.Fab")
		)
		(fp_line
			(start -0.951 -0.053)
			(end -0.285 -0.053)
			(stroke
				(width 0.15)
				(type solid)
			)
			(layer "F.Fab")
		)
		(fp_line
			(start -0.951 0.05)
			(end -0.285 0.05)
			(stroke
				(width 0.15)
				(type solid)
			)
			(layer "F.Fab")
		)
		(fp_line
			(start -0.951 0.147)
			(end -0.285 0.147)
			(stroke
				(width 0.15)
				(type solid)
			)
			(layer "F.Fab")
		)
		(fp_line
			(start -0.951 0.247)
			(end 1.05 0.247)
			(stroke
				(width 0.15)
				(type solid)
			)
			(layer "F.Fab")
		)
		(fp_line
			(start -0.951 0.747)
			(end -0.951 1.249)
			(stroke
				(width 0.15)
				(type solid)
			)
			(layer "F.Fab")
		)
		(fp_line
			(start -0.951 0.847)
			(end -0.285 0.847)
			(stroke
				(width 0.15)
				(type solid)
			)
			(layer "F.Fab")
		)
		(fp_line
			(start -0.951 0.949)
			(end -0.285 0.949)
			(stroke
				(width 0.15)
				(type solid)
			)
			(layer "F.Fab")
		)
		(fp_line
			(start -0.951 1.05)
			(end -0.285 1.05)
			(stroke
				(width 0.15)
				(type solid)
			)
			(layer "F.Fab")
		)
		(fp_line
			(start -0.951 1.148)
			(end -0.285 1.148)
			(stroke
				(width 0.15)
				(type solid)
			)
			(layer "F.Fab")
		)
		(fp_line
			(start -0.951 1.249)
			(end 1.05 1.249)
			(stroke
				(width 0.15)
				(type solid)
			)
			(layer "F.Fab")
		)
		(fp_line
			(start -0.285 -1.25)
			(end -0.285 -0.75)
			(stroke
				(width 0.15)
				(type solid)
			)
			(layer "F.Fab")
		)
		(fp_line
			(start -0.285 -0.25)
			(end -0.285 0.247)
			(stroke
				(width 0.15)
				(type solid)
			)
			(layer "F.Fab")
		)
		(fp_line
			(start -0.285 0.747)
			(end -0.285 1.249)
			(stroke
				(width 0.15)
				(type solid)
			)
			(layer "F.Fab")
		)
		(fp_line
			(start 1.05 -1.25)
			(end -0.951 -1.25)
			(stroke
				(width 0.15)
				(type solid)
			)
			(layer "F.Fab")
		)
		(fp_line
			(start 1.05 -0.75)
			(end 1.05 -1.25)
			(stroke
				(width 0.15)
				(type solid)
			)
			(layer "F.Fab")
		)
		(fp_line
			(start 1.05 -0.25)
			(end -0.951 -0.25)
			(stroke
				(width 0.15)
				(type solid)
			)
			(layer "F.Fab")
		)
		(fp_line
			(start 1.05 0.247)
			(end 1.05 -0.25)
			(stroke
				(width 0.15)
				(type solid)
			)
			(layer "F.Fab")
		)
		(fp_line
			(start 1.05 0.747)
			(end -0.951 0.747)
			(stroke
				(width 0.15)
				(type solid)
			)
			(layer "F.Fab")
		)
		(fp_line
			(start 1.05 1.249)
			(end 1.05 0.747)
			(stroke
				(width 0.15)
				(type solid)
			)
			(layer "F.Fab")
		)
		(fp_line
			(start 2.398 -2)
			(end 2.398 1.999)
			(stroke
				(width 0.15)
				(type solid)
			)
			(layer "F.Fab")
		)
		(fp_line
			(start 2.398 1.999)
			(end -2.301 1.999)
			(stroke
				(width 0.15)
				(type solid)
			)
			(layer "F.Fab")
		)
		(fp_text user "on"
			(at -1.44 0.72 90)
			(layer "F.Fab")
			(effects
				(font
					(size 0.7 0.7)
					(thickness 0.15)
				)
				(justify left bottom)
			)
		)
		(pad "1" smd rect
			(at -2.899 -1)
			(size 1.2 0.5)
			(layers "F.Cu" "F.Mask" "F.Paste")
			(net 633 "/FPGA Config/MODE0")
			(pinfunction "1")
			(pintype "passive")
		)
		(pad "2" smd rect
			(at -2.899 0)
			(size 1.2 0.5)
			(layers "F.Cu" "F.Mask" "F.Paste")
			(net 632 "/FPGA Config/MODE1")
			(pinfunction "2")
			(pintype "passive")
		)
		(pad "3" smd rect
			(at -2.899 0.997)
			(size 1.2 0.5)
			(layers "F.Cu" "F.Mask" "F.Paste")
			(net 631 "/FPGA Config/MODE2")
			(pinfunction "3")
			(pintype "passive")
		)
		(pad "4" smd rect
			(at 2.999 0.997)
			(size 1.2 0.5)
			(layers "F.Cu" "F.Mask" "F.Paste")
			(net 1 "GND")
			(pinfunction "4")
			(pintype "passive")
		)
		(pad "5" smd rect
			(at 2.999 0)
			(size 1.2 0.5)
			(layers "F.Cu" "F.Mask" "F.Paste")
			(net 1 "GND")
			(pinfunction "5")
			(pintype "passive")
		)
		(pad "6" smd rect
			(at 2.999 -1)
			(size 1.2 0.5)
			(layers "F.Cu" "F.Mask" "F.Paste")
			(net 1 "GND")
			(pinfunction "6")
			(pintype "passive")
		)
		(pad "7" smd rect
			(at -2.101 -2)
			(size 0.7 0.7)
			(layers "F.Cu" "F.Mask" "F.Paste")
			(net 1 "GND")
			(pinfunction "7")
			(pintype "power_in")
		)
		(pad "7" smd rect
			(at -2.101 1.999)
			(size 0.7 0.7)
			(layers "F.Cu" "F.Mask" "F.Paste")
			(net 1 "GND")
			(pinfunction "7")
			(pintype "power_in")
		)
		(pad "7" smd rect
			(at 2.201 -2)
			(size 0.7 0.7)
			(layers "F.Cu" "F.Mask" "F.Paste")
			(net 1 "GND")
			(pinfunction "7")
			(pintype "power_in")
		)
		(pad "7" smd rect
			(at 2.201 1.999)
			(size 0.7 0.7)
			(layers "F.Cu" "F.Mask" "F.Paste")
			(net 1 "GND")
			(pinfunction "7")
			(pintype "power_in")
		)
	)
	(footprint "antmicro-footprints:SOT-23-6"
		(layer "F.Cu")
		(at 122.1 202.7)
		(property "Reference" "U18"
			(at 0.45 2.7 0)
			(layer "F.SilkS")
			(effects
				(font
					(size 0.7 0.7)
					(thickness 0.15)
				)
				(justify left bottom)
			)
		)
		(property "Value" "LTC4412IS6"
			(at -1.75 2.75 0)
			(layer "F.Fab")
			(effects
				(font
					(size 0.7 0.7)
					(thickness 0.15)
				)
				(justify left bottom)
			)
		)
		(property "Datasheet" "https://www.mouser.com/datasheet/2/308/NCV8187_D-1813214.pdf"
			(at 0 0 0)
			(layer "F.Fab")
			(hide yes)
			(effects
				(font
					(size 1.27 1.27)
					(thickness 0.15)
				)
			)
		)
		(property "Author" "Antmicro"
			(at 0 0 0)
			(layer "F.Fab")
			(hide yes)
			(effects
				(font
					(size 1 1)
					(thickness 0.15)
				)
			)
		)
		(property "License" "Apache-2.0"
			(at 0 0 0)
			(layer "F.Fab")
			(hide yes)
			(effects
				(font
					(size 1 1)
					(thickness 0.15)
				)
			)
		)
		(property "MPN" "LTC4412IS6#TRMPBF"
			(at 0 0 0)
			(layer "F.Fab")
			(hide yes)
			(effects
				(font
					(size 1 1)
					(thickness 0.15)
				)
			)
		)
		(property "Manufacturer" "Analog Devices"
			(at 0 0 0)
			(layer "F.Fab")
			(hide yes)
			(effects
				(font
					(size 1 1)
					(thickness 0.15)
				)
			)
		)
		(sheetname "/Supply/")
		(sheetfile "supply.kicad_sch")
		(attr smd)
		(fp_line
			(start -1.45 -0.7)
			(end -1.45 -0.4)
			(stroke
				(width 0.12)
				(type solid)
			)
			(layer "F.SilkS")
		)
		(fp_line
			(start -1.45 0.7)
			(end -1.45 0.4)
			(stroke
				(width 0.12)
				(type solid)
			)
			(layer "F.SilkS")
		)
		(fp_line
			(start -1.3 -0.7)
			(end -1.45 -0.7)
			(stroke
				(width 0.12)
				(type solid)
			)
			(layer "F.SilkS")
		)
		(fp_line
			(start 1.3 -0.7)
			(end 1.45 -0.7)
			(stroke
				(width 0.12)
				(type solid)
			)
			(layer "F.SilkS")
		)
		(fp_line
			(start 1.3 0.7)
			(end 1.45 0.7)
			(stroke
				(width 0.12)
				(type solid)
			)
			(layer "F.SilkS")
		)
		(fp_line
			(start 1.45 -0.7)
			(end 1.45 -0.4)
			(stroke
				(width 0.12)
				(type solid)
			)
			(layer "F.SilkS")
		)
		(fp_line
			(start 1.45 0.7)
			(end 1.45 0.4)
			(stroke
				(width 0.12)
				(type solid)
			)
			(layer "F.SilkS")
		)
		(fp_rect
			(start -1.55 -1.85)
			(end 1.55 1.75)
			(stroke
				(width 0.05)
				(type solid)
			)
			(fill no)
			(layer "F.CrtYd")
		)
		(fp_line
			(start -1.5 -0.7)
			(end 1.5 -0.7)
			(stroke
				(width 0.1)
				(type solid)
			)
			(layer "F.Fab")
		)
		(fp_line
			(start -1.5 0.7)
			(end -1.5 -0.7)
			(stroke
				(width 0.1)
				(type solid)
			)
			(layer "F.Fab")
		)
		(fp_line
			(start 1.5 -0.7)
			(end 1.5 0.7)
			(stroke
				(width 0.1)
				(type solid)
			)
			(layer "F.Fab")
		)
		(fp_line
			(start 1.5 0.7)
			(end -1.5 0.7)
			(stroke
				(width 0.1)
				(type solid)
			)
			(layer "F.Fab")
		)
		(fp_text user "."
			(at -1.4 1.2 180)
			(layer "F.SilkS")
			(effects
				(font
					(size 1 1)
					(thickness 0.15)
				)
			)
		)
		(pad "1" smd roundrect
			(at -0.954 1.1)
			(size 0.55 1)
			(layers "F.Cu" "F.Mask" "F.Paste")
			(roundrect_rratio 0.15)
			(net 596 "/Supply/12V_PCIE_fused")
			(pinfunction "IN")
			(pintype "power_in")
		)
		(pad "2" smd roundrect
			(at -0.003 1.1)
			(size 0.55 1)
			(layers "F.Cu" "F.Mask" "F.Paste")
			(roundrect_rratio 0.15)
			(net 1 "GND")
			(pinfunction "GND")
			(pintype "power_in")
		)
		(pad "3" smd roundrect
			(at 0.947 1.1)
			(size 0.55 1)
			(layers "F.Cu" "F.Mask" "F.Paste")
			(roundrect_rratio 0.15)
			(net 1 "GND")
			(pinfunction "CTL")
			(pintype "input")
		)
		(pad "4" smd roundrect
			(at 0.947 -1.214)
			(size 0.55 1)
			(layers "F.Cu" "F.Mask" "F.Paste")
			(roundrect_rratio 0.15)
			(net 725 "unconnected-(U18-STAT-Pad4)")
			(pinfunction "STAT")
			(pintype "output+no_connect")
		)
		(pad "5" smd roundrect
			(at -0.003 -1.214)
			(size 0.55 1)
			(layers "F.Cu" "F.Mask" "F.Paste")
			(roundrect_rratio 0.15)
			(net 366 "Net-(Q13-G)")
			(pinfunction "GATE")
			(pintype "output")
		)
		(pad "6" smd roundrect
			(at -0.954 -1.214)
			(size 0.55 1)
			(layers "F.Cu" "F.Mask" "F.Paste")
			(roundrect_rratio 0.15)
			(net 38 "VDC")
			(pinfunction "SENSE")
			(pintype "input")
		)
	)
	(footprint "antmicro-footprints:X2SON8_1.4x1x0.32mm_P0.35mm"
		(layer "F.Cu")
		(at 104.81 175.535)
		(property "Reference" "U32"
			(at -0.62 3.165 90)
			(layer "F.SilkS")
			(effects
				(font
					(size 0.7 0.7)
					(thickness 0.15)
				)
				(justify left bottom)
			)
		)
		(property "Value" "TXS0102DQER"
			(at 0 1.929 0)
			(layer "F.Fab")
			(effects
				(font
					(size 0.7 0.7)
					(thickness 0.15)
				)
				(justify left bottom)
			)
		)
		(property "Datasheet" "https://www.ti.com/lit/ds/symlink/txs0102.pdf?ts=1637914596981&ref_url=https%253A%252F%252Fwww.ti.com%252Fstore%252Fti%252Fen%252Fp%252Fproduct%252F%253Fp%253DTXS0102DCTR%2526keyMatch%253DTXS0102DCTR%2526tisearch%253Dsearch-everything%2526usecase%253DOPN"
			(at 0 0 0)
			(layer "F.Fab")
			(hide yes)
			(effects
				(font
					(size 1.27 1.27)
					(thickness 0.15)
				)
			)
		)
		(property "Author" "Antmicro"
			(at 0 0 0)
			(layer "F.Fab")
			(hide yes)
			(effects
				(font
					(size 1 1)
					(thickness 0.15)
				)
			)
		)
		(property "License" "Apache-2.0"
			(at 0 0 0)
			(layer "F.Fab")
			(hide yes)
			(effects
				(font
					(size 1 1)
					(thickness 0.15)
				)
			)
		)
		(property "MPN" "TXS0102DQER"
			(at 0 0 0)
			(layer "F.Fab")
			(hide yes)
			(effects
				(font
					(size 1 1)
					(thickness 0.15)
				)
			)
		)
		(property "Manufacturer" "Texas Instruments"
			(at 0 0 0)
			(layer "F.Fab")
			(hide yes)
			(effects
				(font
					(size 1 1)
					(thickness 0.15)
				)
			)
		)
		(sheetname "/Debug FTDI/")
		(sheetfile "debug-ftdi.kicad_sch")
		(attr smd)
		(fp_line
			(start -0.6 -0.801)
			(end -0.6 -0.7)
			(stroke
				(width 0.15)
				(type solid)
			)
			(layer "F.SilkS")
		)
		(fp_line
			(start -0.6 0.7)
			(end -0.6 0.801)
			(stroke
				(width 0.15)
				(type solid)
			)
			(layer "F.SilkS")
		)
		(fp_line
			(start -0.6 0.801)
			(end -0.5 0.801)
			(stroke
				(width 0.15)
				(type solid)
			)
			(layer "F.SilkS")
		)
		(fp_line
			(start -0.402 -0.801)
			(end -0.6 -0.801)
			(stroke
				(width 0.15)
				(type solid)
			)
			(layer "F.SilkS")
		)
		(fp_line
			(start 0.598 -0.801)
			(end 0.498 -0.801)
			(stroke
				(width 0.15)
				(type solid)
			)
			(layer "F.SilkS")
		)
		(fp_line
			(start 0.598 -0.7)
			(end 0.598 -0.801)
			(stroke
				(width 0.15)
				(type solid)
			)
			(layer "F.SilkS")
		)
		(fp_line
			(start 0.598 0.7)
			(end 0.598 0.801)
			(stroke
				(width 0.15)
				(type solid)
			)
			(layer "F.SilkS")
		)
		(fp_line
			(start 0.598 0.801)
			(end 0.498 0.801)
			(stroke
				(width 0.15)
				(type solid)
			)
			(layer "F.SilkS")
		)
		(fp_circle
			(center -0.81 -0.77)
			(end -0.81 -0.72)
			(stroke
				(width 0.15)
				(type solid)
			)
			(fill yes)
			(layer "F.SilkS")
		)
		(fp_rect
			(start 0.75 -0.925)
			(end -0.75 0.925)
			(stroke
				(width 0.05)
				(type solid)
			)
			(fill no)
			(layer "F.CrtYd")
		)
		(fp_line
			(start -0.5 -0.729)
			(end -0.5 0.719)
			(stroke
				(width 0.15)
				(type solid)
			)
			(layer "F.Fab")
		)
		(fp_line
			(start -0.5 -0.724)
			(end 0.498 -0.724)
			(stroke
				(width 0.15)
				(type solid)
			)
			(layer "F.Fab")
		)
		(fp_line
			(start -0.5 0.724)
			(end 0.498 0.724)
			(stroke
				(width 0.15)
				(type solid)
			)
			(layer "F.Fab")
		)
		(fp_line
			(start 0.498 -0.719)
			(end 0.498 0.719)
			(stroke
				(width 0.15)
				(type solid)
			)
			(layer "F.Fab")
		)
		(pad "1" smd rect
			(at -0.43 -0.526 270)
			(size 0.17 0.5)
			(layers "F.Cu" "F.Mask" "F.Paste")
			(net 6 "/Debug FTDI/FTDI_3V3")
			(pinfunction "VCCA")
			(pintype "power_in")
		)
		(pad "2" smd rect
			(at -0.43 -0.175 270)
			(size 0.17 0.5)
			(layers "F.Cu" "F.Mask" "F.Paste")
			(net 640 "/Debug FTDI/FTDI_UART0_RX")
			(pinfunction "A1")
			(pintype "bidirectional")
		)
		(pad "3" smd rect
			(at -0.43 0.175 270)
			(size 0.17 0.5)
			(layers "F.Cu" "F.Mask" "F.Paste")
			(net 638 "/Debug FTDI/FTDI_UART0_TX")
			(pinfunction "A2")
			(pintype "bidirectional")
		)
		(pad "4" smd rect
			(at -0.43 0.526 270)
			(size 0.17 0.5)
			(layers "F.Cu" "F.Mask" "F.Paste")
			(net 1 "GND")
			(pinfunction "GND")
			(pintype "power_in")
		)
		(pad "5" smd rect
			(at 0.43 0.526 270)
			(size 0.17 0.5)
			(layers "F.Cu" "F.Mask" "F.Paste")
			(net 6 "/Debug FTDI/FTDI_3V3")
			(pinfunction "OE")
			(pintype "tri_state")
		)
		(pad "6" smd rect
			(at 0.43 0.175 270)
			(size 0.17 0.5)
			(layers "F.Cu" "F.Mask" "F.Paste")
			(net 747 "Net-(U32-B2)")
			(pinfunction "B2")
			(pintype "bidirectional")
		)
		(pad "7" smd rect
			(at 0.43 -0.175 270)
			(size 0.17 0.5)
			(layers "F.Cu" "F.Mask" "F.Paste")
			(net 746 "Net-(U32-B1)")
			(pinfunction "B1")
			(pintype "bidirectional")
		)
		(pad "8" smd rect
			(at 0.43 -0.526 270)
			(size 0.17 0.5)
			(layers "F.Cu" "F.Mask" "F.Paste")
			(net 200 "+3V3")
			(pinfunction "VCCB")
			(pintype "power_in")
		)
	)
	(footprint "antmicro-footprints:R_0402_1005Metric"
		(layer "F.Cu")
		(at 94.3 194.815 90)
		(descr "Resistor SMD 0402")
		(tags "resistor SMD 0402")
		(property "Reference" "R65"
			(at -1.122484 -0.772697 90)
			(layer "F.SilkS")
			(hide yes)
			(effects
				(font
					(size 0.7 0.7)
					(thickness 0.15)
				)
				(justify left bottom)
			)
		)
		(property "Value" "R_330R_0402"
			(at -1.011843 1.772047 90)
			(layer "F.Fab")
			(effects
				(font
					(size 0.7 0.7)
					(thickness 0.15)
				)
				(justify left bottom)
			)
		)
		(property "Datasheet" "https://www.bourns.com/docs/product-datasheets/cr.pdf"
			(at 0 0 90)
			(layer "F.Fab")
			(hide yes)
			(effects
				(font
					(size 1.27 1.27)
					(thickness 0.15)
				)
			)
		)
		(property "Author" "Antmicro"
			(at 289.115 100.515 0)
			(layer "F.Fab")
			(hide yes)
			(effects
				(font
					(size 1 1)
					(thickness 0.15)
				)
			)
		)
		(property "License" "Apache-2.0"
			(at 289.115 100.515 0)
			(layer "F.Fab")
			(hide yes)
			(effects
				(font
					(size 1 1)
					(thickness 0.15)
				)
			)
		)
		(property "MPN" "CR0402-FX-3300GLF"
			(at 289.115 100.515 0)
			(layer "F.Fab")
			(hide yes)
			(effects
				(font
					(size 1 1)
					(thickness 0.15)
				)
			)
		)
		(property "Manufacturer" "Bourns"
			(at 289.115 100.515 0)
			(layer "F.Fab")
			(hide yes)
			(effects
				(font
					(size 1 1)
					(thickness 0.15)
				)
			)
		)
		(property "Tolerance" "1%"
			(at 289.115 100.515 0)
			(layer "F.Fab")
			(hide yes)
			(effects
				(font
					(size 1 1)
					(thickness 0.15)
				)
			)
		)
		(property "Val" "330R"
			(at 289.115 100.515 0)
			(layer "F.Fab")
			(hide yes)
			(effects
				(font
					(size 1 1)
					(thickness 0.15)
				)
			)
		)
		(sheetname "/Debug FTDI/")
		(sheetfile "debug-ftdi.kicad_sch")
		(attr smd)
		(fp_rect
			(start -0.93 -0.47)
			(end 0.93 0.47)
			(stroke
				(width 0.05)
				(type solid)
			)
			(fill no)
			(layer "F.CrtYd")
		)
		(fp_rect
			(start -0.5 -0.25)
			(end 0.5 0.25)
			(stroke
				(width 0.15)
				(type solid)
			)
			(fill no)
			(layer "F.Fab")
		)
		(pad "1" smd roundrect
			(at -0.485 0 90)
			(size 0.59 0.64)
			(layers "F.Cu" "F.Mask" "F.Paste")
			(roundrect_rratio 0.25)
			(net 316 "Net-(D11-Pad1)")
			(pintype "passive")
		)
		(pad "2" smd roundrect
			(at 0.485 0 90)
			(size 0.59 0.64)
			(layers "F.Cu" "F.Mask" "F.Paste")
			(roundrect_rratio 0.25)
			(net 657 "/Debug FTDI/LED_RX0")
			(pintype "passive")
		)
	)
	(footprint "antmicro-footprints:R_0402_1005Metric"
		(layer "F.Cu")
		(at 177.9125 181.315)
		(descr "Resistor SMD 0402")
		(tags "resistor SMD 0402")
		(property "Reference" "R137"
			(at -1.122484 -0.772697 0)
			(layer "F.SilkS")
			(hide yes)
			(effects
				(font
					(size 0.7 0.7)
					(thickness 0.15)
				)
				(justify left bottom)
			)
		)
		(property "Value" "R_0R_0402"
			(at -1.011843 1.772047 0)
			(layer "F.Fab")
			(effects
				(font
					(size 0.7 0.7)
					(thickness 0.15)
				)
				(justify left bottom)
			)
		)
		(property "Datasheet" "https://industrial.panasonic.com/cdbs/www-data/pdf/RDA0000/AOA0000C301.pdf"
			(at 0 0 0)
			(layer "F.Fab")
			(hide yes)
			(effects
				(font
					(size 1.27 1.27)
					(thickness 0.15)
				)
			)
		)
		(property "Author" "Antmicro"
			(at 0 0 0)
			(layer "F.Fab")
			(hide yes)
			(effects
				(font
					(size 1 1)
					(thickness 0.15)
				)
			)
		)
		(property "Current" "1A"
			(at 0 0 0)
			(layer "F.Fab")
			(hide yes)
			(effects
				(font
					(size 1 1)
					(thickness 0.15)
				)
			)
		)
		(property "License" "Apache-2.0"
			(at 0 0 0)
			(layer "F.Fab")
			(hide yes)
			(effects
				(font
					(size 1 1)
					(thickness 0.15)
				)
			)
		)
		(property "MPN" "ERJ2GE0R00X"
			(at 0 0 0)
			(layer "F.Fab")
			(hide yes)
			(effects
				(font
					(size 1 1)
					(thickness 0.15)
				)
			)
		)
		(property "Manufacturer" "Panasonic"
			(at 0 0 0)
			(layer "F.Fab")
			(hide yes)
			(effects
				(font
					(size 1 1)
					(thickness 0.15)
				)
			)
		)
		(property "Tolerance" ""
			(at 0 0 0)
			(layer "F.Fab")
			(hide yes)
			(effects
				(font
					(size 1 1)
					(thickness 0.15)
				)
			)
		)
		(property "Val" "0R"
			(at 0 0 0)
			(layer "F.Fab")
			(hide yes)
			(effects
				(font
					(size 1 1)
					(thickness 0.15)
				)
			)
		)
		(sheetname "/Supply/")
		(sheetfile "supply.kicad_sch")
		(attr smd)
		(fp_rect
			(start -0.93 -0.47)
			(end 0.93 0.47)
			(stroke
				(width 0.05)
				(type solid)
			)
			(fill no)
			(layer "F.CrtYd")
		)
		(fp_rect
			(start -0.5 -0.25)
			(end 0.5 0.25)
			(stroke
				(width 0.15)
				(type solid)
			)
			(fill no)
			(layer "F.Fab")
		)
		(pad "1" smd roundrect
			(at -0.485 0)
			(size 0.59 0.64)
			(layers "F.Cu" "F.Mask" "F.Paste")
			(roundrect_rratio 0.25)
			(net 240 "POWER")
			(pintype "passive")
		)
		(pad "2" smd roundrect
			(at 0.485 0)
			(size 0.59 0.64)
			(layers "F.Cu" "F.Mask" "F.Paste")
			(roundrect_rratio 0.25)
			(net 281 "/Supply/PG2")
			(pintype "passive")
		)
	)
	(footprint "antmicro-footprints:TP_1206_SMD_RCW-0C"
		(layer "F.Cu")
		(at 194 177.1 180)
		(property "Reference" "TP14"
			(at -2.29 -1.4 180)
			(layer "F.SilkS")
			(hide yes)
			(effects
				(font
					(size 0.7 0.7)
					(thickness 0.15)
				)
				(justify left bottom)
			)
		)
		(property "Value" "TP_1206_SMD_RCW-0C"
			(at -4.68 2.25 180)
			(layer "F.Fab")
			(effects
				(font
					(size 0.7 0.7)
					(thickness 0.15)
				)
				(justify left bottom)
			)
		)
		(property "Datasheet" "https://www.te.com/commerce/DocumentDelivery/DDEController?Action=srchrtrv&DocNm=1773266&DocType=DS&DocLang=English"
			(at 0 0 180)
			(layer "F.Fab")
			(hide yes)
			(effects
				(font
					(size 1.27 1.27)
					(thickness 0.15)
				)
			)
		)
		(property "Author" "Antmicro"
			(at 388 354.2 0)
			(layer "F.Fab")
			(hide yes)
			(effects
				(font
					(size 1 1)
					(thickness 0.15)
				)
			)
		)
		(property "License" "Apache-2.0"
			(at 388 354.2 0)
			(layer "F.Fab")
			(hide yes)
			(effects
				(font
					(size 1 1)
					(thickness 0.15)
				)
			)
		)
		(property "MPN" "RCW-0C"
			(at 388 354.2 0)
			(layer "F.Fab")
			(hide yes)
			(effects
				(font
					(size 1 1)
					(thickness 0.15)
				)
			)
		)
		(property "Manufacturer" "TE Connectivity"
			(at 388 354.2 0)
			(layer "F.Fab")
			(hide yes)
			(effects
				(font
					(size 1 1)
					(thickness 0.15)
				)
			)
		)
		(sheetname "/Supply/")
		(sheetfile "supply.kicad_sch")
		(attr smd)
		(fp_line
			(start 1.78 0.982)
			(end 1.78 0.482)
			(stroke
				(width 0.15)
				(type solid)
			)
			(layer "F.SilkS")
		)
		(fp_line
			(start 1.78 0.982)
			(end 1.281 0.982)
			(stroke
				(width 0.15)
				(type solid)
			)
			(layer "F.SilkS")
		)
		(fp_line
			(start 1.78 -0.981)
			(end 1.78 -0.479)
			(stroke
				(width 0.15)
				(type solid)
			)
			(layer "F.SilkS")
		)
		(fp_line
			(start 1.78 -0.981)
			(end 1.281 -0.981)
			(stroke
				(width 0.15)
				(type solid)
			)
			(layer "F.SilkS")
		)
		(fp_line
			(start -1.779 0.98)
			(end -1.279 0.98)
			(stroke
				(width 0.15)
				(type solid)
			)
			(layer "F.SilkS")
		)
		(fp_line
			(start -1.779 0.482)
			(end -1.779 0.98)
			(stroke
				(width 0.15)
				(type solid)
			)
			(layer "F.SilkS")
		)
		(fp_line
			(start -1.779 -0.981)
			(end -1.279 -0.981)
			(stroke
				(width 0.15)
				(type solid)
			)
			(layer "F.SilkS")
		)
		(fp_line
			(start -1.779 -0.981)
			(end -1.779 -0.479)
			(stroke
				(width 0.15)
				(type solid)
			)
			(layer "F.SilkS")
		)
		(fp_rect
			(start -2.101 -1.314)
			(end 2.1 1.312)
			(stroke
				(width 0.05)
				(type solid)
			)
			(fill no)
			(layer "F.CrtYd")
		)
		(fp_rect
			(start -1.601 -0.814)
			(end 1.6 0.812)
			(stroke
				(width 0.15)
				(type solid)
			)
			(fill no)
			(layer "F.Fab")
		)
		(pad "1" smd rect
			(at 0 0 180)
			(size 3.4 1.8)
			(layers "F.Cu" "F.Mask" "F.Paste")
			(net 239 "/Supply/spare")
			(pinfunction "1")
			(pintype "passive")
		)
	)
	(footprint "antmicro-footprints:SC70-3"
		(layer "F.Cu")
		(at 192.65 141.7)
		(property "Reference" "Q16"
			(at 0 -1.6 0)
			(layer "F.SilkS")
			(hide yes)
			(effects
				(font
					(size 0.7 0.7)
					(thickness 0.15)
				)
				(justify left bottom)
			)
		)
		(property "Value" "BSS138PW,115"
			(at 0 2.3 0)
			(layer "F.Fab")
			(effects
				(font
					(size 0.7 0.7)
					(thickness 0.15)
				)
				(justify left bottom)
			)
		)
		(property "Datasheet" "https://assets.nexperia.com/documents/data-sheet/BSS138PW.pdf"
			(at 0 0 0)
			(layer "F.Fab")
			(hide yes)
			(effects
				(font
					(size 1.27 1.27)
					(thickness 0.15)
				)
			)
		)
		(property "Description" "Power MOSFET, N Channel, 60 V, 320 mA, 0.9 ohm, SOT-323, Surface Mount"
			(at 0 0 0)
			(layer "F.Fab")
			(hide yes)
			(effects
				(font
					(size 1.27 1.27)
					(thickness 0.15)
				)
			)
		)
		(property "Author" "Antmicro"
			(at 0 0 0)
			(layer "F.Fab")
			(hide yes)
			(effects
				(font
					(size 1 1)
					(thickness 0.15)
				)
			)
		)
		(property "License" "Apache-2.0"
			(at 0 0 0)
			(layer "F.Fab")
			(hide yes)
			(effects
				(font
					(size 1 1)
					(thickness 0.15)
				)
			)
		)
		(property "MPN" "BSS138PW,115"
			(at 0 0 0)
			(layer "F.Fab")
			(hide yes)
			(effects
				(font
					(size 1 1)
					(thickness 0.15)
				)
			)
		)
		(property "Manufacturer" "Nexperia"
			(at 0 0 0)
			(layer "F.Fab")
			(hide yes)
			(effects
				(font
					(size 1 1)
					(thickness 0.15)
				)
			)
		)
		(sheetname "/Supply/")
		(sheetfile "supply.kicad_sch")
		(attr smd)
		(fp_line
			(start -0.3 -1)
			(end 0.627 -0.999)
			(stroke
				(width 0.15)
				(type solid)
			)
			(layer "F.SilkS")
		)
		(fp_line
			(start -0.3 1)
			(end 0.627 1.001)
			(stroke
				(width 0.15)
				(type solid)
			)
			(layer "F.SilkS")
		)
		(fp_line
			(start 0.627 -0.6)
			(end 0.627 -0.999)
			(stroke
				(width 0.15)
				(type solid)
			)
			(layer "F.SilkS")
		)
		(fp_line
			(start 0.627 0.6)
			(end 0.627 1.001)
			(stroke
				(width 0.15)
				(type solid)
			)
			(layer "F.SilkS")
		)
		(fp_line
			(start -1.4 1)
			(end -1.4 -1)
			(stroke
				(width 0.05)
				(type solid)
			)
			(layer "F.CrtYd")
		)
		(fp_line
			(start -0.9 -1.3)
			(end -0.9 -1)
			(stroke
				(width 0.05)
				(type solid)
			)
			(layer "F.CrtYd")
		)
		(fp_line
			(start -0.9 -1.3)
			(end 0.9 -1.3)
			(stroke
				(width 0.05)
				(type solid)
			)
			(layer "F.CrtYd")
		)
		(fp_line
			(start -0.9 -1)
			(end -1.4 -1)
			(stroke
				(width 0.05)
				(type solid)
			)
			(layer "F.CrtYd")
		)
		(fp_line
			(start -0.9 1)
			(end -1.4 1)
			(stroke
				(width 0.05)
				(type solid)
			)
			(layer "F.CrtYd")
		)
		(fp_line
			(start -0.9 1.3)
			(end -0.9 1)
			(stroke
				(width 0.05)
				(type solid)
			)
			(layer "F.CrtYd")
		)
		(fp_line
			(start 0.9 -1.3)
			(end 0.9 -0.4)
			(stroke
				(width 0.05)
				(type solid)
			)
			(layer "F.CrtYd")
		)
		(fp_line
			(start 0.9 -0.4)
			(end 1.4 -0.4)
			(stroke
				(width 0.05)
				(type solid)
			)
			(layer "F.CrtYd")
		)
		(fp_line
			(start 0.9 0.4)
			(end 0.9 1.3)
			(stroke
				(width 0.05)
				(type solid)
			)
			(layer "F.CrtYd")
		)
		(fp_line
			(start 0.9 1.3)
			(end -0.9 1.3)
			(stroke
				(width 0.05)
				(type solid)
			)
			(layer "F.CrtYd")
		)
		(fp_line
			(start 1.4 -0.4)
			(end 1.4 0.4)
			(stroke
				(width 0.05)
				(type solid)
			)
			(layer "F.CrtYd")
		)
		(fp_line
			(start 1.4 0.4)
			(end 0.9 0.4)
			(stroke
				(width 0.05)
				(type solid)
			)
			(layer "F.CrtYd")
		)
		(fp_rect
			(start -0.623 -0.999)
			(end 0.627 1.001)
			(stroke
				(width 0.15)
				(type solid)
			)
			(fill no)
			(layer "F.Fab")
		)
		(pad "1" smd rect
			(at -1.051 -0.65 90)
			(size 0.6 0.6)
			(layers "F.Cu" "F.Mask" "F.Paste")
			(net 241 "FPGA_POWER_CYCLE")
			(pinfunction "G")
			(pintype "input")
		)
		(pad "2" smd rect
			(at -1.051 0.65 90)
			(size 0.6 0.6)
			(layers "F.Cu" "F.Mask" "F.Paste")
			(net 1 "GND")
			(pinfunction "S")
			(pintype "passive")
		)
		(pad "3" smd rect
			(at 1.05 0 90)
			(size 0.6 0.6)
			(layers "F.Cu" "F.Mask" "F.Paste")
			(net 367 "Net-(Q16-D)")
			(pinfunction "D")
			(pintype "passive")
		)
	)
	(footprint "antmicro-footprints:MPS_QFN-14_MP8869S"
		(layer "F.Cu")
		(at 172.869501 194.216501 -90)
		(property "Reference" "U27"
			(at 3.983499 2.069501 270)
			(layer "F.SilkS")
			(effects
				(font
					(size 0.7 0.7)
					(thickness 0.15)
				)
				(justify left bottom)
			)
		)
		(property "Value" "MP8869S"
			(at -5.5 3.43 270)
			(layer "F.Fab")
			(effects
				(font
					(size 0.7 0.7)
					(thickness 0.15)
				)
				(justify left bottom)
			)
		)
		(property "Datasheet" "https://www.mouser.com/datasheet/2/277/MP8869S-2946178.pdf"
			(at 0 0 270)
			(layer "F.Fab")
			(hide yes)
			(effects
				(font
					(size 1.27 1.27)
					(thickness 0.15)
				)
			)
		)
		(property "Author" "Antmicro"
			(at -21.347 367.086002 0)
			(layer "F.Fab")
			(hide yes)
			(effects
				(font
					(size 1 1)
					(thickness 0.15)
				)
			)
		)
		(property "License" "Apache-2.0"
			(at -21.347 367.086002 0)
			(layer "F.Fab")
			(hide yes)
			(effects
				(font
					(size 1 1)
					(thickness 0.15)
				)
			)
		)
		(property "MPN" "MP8869SGL-P"
			(at -21.347 367.086002 0)
			(layer "F.Fab")
			(hide yes)
			(effects
				(font
					(size 1 1)
					(thickness 0.15)
				)
			)
		)
		(property "Manufacturer" "Monolithic Power Systems"
			(at -21.347 367.086002 0)
			(layer "F.Fab")
			(hide yes)
			(effects
				(font
					(size 1 1)
					(thickness 0.15)
				)
			)
		)
		(property ki_fp_filters "QFN-14_MP8869S_MNP")
		(sheetname "/Supply/")
		(sheetfile "supply.kicad_sch")
		(attr smd)
		(fp_line
			(start -1.678 2.171)
			(end -1.678 0.481)
			(stroke
				(width 0.15)
				(type solid)
			)
			(layer "F.SilkS")
		)
		(fp_line
			(start 1.675 0.981)
			(end 1.675 2.171)
			(stroke
				(width 0.15)
				(type solid)
			)
			(layer "F.SilkS")
		)
		(fp_line
			(start -1.678 -0.959)
			(end -1.678 -2.173)
			(stroke
				(width 0.15)
				(type solid)
			)
			(layer "F.SilkS")
		)
		(fp_line
			(start 1.675 -2.173)
			(end 1.675 -0.983)
			(stroke
				(width 0.15)
				(type solid)
			)
			(layer "F.SilkS")
		)
		(fp_circle
			(center -2.361 -0.5)
			(end -2.311 -0.5)
			(stroke
				(width 0.15)
				(type solid)
			)
			(fill yes)
			(layer "F.SilkS")
		)
		(fp_rect
			(start -2.061 -2.55)
			(end 2.06 2.548)
			(stroke
				(width 0.05)
				(type solid)
			)
			(fill no)
			(layer "F.CrtYd")
		)
		(fp_line
			(start -1.551 2.043)
			(end 1.548 2.043)
			(stroke
				(width 0.15)
				(type solid)
			)
			(layer "F.Fab")
		)
		(fp_line
			(start 1.548 2.043)
			(end 1.548 -2.045)
			(stroke
				(width 0.15)
				(type solid)
			)
			(layer "F.Fab")
		)
		(fp_line
			(start -1.541 -1.841)
			(end -1.341 -2.04)
			(stroke
				(width 0.15)
				(type solid)
			)
			(layer "F.Fab")
		)
		(fp_line
			(start -1.551 -2.045)
			(end -1.551 2.043)
			(stroke
				(width 0.15)
				(type solid)
			)
			(layer "F.Fab")
		)
		(fp_line
			(start 1.548 -2.045)
			(end -1.551 -2.045)
			(stroke
				(width 0.15)
				(type solid)
			)
			(layer "F.Fab")
		)
		(pad "1" smd custom
			(at -1.401 -0.5 270)
			(size 0.799998 0.249998)
			(layers "F.Cu" "F.Mask" "F.Paste")
			(net 67 "/Supply/1V0_BS")
			(pinfunction "BST")
			(pintype "unspecified")
			(options
				(clearance outline)
				(anchor rect)
			)
			(primitives
				(gr_poly
					(pts
						(xy -0.400002 -0.125001) (xy -0.400002 0.124999) (xy 0.499998 0.124999) (xy 0.499998 -0.000001)
						(xy 0.374998 -0.125001)
					)
					(width 0.1)
					(fill yes)
				)
			)
		)
		(pad "2" smd rect
			(at -0.851 0 270)
			(size 1.9 0.3)
			(layers "F.Cu" "F.Mask" "F.Paste")
			(net 66 "/Supply/1V0_SW")
			(pinfunction "SW")
			(pintype "output")
		)
		(pad "3" smd rect
			(at -1.002 1.848)
			(size 0.9 0.25)
			(layers "F.Cu" "F.Mask" "F.Paste")
			(net 691 "/I^{2}C/PWR.SCL")
			(pinfunction "SCL")
			(pintype "unspecified")
		)
		(pad "4" smd rect
			(at -0.5 1.848)
			(size 0.9 0.25)
			(layers "F.Cu" "F.Mask" "F.Paste")
			(net 690 "/I^{2}C/PWR.SDA")
			(pinfunction "SDA")
			(pintype "unspecified")
		)
		(pad "5" smd rect
			(at 0 1.848)
			(size 0.9 0.25)
			(layers "F.Cu" "F.Mask" "F.Paste")
			(net 221 "/Supply/EN1")
			(pinfunction "EN")
			(pintype "unspecified")
		)
		(pad "6" smd rect
			(at 0.498 1.848)
			(size 0.9 0.25)
			(layers "F.Cu" "F.Mask" "F.Paste")
			(net 1 "GND")
			(pinfunction "A0")
			(pintype "unspecified")
		)
		(pad "7" smd rect
			(at 0.999 1.848)
			(size 0.9 0.25)
			(layers "F.Cu" "F.Mask" "F.Paste")
			(net 280 "/Supply/PG1")
			(pinfunction "PG")
			(pintype "unspecified")
		)
		(pad "8" smd custom
			(at 0.849 0.498 270)
			(size 0.127 0.127)
			(layers "F.Cu" "F.Mask" "F.Paste")
			(net 1 "GND")
			(pinfunction "PGND")
			(pintype "power_in")
			(options
				(clearance outline)
				(anchor rect)
			)
			(primitives
				(gr_poly
					(pts
						(xy 0.95 0.15) (xy 0.95 -0.15) (xy -0.55 -0.15) (xy -0.65 -0.05) (xy -0.95 -0.05) (xy -0.95 0.15)
					)
					(width 0.1)
					(fill yes)
				)
			)
		)
		(pad "9" smd custom
			(at 0.849 -0.5 270)
			(size 0.127 0.127)
			(layers "F.Cu" "F.Mask" "F.Paste")
			(net 38 "VDC")
			(pinfunction "VIN")
			(pintype "power_in")
			(options
				(clearance outline)
				(anchor rect)
			)
			(primitives
				(gr_poly
					(pts
						(xy 0.95 -0.15) (xy 0.95 0.15) (xy -0.55 0.15) (xy -0.65 0.05) (xy -0.95 0.05) (xy -0.95 -0.15)
					)
					(width 0.1)
					(fill yes)
				)
			)
		)
		(pad "10" smd rect
			(at 0.999 -1.851)
			(size 0.9 0.25)
			(layers "F.Cu" "F.Mask" "F.Paste")
			(net 78 "/Supply/1V0_REG")
			(pinfunction "VOUT")
			(pintype "unspecified")
		)
		(pad "11" smd rect
			(at 0.498 -1.851)
			(size 0.9 0.25)
			(layers "F.Cu" "F.Mask" "F.Paste")
			(net 225 "/Supply/1V0_FB")
			(pinfunction "FB")
			(pintype "unspecified")
		)
		(pad "12" smd rect
			(at 0 -1.851)
			(size 0.9 0.25)
			(layers "F.Cu" "F.Mask" "F.Paste")
			(net 75 "/Supply/1V0_SS")
			(pinfunction "SS")
			(pintype "unspecified")
		)
		(pad "13" smd rect
			(at -0.5 -1.851)
			(size 0.9 0.25)
			(layers "F.Cu" "F.Mask" "F.Paste")
			(net 63 "/Supply/1V0_VCC")
			(pinfunction "VCC")
			(pintype "power_out")
		)
		(pad "14" smd rect
			(at -1.002 -1.851)
			(size 0.9 0.25)
			(layers "F.Cu" "F.Mask" "F.Paste")
			(net 1 "GND")
			(pinfunction "AGND")
			(pintype "power_in")
		)
	)
	(footprint "antmicro-footprints:R_0402_1005Metric"
		(layer "F.Cu")
		(at 190.545 138.9 90)
		(descr "Resistor SMD 0402")
		(tags "resistor SMD 0402")
		(property "Reference" "R161"
			(at -1.122484 -0.772697 90)
			(layer "F.SilkS")
			(hide yes)
			(effects
				(font
					(size 0.7 0.7)
					(thickness 0.15)
				)
				(justify left bottom)
			)
		)
		(property "Value" "R_47k_0402"
			(at -1.011843 1.772047 90)
			(layer "F.Fab")
			(effects
				(font
					(size 0.7 0.7)
					(thickness 0.15)
				)
				(justify left bottom)
			)
		)
		(property "Datasheet" "https://www.bourns.com/docs/product-datasheets/cr.pdf"
			(at 0 0 90)
			(layer "F.Fab")
			(hide yes)
			(effects
				(font
					(size 1.27 1.27)
					(thickness 0.15)
				)
			)
		)
		(property "Author" "Antmicro"
			(at 329.445 -51.645 0)
			(layer "F.Fab")
			(hide yes)
			(effects
				(font
					(size 1 1)
					(thickness 0.15)
				)
			)
		)
		(property "License" "Apache-2.0"
			(at 329.445 -51.645 0)
			(layer "F.Fab")
			(hide yes)
			(effects
				(font
					(size 1 1)
					(thickness 0.15)
				)
			)
		)
		(property "MPN" "CR0402-FX-4702GLF"
			(at 329.445 -51.645 0)
			(layer "F.Fab")
			(hide yes)
			(effects
				(font
					(size 1 1)
					(thickness 0.15)
				)
			)
		)
		(property "Manufacturer" "Bourns"
			(at 329.445 -51.645 0)
			(layer "F.Fab")
			(hide yes)
			(effects
				(font
					(size 1 1)
					(thickness 0.15)
				)
			)
		)
		(property "Tolerance" "1%"
			(at 329.445 -51.645 0)
			(layer "F.Fab")
			(hide yes)
			(effects
				(font
					(size 1 1)
					(thickness 0.15)
				)
			)
		)
		(property "Val" "47k"
			(at 329.445 -51.645 0)
			(layer "F.Fab")
			(hide yes)
			(effects
				(font
					(size 1 1)
					(thickness 0.15)
				)
			)
		)
		(sheetname "/Supply/")
		(sheetfile "supply.kicad_sch")
		(attr smd)
		(fp_rect
			(start -0.93 -0.47)
			(end 0.93 0.47)
			(stroke
				(width 0.05)
				(type solid)
			)
			(fill no)
			(layer "F.CrtYd")
		)
		(fp_rect
			(start -0.5 -0.25)
			(end 0.5 0.25)
			(stroke
				(width 0.15)
				(type solid)
			)
			(fill no)
			(layer "F.Fab")
		)
		(pad "1" smd roundrect
			(at -0.485 0 90)
			(size 0.59 0.64)
			(layers "F.Cu" "F.Mask" "F.Paste")
			(roundrect_rratio 0.25)
			(net 1 "GND")
			(pintype "passive")
		)
		(pad "2" smd roundrect
			(at 0.485 0 90)
			(size 0.59 0.64)
			(layers "F.Cu" "F.Mask" "F.Paste")
			(roundrect_rratio 0.25)
			(net 242 "FPGA_POWER_OFF")
			(pintype "passive")
		)
	)
	(footprint "antmicro-footprints:NetTie-2_SMD_Pad0.127mm"
		(layer "F.Cu")
		(at 187.85 179.5 180)
		(descr "Net tie, 2 pin, 0.127mm  SMD pads")
		(tags "net tie")
		(property "Reference" "NT10"
			(at -0.128 -1.345 180)
			(layer "F.SilkS")
			(hide yes)
			(effects
				(font
					(size 0.7 0.7)
					(thickness 0.15)
				)
				(justify left bottom)
			)
		)
		(property "Value" "Net-Tie_P0.127mm"
			(at 0 1.199 180)
			(layer "F.Fab")
			(effects
				(font
					(size 0.7 0.7)
					(thickness 0.15)
				)
				(justify left bottom)
			)
		)
		(property "Author" "Antmicro"
			(at 375.7 359 0)
			(layer "F.Fab")
			(hide yes)
			(effects
				(font
					(size 1 1)
					(thickness 0.15)
				)
			)
		)
		(property "License" "Apache-2.0"
			(at 375.7 359 0)
			(layer "F.Fab")
			(hide yes)
			(effects
				(font
					(size 1 1)
					(thickness 0.15)
				)
			)
		)
		(property "MPN" ""
			(at 375.7 359 0)
			(layer "F.Fab")
			(hide yes)
			(effects
				(font
					(size 1 1)
					(thickness 0.15)
				)
			)
		)
		(property "Manufacturer" ""
			(at 375.7 359 0)
			(layer "F.Fab")
			(hide yes)
			(effects
				(font
					(size 1 1)
					(thickness 0.15)
				)
			)
		)
		(property ki_fp_filters "Net*Tie*")
		(sheetname "/Supply/")
		(sheetfile "supply.kicad_sch")
		(attr smd exclude_from_pos_files exclude_from_bom)
		(net_tie_pad_groups "1, 2")
		(fp_poly
			(pts
				(xy -0.0635 -0.0635) (xy 0.0625 -0.0635) (xy 0.0625 0.0635) (xy -0.0635 0.0635)
			)
			(stroke
				(width 0)
				(type solid)
			)
			(fill yes)
			(layer "F.Cu")
		)
		(pad "1" smd roundrect
			(at -0.127 0)
			(size 0.127 0.127)
			(layers "F.Cu")
			(roundrect_rratio 0.5)
			(chamfer_ratio 0)
			(chamfer top_left bottom_left)
			(net 246 "/Supply/1V8_SEN_-")
			(pinfunction "1")
			(pintype "passive")
		)
		(pad "2" smd roundrect
			(at 0.126 0 180)
			(size 0.127 0.127)
			(layers "F.Cu")
			(roundrect_rratio 0.5)
			(chamfer_ratio 0)
			(chamfer top_left bottom_left)
			(net 188 "+1V8")
			(pinfunction "2")
			(pintype "passive")
		)
	)
	(footprint "antmicro-footprints:USON-10_2.5x1mm_P0.5mm"
		(layer "F.Cu")
		(at 82.4 191 180)
		(descr "USON-10 2.5x1mm_ Pitch 0.5mm")
		(tags "USON-10 2.5x1mm Pitch 0.5mm")
		(property "Reference" "U11"
			(at 0.018 -1.7 180)
			(layer "F.SilkS")
			(hide yes)
			(effects
				(font
					(size 0.7 0.7)
					(thickness 0.15)
				)
				(justify left bottom)
			)
		)
		(property "Value" "TPD4E05U06QDQARQ1"
			(at 0.018 2.499 180)
			(layer "F.Fab")
			(effects
				(font
					(size 0.7 0.7)
					(thickness 0.15)
				)
				(justify left bottom)
			)
		)
		(property "Datasheet" "https://www.ti.com/lit/ds/symlink/tpd4e05u06-q1.pdf?HQS=dis-mous-null-mousermode-dsf-pf-null-wwe&ts=1663591265741&ref_url=https%253A%252F%252Fwww.mouser.com%252F"
			(at 0 0 180)
			(layer "F.Fab")
			(hide yes)
			(effects
				(font
					(size 1.27 1.27)
					(thickness 0.15)
				)
			)
		)
		(property "Author" "Antmicro"
			(at 164.8 382 0)
			(layer "F.Fab")
			(hide yes)
			(effects
				(font
					(size 1 1)
					(thickness 0.15)
				)
			)
		)
		(property "License" "Apache-2.0"
			(at 164.8 382 0)
			(layer "F.Fab")
			(hide yes)
			(effects
				(font
					(size 1 1)
					(thickness 0.15)
				)
			)
		)
		(property "MPN" "TPD4E05U06QDQARQ1"
			(at 164.8 382 0)
			(layer "F.Fab")
			(hide yes)
			(effects
				(font
					(size 1 1)
					(thickness 0.15)
				)
			)
		)
		(property "Manufacturer" "Texas Instruments"
			(at 164.8 382 0)
			(layer "F.Fab")
			(hide yes)
			(effects
				(font
					(size 1 1)
					(thickness 0.15)
				)
			)
		)
		(sheetname "/HDMI + SD Card/")
		(sheetfile "hdmi-sd-card.kicad_sch")
		(attr smd)
		(fp_line
			(start 0.498 1.398)
			(end -0.5 1.398)
			(stroke
				(width 0.15)
				(type solid)
			)
			(layer "F.SilkS")
		)
		(fp_line
			(start 0.498 -1.401)
			(end -0.5 -1.401)
			(stroke
				(width 0.15)
				(type solid)
			)
			(layer "F.SilkS")
		)
		(fp_circle
			(center -0.68 -1.27)
			(end -0.63 -1.27)
			(stroke
				(width 0.15)
				(type solid)
			)
			(fill yes)
			(layer "F.SilkS")
		)
		(fp_rect
			(start -0.8 -1.5)
			(end 0.8 1.499)
			(stroke
				(width 0.05)
				(type solid)
			)
			(fill no)
			(layer "F.CrtYd")
		)
		(fp_line
			(start 0.498 -1.25)
			(end 0.498 1.249)
			(stroke
				(width 0.15)
				(type solid)
			)
			(layer "F.Fab")
		)
		(fp_line
			(start 0.498 -1.25)
			(end -0.25 -1.25)
			(stroke
				(width 0.15)
				(type solid)
			)
			(layer "F.Fab")
		)
		(fp_line
			(start -0.25 -1.25)
			(end -0.5 -1)
			(stroke
				(width 0.15)
				(type solid)
			)
			(layer "F.Fab")
		)
		(fp_line
			(start -0.5 1.249)
			(end 0.498 1.249)
			(stroke
				(width 0.15)
				(type solid)
			)
			(layer "F.Fab")
		)
		(fp_line
			(start -0.5 -1)
			(end -0.5 1.249)
			(stroke
				(width 0.15)
				(type solid)
			)
			(layer "F.Fab")
		)
		(pad "1" smd roundrect
			(at -0.387 -1 90)
			(size 0.25 0.55)
			(layers "F.Cu" "F.Mask" "F.Paste")
			(roundrect_rratio 0.25)
			(net 296 "/HDMI + SD Card/HDMI_CONN_D0_P")
			(pintype "passive")
		)
		(pad "2" smd roundrect
			(at -0.387 -0.5 90)
			(size 0.25 0.55)
			(layers "F.Cu" "F.Mask" "F.Paste")
			(roundrect_rratio 0.25)
			(net 311 "/HDMI + SD Card/HDMI_CONN_D0_N")
			(pintype "passive")
		)
		(pad "3" smd roundrect
			(at -0.387 0 90)
			(size 0.4 0.55)
			(layers "F.Cu" "F.Mask" "F.Paste")
			(roundrect_rratio 0.25)
			(net 1 "GND")
			(pintype "power_in")
		)
		(pad "4" smd roundrect
			(at -0.387 0.498 90)
			(size 0.25 0.55)
			(layers "F.Cu" "F.Mask" "F.Paste")
			(roundrect_rratio 0.25)
			(net 348 "/HDMI + SD Card/HDMI_CONN_CLK_P")
			(pintype "passive")
		)
		(pad "5" smd roundrect
			(at -0.387 0.998 90)
			(size 0.25 0.55)
			(layers "F.Cu" "F.Mask" "F.Paste")
			(roundrect_rratio 0.25)
			(net 349 "/HDMI + SD Card/HDMI_CONN_CLK_N")
			(pintype "passive")
		)
		(pad "6" smd roundrect
			(at 0.385 0.998 90)
			(size 0.25 0.55)
			(layers "F.Cu" "F.Mask" "F.Paste")
			(roundrect_rratio 0.25)
			(net 349 "/HDMI + SD Card/HDMI_CONN_CLK_N")
			(pintype "passive")
		)
		(pad "7" smd roundrect
			(at 0.385 0.498 90)
			(size 0.25 0.55)
			(layers "F.Cu" "F.Mask" "F.Paste")
			(roundrect_rratio 0.25)
			(net 348 "/HDMI + SD Card/HDMI_CONN_CLK_P")
			(pintype "passive")
		)
		(pad "8" smd roundrect
			(at 0.385 0 90)
			(size 0.4 0.55)
			(layers "F.Cu" "F.Mask" "F.Paste")
			(roundrect_rratio 0.25)
			(net 1 "GND")
			(pintype "passive")
		)
		(pad "9" smd roundrect
			(at 0.385 -0.5 90)
			(size 0.25 0.55)
			(layers "F.Cu" "F.Mask" "F.Paste")
			(roundrect_rratio 0.25)
			(net 311 "/HDMI + SD Card/HDMI_CONN_D0_N")
			(pintype "passive")
		)
		(pad "10" smd roundrect
			(at 0.385 -1 90)
			(size 0.25 0.55)
			(layers "F.Cu" "F.Mask" "F.Paste")
			(roundrect_rratio 0.25)
			(net 296 "/HDMI + SD Card/HDMI_CONN_D0_P")
			(pintype "passive")
		)
	)
	(footprint "antmicro-footprints:TSSOP-8_3x3mm_P0.65mm"
		(layer "F.Cu")
		(at 99.300501 141.576 -90)
		(property "Reference" "U16"
			(at 0.424 -2.699499 270)
			(layer "F.SilkS")
			(effects
				(font
					(size 0.7 0.7)
					(thickness 0.15)
				)
				(justify left bottom)
			)
		)
		(property "Value" "PCA9517ADP"
			(at 0 2.8 270)
			(layer "F.Fab")
			(effects
				(font
					(size 0.7 0.7)
					(thickness 0.15)
				)
				(justify left bottom)
			)
		)
		(property "Datasheet" "https://www.nxp.com/docs/en/data-sheet/PCA9517A.pdf"
			(at 0 0 270)
			(layer "F.Fab")
			(hide yes)
			(effects
				(font
					(size 1.27 1.27)
					(thickness 0.15)
				)
			)
		)
		(property "Author" "Antmicro"
			(at -42.275499 240.876501 0)
			(layer "F.Fab")
			(hide yes)
			(effects
				(font
					(size 1 1)
					(thickness 0.15)
				)
			)
		)
		(property "License" "Apache-2.0"
			(at -42.275499 240.876501 0)
			(layer "F.Fab")
			(hide yes)
			(effects
				(font
					(size 1 1)
					(thickness 0.15)
				)
			)
		)
		(property "MPN" "PCA9517ADP,118"
			(at -42.275499 240.876501 0)
			(layer "F.Fab")
			(hide yes)
			(effects
				(font
					(size 1 1)
					(thickness 0.15)
				)
			)
		)
		(property "Manufacturer" "NXP"
			(at -42.275499 240.876501 0)
			(layer "F.Fab")
			(hide yes)
			(effects
				(font
					(size 1 1)
					(thickness 0.15)
				)
			)
		)
		(sheetname "/I^{2}C/")
		(sheetfile "i2c.kicad_sch")
		(attr smd)
		(fp_line
			(start -1.55 1.561)
			(end 1.552 1.561)
			(stroke
				(width 0.15)
				(type solid)
			)
			(layer "F.SilkS")
		)
		(fp_line
			(start -1.525 -1.537)
			(end 1.552 -1.539)
			(stroke
				(width 0.15)
				(type solid)
			)
			(layer "F.SilkS")
		)
		(fp_circle
			(center -1.87 -1.4)
			(end -1.82 -1.4)
			(stroke
				(width 0.15)
				(type solid)
			)
			(fill yes)
			(layer "F.SilkS")
		)
		(fp_rect
			(start -3.15 -1.789)
			(end 3.15 1.811)
			(stroke
				(width 0.05)
				(type solid)
			)
			(fill no)
			(layer "F.CrtYd")
		)
		(fp_line
			(start -1.55 1.561)
			(end 1.552 1.561)
			(stroke
				(width 0.15)
				(type solid)
			)
			(layer "F.Fab")
		)
		(fp_line
			(start -1.55 -0.937)
			(end -1.55 1.561)
			(stroke
				(width 0.15)
				(type solid)
			)
			(layer "F.Fab")
		)
		(fp_line
			(start -1.55 -0.937)
			(end -0.949 -1.539)
			(stroke
				(width 0.15)
				(type solid)
			)
			(layer "F.Fab")
		)
		(fp_line
			(start -0.949 -1.539)
			(end 1.552 -1.539)
			(stroke
				(width 0.15)
				(type solid)
			)
			(layer "F.Fab")
		)
		(fp_line
			(start 1.552 -1.539)
			(end 1.552 1.561)
			(stroke
				(width 0.15)
				(type solid)
			)
			(layer "F.Fab")
		)
		(pad "1" smd roundrect
			(at -2.148 -0.962 270)
			(size 1.47 0.4)
			(layers "F.Cu" "F.Mask" "F.Paste")
			(roundrect_rratio 0.25)
			(net 267 "VDDSPD")
			(pinfunction "V_{CC(A)}")
			(pintype "power_in")
		)
		(pad "2" smd roundrect
			(at -2.148 -0.313 270)
			(size 1.47 0.4)
			(layers "F.Cu" "F.Mask" "F.Paste")
			(roundrect_rratio 0.25)
			(net 50 "/DDR5 SODIMM/DDR.SCL")
			(pinfunction "SCLA")
			(pintype "input")
		)
		(pad "3" smd roundrect
			(at -2.148 0.338 270)
			(size 1.47 0.4)
			(layers "F.Cu" "F.Mask" "F.Paste")
			(roundrect_rratio 0.25)
			(net 54 "/DDR5 SODIMM/DDR.SDA")
			(pinfunction "SDAA")
			(pintype "bidirectional")
		)
		(pad "4" smd roundrect
			(at -2.148 0.987 270)
			(size 1.47 0.4)
			(layers "F.Cu" "F.Mask" "F.Paste")
			(roundrect_rratio 0.25)
			(net 1 "GND")
			(pinfunction "GND")
			(pintype "power_in")
		)
		(pad "5" smd roundrect
			(at 2.151 0.987 270)
			(size 1.47 0.4)
			(layers "F.Cu" "F.Mask" "F.Paste")
			(roundrect_rratio 0.25)
			(net 387 "Net-(U16-EN)")
			(pinfunction "EN")
			(pintype "input")
		)
		(pad "6" smd roundrect
			(at 2.151 0.338 270)
			(size 1.47 0.4)
			(layers "F.Cu" "F.Mask" "F.Paste")
			(roundrect_rratio 0.25)
			(net 683 "/FPGA bank 14/FPGA_DDR.SDA")
			(pinfunction "SDAB")
			(pintype "bidirectional")
		)
		(pad "7" smd roundrect
			(at 2.151 -0.313 270)
			(size 1.47 0.4)
			(layers "F.Cu" "F.Mask" "F.Paste")
			(roundrect_rratio 0.25)
			(net 682 "/FPGA bank 14/FPGA_DDR.SCL")
			(pinfunction "SCLB")
			(pintype "input")
		)
		(pad "8" smd roundrect
			(at 2.151 -0.962 270)
			(size 1.47 0.4)
			(layers "F.Cu" "F.Mask" "F.Paste")
			(roundrect_rratio 0.25)
			(net 200 "+3V3")
			(pinfunction "V_{CC(B)}")
			(pintype "power_in")
		)
	)
	(footprint "antmicro-footprints:R_0402_1005Metric"
		(layer "F.Cu")
		(at 92.7 194.815 90)
		(descr "Resistor SMD 0402")
		(tags "resistor SMD 0402")
		(property "Reference" "R64"
			(at -1.122484 -0.772697 90)
			(layer "F.SilkS")
			(hide yes)
			(effects
				(font
					(size 0.7 0.7)
					(thickness 0.15)
				)
				(justify left bottom)
			)
		)
		(property "Value" "R_330R_0402"
			(at -1.011843 1.772047 90)
			(layer "F.Fab")
			(effects
				(font
					(size 0.7 0.7)
					(thickness 0.15)
				)
				(justify left bottom)
			)
		)
		(property "Datasheet" "https://www.bourns.com/docs/product-datasheets/cr.pdf"
			(at 0 0 90)
			(layer "F.Fab")
			(hide yes)
			(effects
				(font
					(size 1.27 1.27)
					(thickness 0.15)
				)
			)
		)
		(property "Author" "Antmicro"
			(at 287.515 102.115 0)
			(layer "F.Fab")
			(hide yes)
			(effects
				(font
					(size 1 1)
					(thickness 0.15)
				)
			)
		)
		(property "License" "Apache-2.0"
			(at 287.515 102.115 0)
			(layer "F.Fab")
			(hide yes)
			(effects
				(font
					(size 1 1)
					(thickness 0.15)
				)
			)
		)
		(property "MPN" "CR0402-FX-3300GLF"
			(at 287.515 102.115 0)
			(layer "F.Fab")
			(hide yes)
			(effects
				(font
					(size 1 1)
					(thickness 0.15)
				)
			)
		)
		(property "Manufacturer" "Bourns"
			(at 287.515 102.115 0)
			(layer "F.Fab")
			(hide yes)
			(effects
				(font
					(size 1 1)
					(thickness 0.15)
				)
			)
		)
		(property "Tolerance" "1%"
			(at 287.515 102.115 0)
			(layer "F.Fab")
			(hide yes)
			(effects
				(font
					(size 1 1)
					(thickness 0.15)
				)
			)
		)
		(property "Val" "330R"
			(at 287.515 102.115 0)
			(layer "F.Fab")
			(hide yes)
			(effects
				(font
					(size 1 1)
					(thickness 0.15)
				)
			)
		)
		(sheetname "/Debug FTDI/")
		(sheetfile "debug-ftdi.kicad_sch")
		(attr smd)
		(fp_rect
			(start -0.93 -0.47)
			(end 0.93 0.47)
			(stroke
				(width 0.05)
				(type solid)
			)
			(fill no)
			(layer "F.CrtYd")
		)
		(fp_rect
			(start -0.5 -0.25)
			(end 0.5 0.25)
			(stroke
				(width 0.15)
				(type solid)
			)
			(fill no)
			(layer "F.Fab")
		)
		(pad "1" smd roundrect
			(at -0.485 0 90)
			(size 0.59 0.64)
			(layers "F.Cu" "F.Mask" "F.Paste")
			(roundrect_rratio 0.25)
			(net 315 "Net-(D10-Pad1)")
			(pintype "passive")
		)
		(pad "2" smd roundrect
			(at 0.485 0 90)
			(size 0.59 0.64)
			(layers "F.Cu" "F.Mask" "F.Paste")
			(roundrect_rratio 0.25)
			(net 656 "/Debug FTDI/LED_TX0")
			(pintype "passive")
		)
	)
	(footprint "antmicro-footprints:C_0402_1005Metric"
		(layer "F.Cu")
		(at 179.05 189.731 90)
		(descr "Capacitor SMD 0402")
		(tags "capacitor SMD 0402")
		(property "Reference" "C239"
			(at -3.9 0.5 90)
			(layer "F.SilkS")
			(effects
				(font
					(size 0.7 0.7)
					(thickness 0.15)
				)
				(justify left bottom)
			)
		)
		(property "Value" "C_100n_0402"
			(at -1.022927 2.155213 90)
			(layer "F.Fab")
			(effects
				(font
					(size 0.7 0.7)
					(thickness 0.15)
				)
				(justify left bottom)
			)
		)
		(property "Datasheet" "https://www.murata.com/products/productdetail?partno=GRM155R61H104KE14%23"
			(at 0 0 90)
			(layer "F.Fab")
			(hide yes)
			(effects
				(font
					(size 1.27 1.27)
					(thickness 0.15)
				)
			)
		)
		(property "Manufacturer" "Murata"
			(at 0 0 90)
			(unlocked yes)
			(layer "F.Fab")
			(hide yes)
			(effects
				(font
					(size 1 1)
					(thickness 0.15)
				)
			)
		)
		(property "MPN" "GRM155R61H104KE14D"
			(at 0 0 90)
			(unlocked yes)
			(layer "F.Fab")
			(hide yes)
			(effects
				(font
					(size 1 1)
					(thickness 0.15)
				)
			)
		)
		(property "Val" "100n"
			(at 0 0 90)
			(unlocked yes)
			(layer "F.Fab")
			(hide yes)
			(effects
				(font
					(size 1 1)
					(thickness 0.15)
				)
			)
		)
		(property "License" "Apache-2.0"
			(at 0 0 90)
			(unlocked yes)
			(layer "F.Fab")
			(hide yes)
			(effects
				(font
					(size 1 1)
					(thickness 0.15)
				)
			)
		)
		(property "Author" "Antmicro"
			(at 0 0 90)
			(unlocked yes)
			(layer "F.Fab")
			(hide yes)
			(effects
				(font
					(size 1 1)
					(thickness 0.15)
				)
			)
		)
		(property "Voltage" "50V"
			(at 0 0 90)
			(unlocked yes)
			(layer "F.Fab")
			(hide yes)
			(effects
				(font
					(size 1 1)
					(thickness 0.15)
				)
			)
		)
		(property "Dielectric" "X5R"
			(at 0 0 90)
			(unlocked yes)
			(layer "F.Fab")
			(hide yes)
			(effects
				(font
					(size 1 1)
					(thickness 0.15)
				)
			)
		)
		(sheetname "/I^{2}C/")
		(sheetfile "i2c.kicad_sch")
		(attr smd)
		(fp_poly
			(pts
				(xy -0.925 -0.47) (xy 0.925 -0.47) (xy 0.925 0.47) (xy -0.925 0.47)
			)
			(stroke
				(width 0.05)
				(type default)
			)
			(fill no)
			(layer "F.CrtYd")
		)
		(fp_line
			(start 0.504 -0.25)
			(end 0.504 0.248)
			(stroke
				(width 0.15)
				(type solid)
			)
			(layer "F.Fab")
		)
		(fp_line
			(start -0.494 -0.25)
			(end 0.504 -0.25)
			(stroke
				(width 0.15)
				(type solid)
			)
			(layer "F.Fab")
		)
		(fp_line
			(start 0.504 0.248)
			(end -0.494 0.248)
			(stroke
				(width 0.15)
				(type solid)
			)
			(layer "F.Fab")
		)
		(fp_line
			(start -0.494 0.248)
			(end -0.494 -0.25)
			(stroke
				(width 0.15)
				(type solid)
			)
			(layer "F.Fab")
		)
		(fp_text user "License: Apache-2.0"
			(at -0.939 5.799 90)
			(layer "F.Fab")
			(effects
				(font
					(size 0.7 0.7)
					(thickness 0.15)
				)
				(justify left bottom)
			)
		)
		(fp_text user "${REFERENCE}"
			(at -0.939 4.599 90)
			(layer "F.Fab")
			(effects
				(font
					(size 0.7 0.7)
					(thickness 0.15)
				)
				(justify left bottom)
			)
		)
		(fp_text user "Author: Antmicro"
			(at -0.939 3.399 90)
			(layer "F.Fab")
			(effects
				(font
					(size 0.7 0.7)
					(thickness 0.15)
				)
				(justify left bottom)
			)
		)
		(pad "1" smd roundrect
			(at -0.48 0 90)
			(size 0.59 0.64)
			(layers "F.Cu" "F.Mask" "F.Paste")
			(roundrect_rratio 0.25)
			(net 1 "GND")
			(pintype "passive")
		)
		(pad "2" smd roundrect
			(at 0.48 0 90)
			(size 0.59 0.64)
			(layers "F.Cu" "F.Mask" "F.Paste")
			(roundrect_rratio 0.25)
			(net 759 "Net-(D17-C)")
			(pintype "passive")
		)
	)
	(footprint "antmicro-footprints:C_0402_1005Metric"
		(layer "F.Cu")
		(at 184.15 196.65 -90)
		(descr "Capacitor SMD 0402")
		(tags "capacitor SMD 0402")
		(property "Reference" "C196"
			(at 0 -0.699 270)
			(layer "F.SilkS")
			(hide yes)
			(effects
				(font
					(size 0.7 0.7)
					(thickness 0.15)
				)
				(justify left bottom)
			)
		)
		(property "Value" "C_100n_0402"
			(at -1.022927 2.155213 270)
			(layer "F.Fab")
			(effects
				(font
					(size 0.7 0.7)
					(thickness 0.15)
				)
				(justify left bottom)
			)
		)
		(property "Datasheet" "https://www.murata.com/products/productdetail?partno=GRM155R61H104KE14%23"
			(at 0 0 270)
			(layer "F.Fab")
			(hide yes)
			(effects
				(font
					(size 1.27 1.27)
					(thickness 0.15)
				)
			)
		)
		(property "Author" "Antmicro"
			(at -12.5 380.8 0)
			(layer "F.Fab")
			(hide yes)
			(effects
				(font
					(size 1 1)
					(thickness 0.15)
				)
			)
		)
		(property "Dielectric" "X5R"
			(at -12.5 380.8 0)
			(layer "F.Fab")
			(hide yes)
			(effects
				(font
					(size 1 1)
					(thickness 0.15)
				)
			)
		)
		(property "License" "Apache-2.0"
			(at -12.5 380.8 0)
			(layer "F.Fab")
			(hide yes)
			(effects
				(font
					(size 1 1)
					(thickness 0.15)
				)
			)
		)
		(property "MPN" "GRM155R61H104KE14D"
			(at -12.5 380.8 0)
			(layer "F.Fab")
			(hide yes)
			(effects
				(font
					(size 1 1)
					(thickness 0.15)
				)
			)
		)
		(property "Manufacturer" "Murata"
			(at -12.5 380.8 0)
			(layer "F.Fab")
			(hide yes)
			(effects
				(font
					(size 1 1)
					(thickness 0.15)
				)
			)
		)
		(property "Val" "100n"
			(at -12.5 380.8 0)
			(layer "F.Fab")
			(hide yes)
			(effects
				(font
					(size 1 1)
					(thickness 0.15)
				)
			)
		)
		(property "Voltage" "50V"
			(at -12.5 380.8 0)
			(layer "F.Fab")
			(hide yes)
			(effects
				(font
					(size 1 1)
					(thickness 0.15)
				)
			)
		)
		(sheetname "/I^{2}C/")
		(sheetfile "i2c.kicad_sch")
		(attr smd)
		(fp_rect
			(start -0.9659 -0.481258)
			(end 0.9649 0.458742)
			(stroke
				(width 0.05)
				(type solid)
			)
			(fill no)
			(layer "F.CrtYd")
		)
		(fp_line
			(start -0.499 0.248)
			(end -0.499 -0.25)
			(stroke
				(width 0.15)
				(type solid)
			)
			(layer "F.Fab")
		)
		(fp_line
			(start 0.499 0.248)
			(end -0.499 0.248)
			(stroke
				(width 0.15)
				(type solid)
			)
			(layer "F.Fab")
		)
		(fp_line
			(start -0.499 -0.25)
			(end 0.499 -0.25)
			(stroke
				(width 0.15)
				(type solid)
			)
			(layer "F.Fab")
		)
		(fp_line
			(start 0.499 -0.25)
			(end 0.499 0.248)
			(stroke
				(width 0.15)
				(type solid)
			)
			(layer "F.Fab")
		)
		(pad "1" smd roundrect
			(at -0.484 0 270)
			(size 0.59 0.64)
			(layers "F.Cu" "F.Mask" "F.Paste")
			(roundrect_rratio 0.25)
			(net 1 "GND")
			(pintype "passive")
		)
		(pad "2" smd roundrect
			(at 0.484 0 270)
			(size 0.59 0.64)
			(layers "F.Cu" "F.Mask" "F.Paste")
			(roundrect_rratio 0.25)
			(net 41 "+3V3_AON")
			(pintype "passive")
		)
	)
	(footprint "antmicro-footprints:C_0402_1005Metric"
		(layer "F.Cu")
		(at 184.15 192.9 -90)
		(descr "Capacitor SMD 0402")
		(tags "capacitor SMD 0402")
		(property "Reference" "C197"
			(at 0 -0.699 270)
			(layer "F.SilkS")
			(hide yes)
			(effects
				(font
					(size 0.7 0.7)
					(thickness 0.15)
				)
				(justify left bottom)
			)
		)
		(property "Value" "C_100n_0402"
			(at -1.022927 2.155213 270)
			(layer "F.Fab")
			(effects
				(font
					(size 0.7 0.7)
					(thickness 0.15)
				)
				(justify left bottom)
			)
		)
		(property "Datasheet" "https://www.murata.com/products/productdetail?partno=GRM155R61H104KE14%23"
			(at 0 0 270)
			(layer "F.Fab")
			(hide yes)
			(effects
				(font
					(size 1.27 1.27)
					(thickness 0.15)
				)
			)
		)
		(property "Author" "Antmicro"
			(at -8.75 377.05 0)
			(layer "F.Fab")
			(hide yes)
			(effects
				(font
					(size 1 1)
					(thickness 0.15)
				)
			)
		)
		(property "Dielectric" "X5R"
			(at -8.75 377.05 0)
			(layer "F.Fab")
			(hide yes)
			(effects
				(font
					(size 1 1)
					(thickness 0.15)
				)
			)
		)
		(property "License" "Apache-2.0"
			(at -8.75 377.05 0)
			(layer "F.Fab")
			(hide yes)
			(effects
				(font
					(size 1 1)
					(thickness 0.15)
				)
			)
		)
		(property "MPN" "GRM155R61H104KE14D"
			(at -8.75 377.05 0)
			(layer "F.Fab")
			(hide yes)
			(effects
				(font
					(size 1 1)
					(thickness 0.15)
				)
			)
		)
		(property "Manufacturer" "Murata"
			(at -8.75 377.05 0)
			(layer "F.Fab")
			(hide yes)
			(effects
				(font
					(size 1 1)
					(thickness 0.15)
				)
			)
		)
		(property "Val" "100n"
			(at -8.75 377.05 0)
			(layer "F.Fab")
			(hide yes)
			(effects
				(font
					(size 1 1)
					(thickness 0.15)
				)
			)
		)
		(property "Voltage" "50V"
			(at -8.75 377.05 0)
			(layer "F.Fab")
			(hide yes)
			(effects
				(font
					(size 1 1)
					(thickness 0.15)
				)
			)
		)
		(sheetname "/I^{2}C/")
		(sheetfile "i2c.kicad_sch")
		(attr smd)
		(fp_rect
			(start -0.9659 -0.481258)
			(end 0.9649 0.458742)
			(stroke
				(width 0.05)
				(type solid)
			)
			(fill no)
			(layer "F.CrtYd")
		)
		(fp_line
			(start -0.499 0.248)
			(end -0.499 -0.25)
			(stroke
				(width 0.15)
				(type solid)
			)
			(layer "F.Fab")
		)
		(fp_line
			(start 0.499 0.248)
			(end -0.499 0.248)
			(stroke
				(width 0.15)
				(type solid)
			)
			(layer "F.Fab")
		)
		(fp_line
			(start -0.499 -0.25)
			(end 0.499 -0.25)
			(stroke
				(width 0.15)
				(type solid)
			)
			(layer "F.Fab")
		)
		(fp_line
			(start 0.499 -0.25)
			(end 0.499 0.248)
			(stroke
				(width 0.15)
				(type solid)
			)
			(layer "F.Fab")
		)
		(pad "1" smd roundrect
			(at -0.484 0 270)
			(size 0.59 0.64)
			(layers "F.Cu" "F.Mask" "F.Paste")
			(roundrect_rratio 0.25)
			(net 1 "GND")
			(pintype "passive")
		)
		(pad "2" smd roundrect
			(at 0.484 0 270)
			(size 0.59 0.64)
			(layers "F.Cu" "F.Mask" "F.Paste")
			(roundrect_rratio 0.25)
			(net 41 "+3V3_AON")
			(pintype "passive")
		)
	)
	(footprint "antmicro-footprints:NetTie-2_SMD_Pad0.127mm"
		(layer "F.Cu")
		(at 198.7 173.974998 180)
		(descr "Net tie, 2 pin, 0.127mm  SMD pads")
		(tags "net tie")
		(property "Reference" "NT16"
			(at -0.128 -1.345 180)
			(layer "F.SilkS")
			(hide yes)
			(effects
				(font
					(size 0.7 0.7)
					(thickness 0.15)
				)
				(justify left bottom)
			)
		)
		(property "Value" "Net-Tie_P0.127mm"
			(at 0 1.199 180)
			(layer "F.Fab")
			(effects
				(font
					(size 0.7 0.7)
					(thickness 0.15)
				)
				(justify left bottom)
			)
		)
		(property "Author" "Antmicro"
			(at 397.4 347.949996 0)
			(layer "F.Fab")
			(hide yes)
			(effects
				(font
					(size 1 1)
					(thickness 0.15)
				)
			)
		)
		(property "License" "Apache-2.0"
			(at 397.4 347.949996 0)
			(layer "F.Fab")
			(hide yes)
			(effects
				(font
					(size 1 1)
					(thickness 0.15)
				)
			)
		)
		(property "MPN" ""
			(at 397.4 347.949996 0)
			(layer "F.Fab")
			(hide yes)
			(effects
				(font
					(size 1 1)
					(thickness 0.15)
				)
			)
		)
		(property "Manufacturer" ""
			(at 397.4 347.949996 0)
			(layer "F.Fab")
			(hide yes)
			(effects
				(font
					(size 1 1)
					(thickness 0.15)
				)
			)
		)
		(property ki_fp_filters "Net*Tie*")
		(sheetname "/Supply/")
		(sheetfile "supply.kicad_sch")
		(attr smd exclude_from_pos_files exclude_from_bom)
		(net_tie_pad_groups "1, 2")
		(fp_poly
			(pts
				(xy -0.0635 -0.0635) (xy 0.0625 -0.0635) (xy 0.0625 0.0635) (xy -0.0635 0.0635)
			)
			(stroke
				(width 0)
				(type solid)
			)
			(fill yes)
			(layer "F.Cu")
		)
		(pad "1" smd roundrect
			(at -0.127 0)
			(size 0.127 0.127)
			(layers "F.Cu")
			(roundrect_rratio 0.5)
			(chamfer_ratio 0)
			(chamfer top_left bottom_left)
			(net 144 "/Supply/1V2_SEN_-")
			(pinfunction "1")
			(pintype "passive")
		)
		(pad "2" smd roundrect
			(at 0.126 0 180)
			(size 0.127 0.127)
			(layers "F.Cu")
			(roundrect_rratio 0.5)
			(chamfer_ratio 0)
			(chamfer top_left bottom_left)
			(net 199 "+1V2")
			(pinfunction "2")
			(pintype "passive")
		)
	)
	(footprint "antmicro-footprints:NetTie-2_SMD_Pad0.127mm"
		(layer "F.Cu")
		(at 187.875 189.101 180)
		(descr "Net tie, 2 pin, 0.127mm  SMD pads")
		(tags "net tie")
		(property "Reference" "NT9"
			(at -0.128 -1.345 180)
			(layer "F.SilkS")
			(hide yes)
			(effects
				(font
					(size 0.7 0.7)
					(thickness 0.15)
				)
				(justify left bottom)
			)
		)
		(property "Value" "Net-Tie_P0.127mm"
			(at 0 1.199 180)
			(layer "F.Fab")
			(effects
				(font
					(size 0.7 0.7)
					(thickness 0.15)
				)
				(justify left bottom)
			)
		)
		(property "Author" "Antmicro"
			(at 375.75 378.202 0)
			(layer "F.Fab")
			(hide yes)
			(effects
				(font
					(size 1 1)
					(thickness 0.15)
				)
			)
		)
		(property "License" "Apache-2.0"
			(at 375.75 378.202 0)
			(layer "F.Fab")
			(hide yes)
			(effects
				(font
					(size 1 1)
					(thickness 0.15)
				)
			)
		)
		(property "MPN" ""
			(at 375.75 378.202 0)
			(layer "F.Fab")
			(hide yes)
			(effects
				(font
					(size 1 1)
					(thickness 0.15)
				)
			)
		)
		(property "Manufacturer" ""
			(at 375.75 378.202 0)
			(layer "F.Fab")
			(hide yes)
			(effects
				(font
					(size 1 1)
					(thickness 0.15)
				)
			)
		)
		(property ki_fp_filters "Net*Tie*")
		(sheetname "/Supply/")
		(sheetfile "supply.kicad_sch")
		(attr smd exclude_from_pos_files exclude_from_bom)
		(net_tie_pad_groups "1, 2")
		(fp_poly
			(pts
				(xy -0.0635 -0.0635) (xy 0.0625 -0.0635) (xy 0.0625 0.0635) (xy -0.0635 0.0635)
			)
			(stroke
				(width 0)
				(type solid)
			)
			(fill yes)
			(layer "F.Cu")
		)
		(pad "1" smd roundrect
			(at -0.127 0)
			(size 0.127 0.127)
			(layers "F.Cu")
			(roundrect_rratio 0.5)
			(chamfer_ratio 0)
			(chamfer top_left bottom_left)
			(net 143 "/Supply/MGTAVCC_SEN_-")
			(pinfunction "1")
			(pintype "passive")
		)
		(pad "2" smd roundrect
			(at 0.126 0 180)
			(size 0.127 0.127)
			(layers "F.Cu")
			(roundrect_rratio 0.5)
			(chamfer_ratio 0)
			(chamfer top_left bottom_left)
			(net 187 "+1V0_MGTAVCC")
			(pinfunction "2")
			(pintype "passive")
		)
	)
	(footprint "antmicro-footprints:R_0402_1005Metric"
		(layer "F.Cu")
		(at 89.050501 119.926 -90)
		(descr "Resistor SMD 0402")
		(tags "resistor SMD 0402")
		(property "Reference" "R41"
			(at -1.122484 -0.772697 270)
			(layer "F.SilkS")
			(hide yes)
			(effects
				(font
					(size 0.7 0.7)
					(thickness 0.15)
				)
				(justify left bottom)
			)
		)
		(property "Value" "R_330R_0402"
			(at -1.011843 1.772047 270)
			(layer "F.Fab")
			(effects
				(font
					(size 0.7 0.7)
					(thickness 0.15)
				)
				(justify left bottom)
			)
		)
		(property "Datasheet" "https://www.bourns.com/docs/product-datasheets/cr.pdf"
			(at 0 0 270)
			(layer "F.Fab")
			(hide yes)
			(effects
				(font
					(size 1.27 1.27)
					(thickness 0.15)
				)
			)
		)
		(property "Author" "Antmicro"
			(at -30.875499 208.976501 0)
			(layer "F.Fab")
			(hide yes)
			(effects
				(font
					(size 1 1)
					(thickness 0.15)
				)
			)
		)
		(property "License" "Apache-2.0"
			(at -30.875499 208.976501 0)
			(layer "F.Fab")
			(hide yes)
			(effects
				(font
					(size 1 1)
					(thickness 0.15)
				)
			)
		)
		(property "MPN" "CR0402-FX-3300GLF"
			(at -30.875499 208.976501 0)
			(layer "F.Fab")
			(hide yes)
			(effects
				(font
					(size 1 1)
					(thickness 0.15)
				)
			)
		)
		(property "Manufacturer" "Bourns"
			(at -30.875499 208.976501 0)
			(layer "F.Fab")
			(hide yes)
			(effects
				(font
					(size 1 1)
					(thickness 0.15)
				)
			)
		)
		(property "Tolerance" "1%"
			(at -30.875499 208.976501 0)
			(layer "F.Fab")
			(hide yes)
			(effects
				(font
					(size 1 1)
					(thickness 0.15)
				)
			)
		)
		(property "Val" "330R"
			(at -30.875499 208.976501 0)
			(layer "F.Fab")
			(hide yes)
			(effects
				(font
					(size 1 1)
					(thickness 0.15)
				)
			)
		)
		(sheetname "/FPGA bank 14/")
		(sheetfile "fpga-bank-14.kicad_sch")
		(attr smd)
		(fp_rect
			(start -0.93 -0.47)
			(end 0.93 0.47)
			(stroke
				(width 0.05)
				(type solid)
			)
			(fill no)
			(layer "F.CrtYd")
		)
		(fp_rect
			(start -0.5 -0.25)
			(end 0.5 0.25)
			(stroke
				(width 0.15)
				(type solid)
			)
			(fill no)
			(layer "F.Fab")
		)
		(pad "1" smd roundrect
			(at -0.485 0 270)
			(size 0.59 0.64)
			(layers "F.Cu" "F.Mask" "F.Paste")
			(roundrect_rratio 0.25)
			(net 308 "Net-(D5-Pad2)")
			(pintype "passive")
		)
		(pad "2" smd roundrect
			(at 0.485 0 270)
			(size 0.59 0.64)
			(layers "F.Cu" "F.Mask" "F.Paste")
			(roundrect_rratio 0.25)
			(net 354 "Net-(Q5-D)")
			(pintype "passive")
		)
	)
	(footprint "antmicro-footprints:SOT-23-5"
		(layer "F.Cu")
		(at 196.663499 135.49)
		(property "Reference" "U21"
			(at -2.363499 2.81 90)
			(layer "F.SilkS")
			(effects
				(font
					(size 0.7 0.7)
					(thickness 0.15)
				)
				(justify left bottom)
			)
		)
		(property "Value" "NCP718BSN330T1G"
			(at 0.002 2.799 0)
			(layer "F.Fab")
			(effects
				(font
					(size 0.7 0.7)
					(thickness 0.15)
				)
				(justify left bottom)
			)
		)
		(property "Datasheet" "https://www.mouser.com/datasheet/2/308/NCP718_D-1224359.pdf"
			(at 0 0 0)
			(layer "F.Fab")
			(hide yes)
			(effects
				(font
					(size 1.27 1.27)
					(thickness 0.15)
				)
			)
		)
		(property "Author" "Antmicro"
			(at 0 0 0)
			(layer "F.Fab")
			(hide yes)
			(effects
				(font
					(size 1 1)
					(thickness 0.15)
				)
			)
		)
		(property "License" "Apache-2.0"
			(at 0 0 0)
			(layer "F.Fab")
			(hide yes)
			(effects
				(font
					(size 1 1)
					(thickness 0.15)
				)
			)
		)
		(property "MPN" "NCP718BSN330T1G"
			(at 0 0 0)
			(layer "F.Fab")
			(hide yes)
			(effects
				(font
					(size 1 1)
					(thickness 0.15)
				)
			)
		)
		(property "Manufacturer" "ON Semiconductor"
			(at 0 0 0)
			(layer "F.Fab")
			(hide yes)
			(effects
				(font
					(size 1 1)
					(thickness 0.15)
				)
			)
		)
		(sheetname "/Supply/")
		(sheetfile "supply.kicad_sch")
		(attr smd)
		(fp_line
			(start -0.85 1.6)
			(end -0.85 1.301)
			(stroke
				(width 0.15)
				(type solid)
			)
			(layer "F.SilkS")
		)
		(fp_line
			(start -0.8 -1.6)
			(end -0.8 -1.3)
			(stroke
				(width 0.15)
				(type solid)
			)
			(layer "F.SilkS")
		)
		(fp_line
			(start -0.8 -1.6)
			(end -0.5 -1.6)
			(stroke
				(width 0.15)
				(type solid)
			)
			(layer "F.SilkS")
		)
		(fp_line
			(start -0.55 1.6)
			(end -0.85 1.6)
			(stroke
				(width 0.15)
				(type solid)
			)
			(layer "F.SilkS")
		)
		(fp_line
			(start 0.8 -1.6)
			(end 0.5 -1.6)
			(stroke
				(width 0.15)
				(type solid)
			)
			(layer "F.SilkS")
		)
		(fp_line
			(start 0.8 -1.3)
			(end 0.8 -1.6)
			(stroke
				(width 0.15)
				(type solid)
			)
			(layer "F.SilkS")
		)
		(fp_line
			(start 0.8 0.55)
			(end 0.8 -0.55)
			(stroke
				(width 0.15)
				(type solid)
			)
			(layer "F.SilkS")
		)
		(fp_line
			(start 0.8 1.3)
			(end 0.8 1.599)
			(stroke
				(width 0.15)
				(type solid)
			)
			(layer "F.SilkS")
		)
		(fp_line
			(start 0.8 1.599)
			(end 0.549 1.599)
			(stroke
				(width 0.15)
				(type solid)
			)
			(layer "F.SilkS")
		)
		(fp_circle
			(center -1.25 -1.5)
			(end -1.2 -1.5)
			(stroke
				(width 0.15)
				(type solid)
			)
			(fill yes)
			(layer "F.SilkS")
		)
		(fp_rect
			(start 1.9 -1.76)
			(end -1.9 1.75)
			(stroke
				(width 0.05)
				(type solid)
			)
			(fill no)
			(layer "F.CrtYd")
		)
		(fp_line
			(start -0.398 -1.526)
			(end -0.874 -1.05)
			(stroke
				(width 0.15)
				(type solid)
			)
			(layer "F.Fab")
		)
		(fp_rect
			(start 0.874 1.523)
			(end -0.873 -1.525)
			(stroke
				(width 0.15)
				(type solid)
			)
			(fill no)
			(layer "F.Fab")
		)
		(pad "1" smd rect
			(at -1.351 -0.951 270)
			(size 0.55 1)
			(layers "F.Cu" "F.Mask" "F.Paste")
			(net 38 "VDC")
			(pinfunction "VIN")
			(pintype "passive")
		)
		(pad "2" smd rect
			(at -1.351 0 270)
			(size 0.55 1)
			(layers "F.Cu" "F.Mask" "F.Paste")
			(net 1 "GND")
			(pinfunction "GND")
			(pintype "passive")
		)
		(pad "3" smd rect
			(at -1.351 0.949 270)
			(size 0.55 1)
			(layers "F.Cu" "F.Mask" "F.Paste")
			(net 38 "VDC")
			(pinfunction "EN")
			(pintype "passive")
		)
		(pad "4" smd rect
			(at 1.35 0.949 270)
			(size 0.55 1)
			(layers "F.Cu" "F.Mask" "F.Paste")
			(net 730 "unconnected-(U21-NC-Pad4)")
			(pinfunction "NC")
			(pintype "no_connect")
		)
		(pad "5" smd rect
			(at 1.35 -0.951 270)
			(size 0.55 1)
			(layers "F.Cu" "F.Mask" "F.Paste")
			(net 41 "+3V3_AON")
			(pinfunction "VOUT")
			(pintype "passive")
		)
	)
	(footprint "antmicro-footprints:C_0402_1005Metric"
		(layer "F.Cu")
		(at 107.251 180.584 -90)
		(descr "Capacitor SMD 0402")
		(tags "capacitor SMD 0402")
		(property "Reference" "C130"
			(at 0 -0.699 270)
			(layer "F.SilkS")
			(hide yes)
			(effects
				(font
					(size 0.7 0.7)
					(thickness 0.15)
				)
				(justify left bottom)
			)
		)
		(property "Value" "C_100n_0402"
			(at -1.022927 2.155213 270)
			(layer "F.Fab")
			(effects
				(font
					(size 0.7 0.7)
					(thickness 0.15)
				)
				(justify left bottom)
			)
		)
		(property "Datasheet" "https://www.murata.com/products/productdetail?partno=GRM155R61H104KE14%23"
			(at 0 0 270)
			(layer "F.Fab")
			(hide yes)
			(effects
				(font
					(size 1.27 1.27)
					(thickness 0.15)
				)
			)
		)
		(property "Author" "Antmicro"
			(at -73.333 287.835 0)
			(layer "F.Fab")
			(hide yes)
			(effects
				(font
					(size 1 1)
					(thickness 0.15)
				)
			)
		)
		(property "Dielectric" "X5R"
			(at -73.333 287.835 0)
			(layer "F.Fab")
			(hide yes)
			(effects
				(font
					(size 1 1)
					(thickness 0.15)
				)
			)
		)
		(property "License" "Apache-2.0"
			(at -73.333 287.835 0)
			(layer "F.Fab")
			(hide yes)
			(effects
				(font
					(size 1 1)
					(thickness 0.15)
				)
			)
		)
		(property "MPN" "GRM155R61H104KE14D"
			(at -73.333 287.835 0)
			(layer "F.Fab")
			(hide yes)
			(effects
				(font
					(size 1 1)
					(thickness 0.15)
				)
			)
		)
		(property "Manufacturer" "Murata"
			(at -73.333 287.835 0)
			(layer "F.Fab")
			(hide yes)
			(effects
				(font
					(size 1 1)
					(thickness 0.15)
				)
			)
		)
		(property "Val" "100n"
			(at -73.333 287.835 0)
			(layer "F.Fab")
			(hide yes)
			(effects
				(font
					(size 1 1)
					(thickness 0.15)
				)
			)
		)
		(property "Voltage" "50V"
			(at -73.333 287.835 0)
			(layer "F.Fab")
			(hide yes)
			(effects
				(font
					(size 1 1)
					(thickness 0.15)
				)
			)
		)
		(sheetname "/Debug FTDI/")
		(sheetfile "debug-ftdi.kicad_sch")
		(attr smd)
		(fp_rect
			(start -0.9659 -0.481258)
			(end 0.9649 0.458742)
			(stroke
				(width 0.05)
				(type solid)
			)
			(fill no)
			(layer "F.CrtYd")
		)
		(fp_line
			(start -0.499 0.248)
			(end -0.499 -0.25)
			(stroke
				(width 0.15)
				(type solid)
			)
			(layer "F.Fab")
		)
		(fp_line
			(start 0.499 0.248)
			(end -0.499 0.248)
			(stroke
				(width 0.15)
				(type solid)
			)
			(layer "F.Fab")
		)
		(fp_line
			(start -0.499 -0.25)
			(end 0.499 -0.25)
			(stroke
				(width 0.15)
				(type solid)
			)
			(layer "F.Fab")
		)
		(fp_line
			(start 0.499 -0.25)
			(end 0.499 0.248)
			(stroke
				(width 0.15)
				(type solid)
			)
			(layer "F.Fab")
		)
		(pad "1" smd roundrect
			(at -0.484 0 270)
			(size 0.59 0.64)
			(layers "F.Cu" "F.Mask" "F.Paste")
			(roundrect_rratio 0.25)
			(net 1 "GND")
			(pintype "passive")
		)
		(pad "2" smd roundrect
			(at 0.484 0 270)
			(size 0.59 0.64)
			(layers "F.Cu" "F.Mask" "F.Paste")
			(roundrect_rratio 0.25)
			(net 6 "/Debug FTDI/FTDI_3V3")
			(pintype "passive")
		)
	)
	(footprint "antmicro-footprints:USON-10_2.5x1mm_P0.5mm"
		(layer "F.Cu")
		(at 165.1 174.2 180)
		(descr "USON-10 2.5x1mm_ Pitch 0.5mm")
		(tags "USON-10 2.5x1mm Pitch 0.5mm")
		(property "Reference" "U2"
			(at 0.018 -1.7 180)
			(layer "F.SilkS")
			(hide yes)
			(effects
				(font
					(size 0.7 0.7)
					(thickness 0.15)
				)
				(justify left bottom)
			)
		)
		(property "Value" "TPD4E05U06QDQARQ1"
			(at 0.018 2.499 180)
			(layer "F.Fab")
			(effects
				(font
					(size 0.7 0.7)
					(thickness 0.15)
				)
				(justify left bottom)
			)
		)
		(property "Datasheet" "https://www.ti.com/lit/ds/symlink/tpd4e05u06-q1.pdf?HQS=dis-mous-null-mousermode-dsf-pf-null-wwe&ts=1663591265741&ref_url=https%253A%252F%252Fwww.mouser.com%252F"
			(at 0 0 180)
			(layer "F.Fab")
			(hide yes)
			(effects
				(font
					(size 1.27 1.27)
					(thickness 0.15)
				)
			)
		)
		(property "Author" "Antmicro"
			(at 330.2 348.4 0)
			(layer "F.Fab")
			(hide yes)
			(effects
				(font
					(size 1 1)
					(thickness 0.15)
				)
			)
		)
		(property "License" "Apache-2.0"
			(at 330.2 348.4 0)
			(layer "F.Fab")
			(hide yes)
			(effects
				(font
					(size 1 1)
					(thickness 0.15)
				)
			)
		)
		(property "MPN" "TPD4E05U06QDQARQ1"
			(at 330.2 348.4 0)
			(layer "F.Fab")
			(hide yes)
			(effects
				(font
					(size 1 1)
					(thickness 0.15)
				)
			)
		)
		(property "Manufacturer" "Texas Instruments"
			(at 330.2 348.4 0)
			(layer "F.Fab")
			(hide yes)
			(effects
				(font
					(size 1 1)
					(thickness 0.15)
				)
			)
		)
		(sheetname "/FPGA Config/")
		(sheetfile "fpga-config.kicad_sch")
		(attr exclude_from_pos_files exclude_from_bom dnp)
		(fp_line
			(start 0.498 1.398)
			(end -0.5 1.398)
			(stroke
				(width 0.15)
				(type solid)
			)
			(layer "F.SilkS")
		)
		(fp_line
			(start 0.498 -1.401)
			(end -0.5 -1.401)
			(stroke
				(width 0.15)
				(type solid)
			)
			(layer "F.SilkS")
		)
		(fp_circle
			(center -0.68 -1.27)
			(end -0.63 -1.27)
			(stroke
				(width 0.15)
				(type solid)
			)
			(fill yes)
			(layer "F.SilkS")
		)
		(fp_rect
			(start -0.8 -1.5)
			(end 0.8 1.499)
			(stroke
				(width 0.05)
				(type solid)
			)
			(fill no)
			(layer "F.CrtYd")
		)
		(fp_line
			(start 0.498 -1.25)
			(end 0.498 1.249)
			(stroke
				(width 0.15)
				(type solid)
			)
			(layer "F.Fab")
		)
		(fp_line
			(start 0.498 -1.25)
			(end -0.25 -1.25)
			(stroke
				(width 0.15)
				(type solid)
			)
			(layer "F.Fab")
		)
		(fp_line
			(start -0.25 -1.25)
			(end -0.5 -1)
			(stroke
				(width 0.15)
				(type solid)
			)
			(layer "F.Fab")
		)
		(fp_line
			(start -0.5 1.249)
			(end 0.498 1.249)
			(stroke
				(width 0.15)
				(type solid)
			)
			(layer "F.Fab")
		)
		(fp_line
			(start -0.5 -1)
			(end -0.5 1.249)
			(stroke
				(width 0.15)
				(type solid)
			)
			(layer "F.Fab")
		)
		(pad "1" smd roundrect
			(at -0.387 -1 90)
			(size 0.25 0.55)
			(layers "F.Cu" "F.Mask" "F.Paste")
			(roundrect_rratio 0.25)
			(net 45 "/Debug FTDI/JTAG.TMS")
			(pintype "passive")
		)
		(pad "2" smd roundrect
			(at -0.387 -0.5 90)
			(size 0.25 0.55)
			(layers "F.Cu" "F.Mask" "F.Paste")
			(roundrect_rratio 0.25)
			(net 46 "/Debug FTDI/JTAG.TCK")
			(pintype "passive")
		)
		(pad "3" smd roundrect
			(at -0.387 0 90)
			(size 0.4 0.55)
			(layers "F.Cu" "F.Mask" "F.Paste")
			(roundrect_rratio 0.25)
			(net 1 "GND")
			(pintype "power_in")
		)
		(pad "4" smd roundrect
			(at -0.387 0.498 90)
			(size 0.25 0.55)
			(layers "F.Cu" "F.Mask" "F.Paste")
			(roundrect_rratio 0.25)
			(net 47 "/Debug FTDI/JTAG.TDO")
			(pintype "passive")
		)
		(pad "5" smd roundrect
			(at -0.387 0.998 90)
			(size 0.25 0.55)
			(layers "F.Cu" "F.Mask" "F.Paste")
			(roundrect_rratio 0.25)
			(net 48 "/Debug FTDI/JTAG.TDI")
			(pintype "passive")
		)
		(pad "6" smd roundrect
			(at 0.385 0.998 90)
			(size 0.25 0.55)
			(layers "F.Cu" "F.Mask" "F.Paste")
			(roundrect_rratio 0.25)
			(net 48 "/Debug FTDI/JTAG.TDI")
			(pintype "passive")
		)
		(pad "7" smd roundrect
			(at 0.385 0.498 90)
			(size 0.25 0.55)
			(layers "F.Cu" "F.Mask" "F.Paste")
			(roundrect_rratio 0.25)
			(net 47 "/Debug FTDI/JTAG.TDO")
			(pintype "passive")
		)
		(pad "8" smd roundrect
			(at 0.385 0 90)
			(size 0.4 0.55)
			(layers "F.Cu" "F.Mask" "F.Paste")
			(roundrect_rratio 0.25)
			(net 1 "GND")
			(pintype "passive")
		)
		(pad "9" smd roundrect
			(at 0.385 -0.5 90)
			(size 0.25 0.55)
			(layers "F.Cu" "F.Mask" "F.Paste")
			(roundrect_rratio 0.25)
			(net 46 "/Debug FTDI/JTAG.TCK")
			(pintype "passive")
		)
		(pad "10" smd roundrect
			(at 0.385 -1 90)
			(size 0.25 0.55)
			(layers "F.Cu" "F.Mask" "F.Paste")
			(roundrect_rratio 0.25)
			(net 45 "/Debug FTDI/JTAG.TMS")
			(pintype "passive")
		)
	)
	(footprint "antmicro-footprints:VQFN-16-1EP_3x3mm_P0.5mm_EP1.1x1.1mm"
		(layer "F.Cu")
		(at 182.387107 184.914 -90)
		(descr "VQFN, 16 Pin (https://ww1.microchip.com/downloads/en/DeviceDoc/16L_VQFN-WFS_3x3mm_4MX_C04-00508a.pdf), generated with kicad-footprint-generator ipc_noLead_generator.py")
		(tags "VQFN NoLead")
		(property "Reference" "U25"
			(at 2.886 -0.012893 180)
			(layer "F.SilkS")
			(effects
				(font
					(size 0.7 0.7)
					(thickness 0.15)
				)
				(justify left bottom)
			)
		)
		(property "Value" "PAC1954T-E_VQFN"
			(at 0 2.797 270)
			(layer "F.Fab")
			(effects
				(font
					(size 0.7 0.7)
					(thickness 0.15)
				)
				(justify left bottom)
			)
		)
		(property "Datasheet" "https://ww1.microchip.com/downloads/aemDocuments/documents/MSLD/ProductDocuments/DataSheets/PAC195X-Family-Data-Sheet-DS20006539.pdf"
			(at 0 0 270)
			(layer "F.Fab")
			(hide yes)
			(effects
				(font
					(size 1.27 1.27)
					(thickness 0.15)
				)
			)
		)
		(property "Author" "Antmicro"
			(at -2.526893 367.301107 0)
			(layer "F.Fab")
			(hide yes)
			(effects
				(font
					(size 1 1)
					(thickness 0.15)
				)
			)
		)
		(property "License" "Apache-2.0"
			(at -2.526893 367.301107 0)
			(layer "F.Fab")
			(hide yes)
			(effects
				(font
					(size 1 1)
					(thickness 0.15)
				)
			)
		)
		(property "MPN" "PAC1954T-E/4MX"
			(at -2.526893 367.301107 0)
			(layer "F.Fab")
			(hide yes)
			(effects
				(font
					(size 1 1)
					(thickness 0.15)
				)
			)
		)
		(property "Manufacturer" "Microchip Technology"
			(at -2.526893 367.301107 0)
			(layer "F.Fab")
			(hide yes)
			(effects
				(font
					(size 1 1)
					(thickness 0.15)
				)
			)
		)
		(property ki_fp_filters "UQFN*1EP*4x4mm*P0.65mm*")
		(sheetname "/Supply/")
		(sheetfile "supply.kicad_sch")
		(attr smd)
		(fp_line
			(start -1.611 1.61)
			(end -1.611 1.134)
			(stroke
				(width 0.15)
				(type solid)
			)
			(layer "F.SilkS")
		)
		(fp_line
			(start -1.135 1.61)
			(end -1.611 1.61)
			(stroke
				(width 0.15)
				(type solid)
			)
			(layer "F.SilkS")
		)
		(fp_line
			(start 1.134 1.61)
			(end 1.61 1.61)
			(stroke
				(width 0.15)
				(type solid)
			)
			(layer "F.SilkS")
		)
		(fp_line
			(start 1.61 1.61)
			(end 1.61 1.134)
			(stroke
				(width 0.15)
				(type solid)
			)
			(layer "F.SilkS")
		)
		(fp_line
			(start -1.135 -1.611)
			(end -1.611 -1.611)
			(stroke
				(width 0.15)
				(type solid)
			)
			(layer "F.SilkS")
		)
		(fp_line
			(start 1.134 -1.611)
			(end 1.61 -1.611)
			(stroke
				(width 0.15)
				(type solid)
			)
			(layer "F.SilkS")
		)
		(fp_line
			(start 1.61 -1.611)
			(end 1.61 -1.135)
			(stroke
				(width 0.15)
				(type solid)
			)
			(layer "F.SilkS")
		)
		(fp_circle
			(center -2.3 -0.75)
			(end -2.25 -0.75)
			(stroke
				(width 0.15)
				(type solid)
			)
			(fill yes)
			(layer "F.SilkS")
		)
		(fp_rect
			(start -2 -2)
			(end 1.999 1.999)
			(stroke
				(width 0.05)
				(type solid)
			)
			(fill no)
			(layer "F.CrtYd")
		)
		(fp_line
			(start -1.5 1.499)
			(end -1.5 -0.75)
			(stroke
				(width 0.15)
				(type solid)
			)
			(layer "F.Fab")
		)
		(fp_line
			(start 1.499 1.499)
			(end -1.5 1.499)
			(stroke
				(width 0.15)
				(type solid)
			)
			(layer "F.Fab")
		)
		(fp_line
			(start -1.5 -0.75)
			(end -0.75 -1.5)
			(stroke
				(width 0.15)
				(type solid)
			)
			(layer "F.Fab")
		)
		(fp_line
			(start -0.75 -1.5)
			(end 1.499 -1.5)
			(stroke
				(width 0.15)
				(type solid)
			)
			(layer "F.Fab")
		)
		(fp_line
			(start 1.499 -1.5)
			(end 1.499 1.499)
			(stroke
				(width 0.15)
				(type solid)
			)
			(layer "F.Fab")
		)
		(fp_circle
			(center -2.3 -0.75)
			(end -2.25 -0.75)
			(stroke
				(width 0.15)
				(type solid)
			)
			(fill yes)
			(layer "F.Fab")
		)
		(pad "" smd roundrect
			(at 0 0 270)
			(size 0.89 0.89)
			(layers "F.Paste")
			(roundrect_rratio 0.25)
		)
		(pad "1" smd roundrect
			(at -1.464 -0.75 270)
			(size 0.775 0.25)
			(layers "F.Cu" "F.Mask" "F.Paste")
			(roundrect_rratio 0.25)
			(net 1 "GND")
			(pinfunction "SLOW/~{ALERT1}")
			(pintype "bidirectional")
		)
		(pad "2" smd roundrect
			(at -1.464 -0.25 270)
			(size 0.775 0.25)
			(layers "F.Cu" "F.Mask" "F.Paste")
			(roundrect_rratio 0.25)
			(net 200 "+3V3")
			(pinfunction "VDD")
			(pintype "power_in")
		)
		(pad "3" smd roundrect
			(at -1.464 0.247 270)
			(size 0.775 0.25)
			(layers "F.Cu" "F.Mask" "F.Paste")
			(roundrect_rratio 0.25)
			(net 1 "GND")
			(pinfunction "GND")
			(pintype "power_in")
		)
		(pad "4" smd roundrect
			(at -1.464 0.747 270)
			(size 0.775 0.25)
			(layers "F.Cu" "F.Mask" "F.Paste")
			(roundrect_rratio 0.25)
			(net 297 "/Supply/PWR_SCL_2")
			(pinfunction "SCL")
			(pintype "input")
		)
		(pad "5" smd roundrect
			(at -0.75 1.461 270)
			(size 0.25 0.775)
			(layers "F.Cu" "F.Mask" "F.Paste")
			(roundrect_rratio 0.25)
			(net 298 "/Supply/PWR_SDA_2")
			(pinfunction "SDA")
			(pintype "bidirectional")
		)
		(pad "6" smd roundrect
			(at -0.25 1.461 270)
			(size 0.25 0.775)
			(layers "F.Cu" "F.Mask" "F.Paste")
			(roundrect_rratio 0.25)
			(net 200 "+3V3")
			(pinfunction "ADDRSEL")
			(pintype "bidirectional")
		)
		(pad "7" smd roundrect
			(at 0.247 1.461 270)
			(size 0.25 0.775)
			(layers "F.Cu" "F.Mask" "F.Paste")
			(roundrect_rratio 0.25)
			(net 237 "/Supply/sp_SEN_-")
			(pinfunction "IN3-")
			(pintype "input")
		)
		(pad "8" smd roundrect
			(at 0.747 1.461 270)
			(size 0.25 0.775)
			(layers "F.Cu" "F.Mask" "F.Paste")
			(roundrect_rratio 0.25)
			(net 232 "/Supply/sp_SEN_+")
			(pinfunction "IN3+")
			(pintype "input")
		)
		(pad "9" smd roundrect
			(at 1.461 0.747 270)
			(size 0.775 0.25)
			(layers "F.Cu" "F.Mask" "F.Paste")
			(roundrect_rratio 0.25)
			(net 145 "/Supply/1V7_SEN_-")
			(pinfunction "IN4-")
			(pintype "input")
		)
		(pad "10" smd roundrect
			(at 1.461 0.247 270)
			(size 0.775 0.25)
			(layers "F.Cu" "F.Mask" "F.Paste")
			(roundrect_rratio 0.25)
			(net 131 "/Supply/1V7_SEN_+")
			(pinfunction "IN4+")
			(pintype "input")
		)
		(pad "11" smd roundrect
			(at 1.461 -0.25 270)
			(size 0.775 0.25)
			(layers "F.Cu" "F.Mask" "F.Paste")
			(roundrect_rratio 0.25)
			(net 86 "/Supply/MGTAVCC_SEN_+")
			(pinfunction "IN1+")
			(pintype "input")
		)
		(pad "12" smd roundrect
			(at 1.461 -0.75 270)
			(size 0.775 0.25)
			(layers "F.Cu" "F.Mask" "F.Paste")
			(roundrect_rratio 0.25)
			(net 143 "/Supply/MGTAVCC_SEN_-")
			(pinfunction "IN1-")
			(pintype "input")
		)
		(pad "13" smd roundrect
			(at 0.747 -1.464 270)
			(size 0.25 0.775)
			(layers "F.Cu" "F.Mask" "F.Paste")
			(roundrect_rratio 0.25)
			(net 244 "/Supply/1V8_SEN_+")
			(pinfunction "IN2+")
			(pintype "input")
		)
		(pad "14" smd roundrect
			(at 0.247 -1.464 270)
			(size 0.25 0.775)
			(layers "F.Cu" "F.Mask" "F.Paste")
			(roundrect_rratio 0.25)
			(net 246 "/Supply/1V8_SEN_-")
			(pinfunction "IN2-")
			(pintype "input")
		)
		(pad "15" smd roundrect
			(at -0.25 -1.464 270)
			(size 0.25 0.775)
			(layers "F.Cu" "F.Mask" "F.Paste")
			(roundrect_rratio 0.25)
			(net 1 "GND")
			(pinfunction "GPIO/~{ALERT2}")
			(pintype "bidirectional")
		)
		(pad "16" smd roundrect
			(at -0.75 -1.464 270)
			(size 0.25 0.775)
			(layers "F.Cu" "F.Mask" "F.Paste")
			(roundrect_rratio 0.25)
			(net 385 "Net-(U25-~{PWRDN})")
			(pinfunction "~{PWRDN}")
			(pintype "input")
		)
		(pad "17" smd rect
			(at 0 0 270)
			(size 1.1 1.1)
			(layers "F.Cu" "F.Mask")
			(net 731 "unconnected-(U25-EP-Pad17)")
			(pinfunction "EP")
			(pintype "no_connect")
		)
	)
	(footprint "antmicro-footprints:MP_NPTH_Drill3mm"
		(layer "F.Cu")
		(at 202.878201 197.551)
		(property "Reference" "MP3"
			(at 0 -1.8 0)
			(layer "F.SilkS")
			(hide yes)
			(effects
				(font
					(size 0.7 0.7)
					(thickness 0.15)
				)
				(justify left bottom)
			)
		)
		(property "Value" "MP_NPTH_Drill3mm"
			(at 0 2.4 0)
			(layer "F.Fab")
			(effects
				(font
					(size 0.7 0.7)
					(thickness 0.15)
				)
				(justify left bottom)
			)
		)
		(property "Author" "Antmicro"
			(at 0 0 0)
			(layer "F.Fab")
			(hide yes)
			(effects
				(font
					(size 1 1)
					(thickness 0.15)
				)
			)
		)
		(property "License" "Apache-2.0"
			(at 0 0 0)
			(layer "F.Fab")
			(hide yes)
			(effects
				(font
					(size 1 1)
					(thickness 0.15)
				)
			)
		)
		(sheetfile "sodimm-ddr5-tester.kicad_sch")
		(attr board_only exclude_from_pos_files exclude_from_bom)
		(pad "" np_thru_hole circle
			(at 0 0)
			(size 3 3)
			(drill 3)
			(layers "*.Cu" "*.Mask")
		)
	)
	(footprint "antmicro-footprints:C_0402_1005Metric"
		(layer "F.Cu")
		(at 96.5 180.65 -90)
		(descr "Capacitor SMD 0402")
		(tags "capacitor SMD 0402")
		(property "Reference" "C121"
			(at 0 -0.699 270)
			(layer "F.SilkS")
			(hide yes)
			(effects
				(font
					(size 0.7 0.7)
					(thickness 0.15)
				)
				(justify left bottom)
			)
		)
		(property "Value" "C_100n_0402"
			(at -1.022927 2.155213 270)
			(layer "F.Fab")
			(effects
				(font
					(size 0.7 0.7)
					(thickness 0.15)
				)
				(justify left bottom)
			)
		)
		(property "Datasheet" "https://www.murata.com/products/productdetail?partno=GRM155R61H104KE14%23"
			(at 0 0 270)
			(layer "F.Fab")
			(hide yes)
			(effects
				(font
					(size 1.27 1.27)
					(thickness 0.15)
				)
			)
		)
		(property "Author" "Antmicro"
			(at -84.15 277.15 0)
			(layer "F.Fab")
			(hide yes)
			(effects
				(font
					(size 1 1)
					(thickness 0.15)
				)
			)
		)
		(property "Dielectric" "X5R"
			(at -84.15 277.15 0)
			(layer "F.Fab")
			(hide yes)
			(effects
				(font
					(size 1 1)
					(thickness 0.15)
				)
			)
		)
		(property "License" "Apache-2.0"
			(at -84.15 277.15 0)
			(layer "F.Fab")
			(hide yes)
			(effects
				(font
					(size 1 1)
					(thickness 0.15)
				)
			)
		)
		(property "MPN" "GRM155R61H104KE14D"
			(at -84.15 277.15 0)
			(layer "F.Fab")
			(hide yes)
			(effects
				(font
					(size 1 1)
					(thickness 0.15)
				)
			)
		)
		(property "Manufacturer" "Murata"
			(at -84.15 277.15 0)
			(layer "F.Fab")
			(hide yes)
			(effects
				(font
					(size 1 1)
					(thickness 0.15)
				)
			)
		)
		(property "Val" "100n"
			(at -84.15 277.15 0)
			(layer "F.Fab")
			(hide yes)
			(effects
				(font
					(size 1 1)
					(thickness 0.15)
				)
			)
		)
		(property "Voltage" "50V"
			(at -84.15 277.15 0)
			(layer "F.Fab")
			(hide yes)
			(effects
				(font
					(size 1 1)
					(thickness 0.15)
				)
			)
		)
		(sheetname "/Debug FTDI/")
		(sheetfile "debug-ftdi.kicad_sch")
		(attr smd)
		(fp_rect
			(start -0.9659 -0.481258)
			(end 0.9649 0.458742)
			(stroke
				(width 0.05)
				(type solid)
			)
			(fill no)
			(layer "F.CrtYd")
		)
		(fp_line
			(start -0.499 0.248)
			(end -0.499 -0.25)
			(stroke
				(width 0.15)
				(type solid)
			)
			(layer "F.Fab")
		)
		(fp_line
			(start 0.499 0.248)
			(end -0.499 0.248)
			(stroke
				(width 0.15)
				(type solid)
			)
			(layer "F.Fab")
		)
		(fp_line
			(start -0.499 -0.25)
			(end 0.499 -0.25)
			(stroke
				(width 0.15)
				(type solid)
			)
			(layer "F.Fab")
		)
		(fp_line
			(start 0.499 -0.25)
			(end 0.499 0.248)
			(stroke
				(width 0.15)
				(type solid)
			)
			(layer "F.Fab")
		)
		(pad "1" smd roundrect
			(at -0.484 0 270)
			(size 0.59 0.64)
			(layers "F.Cu" "F.Mask" "F.Paste")
			(roundrect_rratio 0.25)
			(net 1 "GND")
			(pintype "passive")
		)
		(pad "2" smd roundrect
			(at 0.484 0 270)
			(size 0.59 0.64)
			(layers "F.Cu" "F.Mask" "F.Paste")
			(roundrect_rratio 0.25)
			(net 6 "/Debug FTDI/FTDI_3V3")
			(pintype "passive")
		)
	)
	(footprint "antmicro-footprints:R_0402_1005Metric"
		(layer "F.Cu")
		(at 202.945501 180.9455 90)
		(descr "Resistor SMD 0402")
		(tags "resistor SMD 0402")
		(property "Reference" "R162"
			(at 0.9455 0.304499 90)
			(layer "F.SilkS")
			(effects
				(font
					(size 0.7 0.7)
					(thickness 0.15)
				)
				(justify left bottom)
			)
		)
		(property "Value" "R_0R_0402"
			(at -1.011843 1.772047 90)
			(layer "F.Fab")
			(effects
				(font
					(size 0.7 0.7)
					(thickness 0.15)
				)
				(justify left bottom)
			)
		)
		(property "Datasheet" "https://industrial.panasonic.com/cdbs/www-data/pdf/RDA0000/AOA0000C301.pdf"
			(at 0 0 90)
			(layer "F.Fab")
			(hide yes)
			(effects
				(font
					(size 1.27 1.27)
					(thickness 0.15)
				)
			)
		)
		(property "Author" "Antmicro"
			(at 383.891001 -22.000001 0)
			(layer "F.Fab")
			(hide yes)
			(effects
				(font
					(size 1 1)
					(thickness 0.15)
				)
			)
		)
		(property "Current" "1A"
			(at 383.891001 -22.000001 0)
			(layer "F.Fab")
			(hide yes)
			(effects
				(font
					(size 1 1)
					(thickness 0.15)
				)
			)
		)
		(property "License" "Apache-2.0"
			(at 383.891001 -22.000001 0)
			(layer "F.Fab")
			(hide yes)
			(effects
				(font
					(size 1 1)
					(thickness 0.15)
				)
			)
		)
		(property "MPN" "ERJ2GE0R00X"
			(at 383.891001 -22.000001 0)
			(layer "F.Fab")
			(hide yes)
			(effects
				(font
					(size 1 1)
					(thickness 0.15)
				)
			)
		)
		(property "Manufacturer" "Panasonic"
			(at 383.891001 -22.000001 0)
			(layer "F.Fab")
			(hide yes)
			(effects
				(font
					(size 1 1)
					(thickness 0.15)
				)
			)
		)
		(property "Tolerance" ""
			(at 383.891001 -22.000001 0)
			(layer "F.Fab")
			(hide yes)
			(effects
				(font
					(size 1 1)
					(thickness 0.15)
				)
			)
		)
		(property "Val" "0R"
			(at 383.891001 -22.000001 0)
			(layer "F.Fab")
			(hide yes)
			(effects
				(font
					(size 1 1)
					(thickness 0.15)
				)
			)
		)
		(sheetname "/Supply/")
		(sheetfile "supply.kicad_sch")
		(attr smd)
		(fp_rect
			(start -0.93 -0.47)
			(end 0.93 0.47)
			(stroke
				(width 0.05)
				(type solid)
			)
			(fill no)
			(layer "F.CrtYd")
		)
		(fp_rect
			(start -0.5 -0.25)
			(end 0.5 0.25)
			(stroke
				(width 0.15)
				(type solid)
			)
			(fill no)
			(layer "F.Fab")
		)
		(pad "1" smd roundrect
			(at -0.485 0 90)
			(size 0.59 0.64)
			(layers "F.Cu" "F.Mask" "F.Paste")
			(roundrect_rratio 0.25)
			(net 216 "/Supply/FB3")
			(pintype "passive")
		)
		(pad "2" smd roundrect
			(at 0.485 0 90)
			(size 0.59 0.64)
			(layers "F.Cu" "F.Mask" "F.Paste")
			(roundrect_rratio 0.25)
			(net 35 "/Supply/spare_local")
			(pintype "passive")
		)
	)
	(footprint "antmicro-footprints:C_0402_1005Metric"
		(layer "F.Cu")
		(at 86.227001 184.9005 180)
		(descr "Capacitor SMD 0402")
		(tags "capacitor SMD 0402")
		(property "Reference" "C126"
			(at 0 -0.699 180)
			(layer "F.SilkS")
			(hide yes)
			(effects
				(font
					(size 0.7 0.7)
					(thickness 0.15)
				)
				(justify left bottom)
			)
		)
		(property "Value" "C_10u_6.3V_0402"
			(at -1.022927 2.155213 180)
			(layer "F.Fab")
			(effects
				(font
					(size 0.7 0.7)
					(thickness 0.15)
				)
				(justify left bottom)
			)
		)
		(property "Datasheet" "https://www.murata.com/products/productdetail?partno=GRM155R60J106ME15%23"
			(at 0 0 180)
			(layer "F.Fab")
			(hide yes)
			(effects
				(font
					(size 1.27 1.27)
					(thickness 0.15)
				)
			)
		)
		(property "Author" "Antmicro"
			(at 172.454002 369.801 0)
			(layer "F.Fab")
			(hide yes)
			(effects
				(font
					(size 1 1)
					(thickness 0.15)
				)
			)
		)
		(property "Dielectric" "X5R"
			(at 172.454002 369.801 0)
			(layer "F.Fab")
			(hide yes)
			(effects
				(font
					(size 1 1)
					(thickness 0.15)
				)
			)
		)
		(property "License" "Apache-2.0"
			(at 172.454002 369.801 0)
			(layer "F.Fab")
			(hide yes)
			(effects
				(font
					(size 1 1)
					(thickness 0.15)
				)
			)
		)
		(property "MPN" "GRM155R60J106ME15D"
			(at 172.454002 369.801 0)
			(layer "F.Fab")
			(hide yes)
			(effects
				(font
					(size 1 1)
					(thickness 0.15)
				)
			)
		)
		(property "Manufacturer" "Murata"
			(at 172.454002 369.801 0)
			(layer "F.Fab")
			(hide yes)
			(effects
				(font
					(size 1 1)
					(thickness 0.15)
				)
			)
		)
		(property "Val" "10u"
			(at 172.454002 369.801 0)
			(layer "F.Fab")
			(hide yes)
			(effects
				(font
					(size 1 1)
					(thickness 0.15)
				)
			)
		)
		(property "Voltage" "6.3V"
			(at 172.454002 369.801 0)
			(layer "F.Fab")
			(hide yes)
			(effects
				(font
					(size 1 1)
					(thickness 0.15)
				)
			)
		)
		(sheetname "/HDMI + SD Card/")
		(sheetfile "hdmi-sd-card.kicad_sch")
		(attr smd)
		(fp_rect
			(start -0.9659 -0.481258)
			(end 0.9649 0.458742)
			(stroke
				(width 0.05)
				(type solid)
			)
			(fill no)
			(layer "F.CrtYd")
		)
		(fp_line
			(start 0.499 0.248)
			(end -0.499 0.248)
			(stroke
				(width 0.15)
				(type solid)
			)
			(layer "F.Fab")
		)
		(fp_line
			(start 0.499 -0.25)
			(end 0.499 0.248)
			(stroke
				(width 0.15)
				(type solid)
			)
			(layer "F.Fab")
		)
		(fp_line
			(start -0.499 0.248)
			(end -0.499 -0.25)
			(stroke
				(width 0.15)
				(type solid)
			)
			(layer "F.Fab")
		)
		(fp_line
			(start -0.499 -0.25)
			(end 0.499 -0.25)
			(stroke
				(width 0.15)
				(type solid)
			)
			(layer "F.Fab")
		)
		(pad "1" smd roundrect
			(at -0.484 0 180)
			(size 0.59 0.64)
			(layers "F.Cu" "F.Mask" "F.Paste")
			(roundrect_rratio 0.25)
			(net 1 "GND")
			(pintype "passive")
		)
		(pad "2" smd roundrect
			(at 0.484 0 180)
			(size 0.59 0.64)
			(layers "F.Cu" "F.Mask" "F.Paste")
			(roundrect_rratio 0.25)
			(net 9 "/HDMI + SD Card/HDMI_CONN_5V")
			(pintype "passive")
		)
	)
	(footprint "antmicro-footprints:C_0402_1005Metric"
		(layer "F.Cu")
		(at 183.55 149.675)
		(descr "Capacitor SMD 0402")
		(tags "capacitor SMD 0402")
		(property "Reference" "C207"
			(at 0 -0.699 0)
			(layer "F.SilkS")
			(hide yes)
			(effects
				(font
					(size 0.7 0.7)
					(thickness 0.15)
				)
				(justify left bottom)
			)
		)
		(property "Value" "C_10u_6.3V_0402"
			(at -1.022927 2.155213 0)
			(layer "F.Fab")
			(effects
				(font
					(size 0.7 0.7)
					(thickness 0.15)
				)
				(justify left bottom)
			)
		)
		(property "Datasheet" "https://www.murata.com/products/productdetail?partno=GRM155R60J106ME15%23"
			(at 0 0 0)
			(layer "F.Fab")
			(hide yes)
			(effects
				(font
					(size 1.27 1.27)
					(thickness 0.15)
				)
			)
		)
		(property "Author" "Antmicro"
			(at 0 0 0)
			(layer "F.Fab")
			(hide yes)
			(effects
				(font
					(size 1 1)
					(thickness 0.15)
				)
			)
		)
		(property "Dielectric" "X5R"
			(at 0 0 0)
			(layer "F.Fab")
			(hide yes)
			(effects
				(font
					(size 1 1)
					(thickness 0.15)
				)
			)
		)
		(property "License" "Apache-2.0"
			(at 0 0 0)
			(layer "F.Fab")
			(hide yes)
			(effects
				(font
					(size 1 1)
					(thickness 0.15)
				)
			)
		)
		(property "MPN" "GRM155R60J106ME15D"
			(at 0 0 0)
			(layer "F.Fab")
			(hide yes)
			(effects
				(font
					(size 1 1)
					(thickness 0.15)
				)
			)
		)
		(property "Manufacturer" "Murata"
			(at 0 0 0)
			(layer "F.Fab")
			(hide yes)
			(effects
				(font
					(size 1 1)
					(thickness 0.15)
				)
			)
		)
		(property "Val" "10u"
			(at 0 0 0)
			(layer "F.Fab")
			(hide yes)
			(effects
				(font
					(size 1 1)
					(thickness 0.15)
				)
			)
		)
		(property "Voltage" "6.3V"
			(at 0 0 0)
			(layer "F.Fab")
			(hide yes)
			(effects
				(font
					(size 1 1)
					(thickness 0.15)
				)
			)
		)
		(sheetname "/Supply/")
		(sheetfile "supply.kicad_sch")
		(attr smd)
		(fp_rect
			(start -0.9659 -0.481258)
			(end 0.9649 0.458742)
			(stroke
				(width 0.05)
				(type solid)
			)
			(fill no)
			(layer "F.CrtYd")
		)
		(fp_line
			(start -0.499 -0.25)
			(end 0.499 -0.25)
			(stroke
				(width 0.15)
				(type solid)
			)
			(layer "F.Fab")
		)
		(fp_line
			(start -0.499 0.248)
			(end -0.499 -0.25)
			(stroke
				(width 0.15)
				(type solid)
			)
			(layer "F.Fab")
		)
		(fp_line
			(start 0.499 -0.25)
			(end 0.499 0.248)
			(stroke
				(width 0.15)
				(type solid)
			)
			(layer "F.Fab")
		)
		(fp_line
			(start 0.499 0.248)
			(end -0.499 0.248)
			(stroke
				(width 0.15)
				(type solid)
			)
			(layer "F.Fab")
		)
		(pad "1" smd roundrect
			(at -0.484 0)
			(size 0.59 0.64)
			(layers "F.Cu" "F.Mask" "F.Paste")
			(roundrect_rratio 0.25)
			(net 1 "GND")
			(pintype "passive")
		)
		(pad "2" smd roundrect
			(at 0.484 0)
			(size 0.59 0.64)
			(layers "F.Cu" "F.Mask" "F.Paste")
			(roundrect_rratio 0.25)
			(net 200 "+3V3")
			(pintype "passive")
		)
	)
	(footprint "antmicro-footprints:R_0402_1005Metric"
		(layer "F.Cu")
		(at 195.795501 179.4105 180)
		(descr "Resistor SMD 0402")
		(tags "resistor SMD 0402")
		(property "Reference" "R153"
			(at 4.045501 -0.3395 180)
			(layer "F.SilkS")
			(effects
				(font
					(size 0.7 0.7)
					(thickness 0.15)
				)
				(justify left bottom)
			)
		)
		(property "Value" "R_0R_0402"
			(at -1.011843 1.772047 180)
			(layer "F.Fab")
			(effects
				(font
					(size 0.7 0.7)
					(thickness 0.15)
				)
				(justify left bottom)
			)
		)
		(property "Datasheet" "https://industrial.panasonic.com/cdbs/www-data/pdf/RDA0000/AOA0000C301.pdf"
			(at 0 0 180)
			(layer "F.Fab")
			(hide yes)
			(effects
				(font
					(size 1.27 1.27)
					(thickness 0.15)
				)
			)
		)
		(property "Author" "Antmicro"
			(at 391.591002 358.821 0)
			(layer "F.Fab")
			(hide yes)
			(effects
				(font
					(size 1 1)
					(thickness 0.15)
				)
			)
		)
		(property "Current" "1A"
			(at 391.591002 358.821 0)
			(layer "F.Fab")
			(hide yes)
			(effects
				(font
					(size 1 1)
					(thickness 0.15)
				)
			)
		)
		(property "License" "Apache-2.0"
			(at 391.591002 358.821 0)
			(layer "F.Fab")
			(hide yes)
			(effects
				(font
					(size 1 1)
					(thickness 0.15)
				)
			)
		)
		(property "MPN" "ERJ2GE0R00X"
			(at 391.591002 358.821 0)
			(layer "F.Fab")
			(hide yes)
			(effects
				(font
					(size 1 1)
					(thickness 0.15)
				)
			)
		)
		(property "Manufacturer" "Panasonic"
			(at 391.591002 358.821 0)
			(layer "F.Fab")
			(hide yes)
			(effects
				(font
					(size 1 1)
					(thickness 0.15)
				)
			)
		)
		(property "Tolerance" ""
			(at 391.591002 358.821 0)
			(layer "F.Fab")
			(hide yes)
			(effects
				(font
					(size 1 1)
					(thickness 0.15)
				)
			)
		)
		(property "Val" "0R"
			(at 391.591002 358.821 0)
			(layer "F.Fab")
			(hide yes)
			(effects
				(font
					(size 1 1)
					(thickness 0.15)
				)
			)
		)
		(sheetname "/Supply/")
		(sheetfile "supply.kicad_sch")
		(attr smd)
		(fp_rect
			(start -0.93 -0.47)
			(end 0.93 0.47)
			(stroke
				(width 0.05)
				(type solid)
			)
			(fill no)
			(layer "F.CrtYd")
		)
		(fp_rect
			(start -0.5 -0.25)
			(end 0.5 0.25)
			(stroke
				(width 0.15)
				(type solid)
			)
			(fill no)
			(layer "F.Fab")
		)
		(pad "1" smd roundrect
			(at -0.485 0 180)
			(size 0.59 0.64)
			(layers "F.Cu" "F.Mask" "F.Paste")
			(roundrect_rratio 0.25)
			(net 211 "/Supply/FB2")
			(pintype "passive")
		)
		(pad "2" smd roundrect
			(at 0.485 0 180)
			(size 0.59 0.64)
			(layers "F.Cu" "F.Mask" "F.Paste")
			(roundrect_rratio 0.25)
			(net 51 "/Supply/1V8_local")
			(pintype "passive")
		)
	)
	(footprint "antmicro-footprints:R_0402_1005Metric"
		(layer "F.Cu")
		(at 202.881001 163.472 90)
		(descr "Resistor SMD 0402")
		(tags "resistor SMD 0402")
		(property "Reference" "R166"
			(at 0.972 0.368999 90)
			(layer "F.SilkS")
			(effects
				(font
					(size 0.7 0.7)
					(thickness 0.15)
				)
				(justify left bottom)
			)
		)
		(property "Value" "R_0R_0402"
			(at -1.011843 1.772047 90)
			(layer "F.Fab")
			(effects
				(font
					(size 0.7 0.7)
					(thickness 0.15)
				)
				(justify left bottom)
			)
		)
		(property "Datasheet" "https://industrial.panasonic.com/cdbs/www-data/pdf/RDA0000/AOA0000C301.pdf"
			(at 0 0 90)
			(layer "F.Fab")
			(hide yes)
			(effects
				(font
					(size 1.27 1.27)
					(thickness 0.15)
				)
			)
		)
		(property "Author" "Antmicro"
			(at 366.353001 -39.409001 0)
			(layer "F.Fab")
			(hide yes)
			(effects
				(font
					(size 1 1)
					(thickness 0.15)
				)
			)
		)
		(property "Current" "1A"
			(at 366.353001 -39.409001 0)
			(layer "F.Fab")
			(hide yes)
			(effects
				(font
					(size 1 1)
					(thickness 0.15)
				)
			)
		)
		(property "License" "Apache-2.0"
			(at 366.353001 -39.409001 0)
			(layer "F.Fab")
			(hide yes)
			(effects
				(font
					(size 1 1)
					(thickness 0.15)
				)
			)
		)
		(property "MPN" "ERJ2GE0R00X"
			(at 366.353001 -39.409001 0)
			(layer "F.Fab")
			(hide yes)
			(effects
				(font
					(size 1 1)
					(thickness 0.15)
				)
			)
		)
		(property "Manufacturer" "Panasonic"
			(at 366.353001 -39.409001 0)
			(layer "F.Fab")
			(hide yes)
			(effects
				(font
					(size 1 1)
					(thickness 0.15)
				)
			)
		)
		(property "Tolerance" ""
			(at 366.353001 -39.409001 0)
			(layer "F.Fab")
			(hide yes)
			(effects
				(font
					(size 1 1)
					(thickness 0.15)
				)
			)
		)
		(property "Val" "0R"
			(at 366.353001 -39.409001 0)
			(layer "F.Fab")
			(hide yes)
			(effects
				(font
					(size 1 1)
					(thickness 0.15)
				)
			)
		)
		(sheetname "/Supply/")
		(sheetfile "supply.kicad_sch")
		(attr smd)
		(fp_rect
			(start -0.93 -0.47)
			(end 0.93 0.47)
			(stroke
				(width 0.05)
				(type solid)
			)
			(fill no)
			(layer "F.CrtYd")
		)
		(fp_rect
			(start -0.5 -0.25)
			(end 0.5 0.25)
			(stroke
				(width 0.15)
				(type solid)
			)
			(fill no)
			(layer "F.Fab")
		)
		(pad "1" smd roundrect
			(at -0.485 0 90)
			(size 0.59 0.64)
			(layers "F.Cu" "F.Mask" "F.Paste")
			(roundrect_rratio 0.25)
			(net 217 "/Supply/FB7")
			(pintype "passive")
		)
		(pad "2" smd roundrect
			(at 0.485 0 90)
			(size 0.59 0.64)
			(layers "F.Cu" "F.Mask" "F.Paste")
			(roundrect_rratio 0.25)
			(net 53 "/Supply/1V1_local")
			(pintype "passive")
		)
	)
	(footprint "antmicro-footprints:C_0603_1608Metric"
		(layer "F.Cu")
		(at 168.655502 192.614501 180)
		(descr "Capacitor SMD 0603")
		(tags "capacitor 0603")
		(property "Reference" "C215"
			(at -1.42757 -1.000252 180)
			(layer "F.SilkS")
			(hide yes)
			(effects
				(font
					(size 0.7 0.7)
					(thickness 0.15)
				)
				(justify left bottom)
			)
		)
		(property "Value" "C_22u_0603"
			(at -1.42757 1.770288 180)
			(layer "F.Fab")
			(effects
				(font
					(size 0.7 0.7)
					(thickness 0.15)
				)
				(justify left bottom)
			)
		)
		(property "Datasheet" "https://www.murata.com/products/productdetail?partno=GRM188R60J226MEA0%23"
			(at 0 0 180)
			(layer "F.Fab")
			(hide yes)
			(effects
				(font
					(size 1.27 1.27)
					(thickness 0.15)
				)
			)
		)
		(property "Author" "Antmicro"
			(at 337.311004 385.229002 0)
			(layer "F.Fab")
			(hide yes)
			(effects
				(font
					(size 1 1)
					(thickness 0.15)
				)
			)
		)
		(property "Dielectric" ""
			(at 337.311004 385.229002 0)
			(layer "F.Fab")
			(hide yes)
			(effects
				(font
					(size 1 1)
					(thickness 0.15)
				)
			)
		)
		(property "License" "Apache-2.0"
			(at 337.311004 385.229002 0)
			(layer "F.Fab")
			(hide yes)
			(effects
				(font
					(size 1 1)
					(thickness 0.15)
				)
			)
		)
		(property "MPN" "GRM188R60J226MEA0D"
			(at 337.311004 385.229002 0)
			(layer "F.Fab")
			(hide yes)
			(effects
				(font
					(size 1 1)
					(thickness 0.15)
				)
			)
		)
		(property "Manufacturer" "Murata"
			(at 337.311004 385.229002 0)
			(layer "F.Fab")
			(hide yes)
			(effects
				(font
					(size 1 1)
					(thickness 0.15)
				)
			)
		)
		(property "Val" "22u"
			(at 337.311004 385.229002 0)
			(layer "F.Fab")
			(hide yes)
			(effects
				(font
					(size 1 1)
					(thickness 0.15)
				)
			)
		)
		(property "Voltage" ""
			(at 337.311004 385.229002 0)
			(layer "F.Fab")
			(hide yes)
			(effects
				(font
					(size 1 1)
					(thickness 0.15)
				)
			)
		)
		(sheetname "/Supply/")
		(sheetfile "supply.kicad_sch")
		(attr smd)
		(fp_line
			(start -0.3 0.3)
			(end 0.3 0.3)
			(stroke
				(width 0.15)
				(type solid)
			)
			(layer "F.SilkS")
		)
		(fp_line
			(start -0.3 -0.3)
			(end 0.3 -0.3)
			(stroke
				(width 0.15)
				(type solid)
			)
			(layer "F.SilkS")
		)
		(fp_rect
			(start -1.24 -0.7)
			(end 1.24 0.7)
			(stroke
				(width 0.05)
				(type solid)
			)
			(fill no)
			(layer "F.CrtYd")
		)
		(fp_rect
			(start -0.8 -0.4)
			(end 0.8 0.4)
			(stroke
				(width 0.15)
				(type solid)
			)
			(fill no)
			(layer "F.Fab")
		)
		(pad "1" smd roundrect
			(at -0.7 0 180)
			(size 0.6 0.8)
			(layers "F.Cu" "F.Mask" "F.Paste")
			(roundrect_rratio 0.2)
			(net 1 "GND")
			(pintype "passive")
		)
		(pad "2" smd roundrect
			(at 0.7 0 180)
			(size 0.6 0.8)
			(layers "F.Cu" "F.Mask" "F.Paste")
			(roundrect_rratio 0.2)
			(net 78 "/Supply/1V0_REG")
			(pintype "passive")
		)
	)
	(footprint "antmicro-footprints:C_Pol_EIA-B"
		(layer "F.Cu")
		(at 165.4 186.6 90)
		(property "Reference" "C25"
			(at 0 -2.3 90)
			(layer "F.SilkS")
			(hide yes)
			(effects
				(font
					(size 0.7 0.7)
					(thickness 0.15)
				)
				(justify left bottom)
			)
		)
		(property "Value" "C_Pol_330u_6.3V_KEMET-T520-B"
			(at 0 2.85 90)
			(layer "F.Fab")
			(effects
				(font
					(size 0.7 0.7)
					(thickness 0.15)
				)
				(justify left bottom)
			)
		)
		(property "Datasheet" "https://content.kemet.com/datasheets/KEM_T2076_T52X-530.pdf"
			(at 0 0 90)
			(layer "F.Fab")
			(hide yes)
			(effects
				(font
					(size 1.27 1.27)
					(thickness 0.15)
				)
			)
		)
		(property "Author" "Antmicro"
			(at 352 21.2 0)
			(layer "F.Fab")
			(hide yes)
			(effects
				(font
					(size 1 1)
					(thickness 0.15)
				)
			)
		)
		(property "License" "Apache-2.0"
			(at 352 21.2 0)
			(layer "F.Fab")
			(hide yes)
			(effects
				(font
					(size 1 1)
					(thickness 0.15)
				)
			)
		)
		(property "MPN" "T520B337M006ATE040"
			(at 352 21.2 0)
			(layer "F.Fab")
			(hide yes)
			(effects
				(font
					(size 1 1)
					(thickness 0.15)
				)
			)
		)
		(property "Manufacturer" "KEMET"
			(at 352 21.2 0)
			(layer "F.Fab")
			(hide yes)
			(effects
				(font
					(size 1 1)
					(thickness 0.15)
				)
			)
		)
		(property "Val" "330u/6.3V"
			(at 352 21.2 0)
			(layer "F.Fab")
			(hide yes)
			(effects
				(font
					(size 1 1)
					(thickness 0.15)
				)
			)
		)
		(property "Voltage" "6.3V"
			(at 352 21.2 0)
			(layer "F.Fab")
			(hide yes)
			(effects
				(font
					(size 1 1)
					(thickness 0.15)
				)
			)
		)
		(sheetname "/FPGA power/")
		(sheetfile "fpga-power.kicad_sch")
		(attr smd)
		(fp_line
			(start -2.521 -1.676)
			(end -2.123 -1.676)
			(stroke
				(width 0.15)
				(type solid)
			)
			(layer "F.SilkS")
		)
		(fp_line
			(start -1.8 -1.6)
			(end 1.8 -1.6)
			(stroke
				(width 0.15)
				(type solid)
			)
			(layer "F.SilkS")
		)
		(fp_line
			(start -2.325 -1.475)
			(end -2.325 -1.878)
			(stroke
				(width 0.15)
				(type solid)
			)
			(layer "F.SilkS")
		)
		(fp_line
			(start 1.8 -1.3)
			(end 1.8 -1.6)
			(stroke
				(width 0.15)
				(type solid)
			)
			(layer "F.SilkS")
		)
		(fp_line
			(start -1.8 -1.3)
			(end -1.8 -1.6)
			(stroke
				(width 0.15)
				(type solid)
			)
			(layer "F.SilkS")
		)
		(fp_line
			(start 1.8 1.3)
			(end 1.8 1.6)
			(stroke
				(width 0.15)
				(type solid)
			)
			(layer "F.SilkS")
		)
		(fp_line
			(start -1.8 1.3)
			(end -1.8 1.6)
			(stroke
				(width 0.15)
				(type solid)
			)
			(layer "F.SilkS")
		)
		(fp_line
			(start 1.8 1.6)
			(end -1.8 1.6)
			(stroke
				(width 0.15)
				(type solid)
			)
			(layer "F.SilkS")
		)
		(fp_line
			(start 1.959 -1.75)
			(end -1.971 -1.75)
			(stroke
				(width 0.05)
				(type solid)
			)
			(layer "F.CrtYd")
		)
		(fp_line
			(start 1.959 -1.75)
			(end 1.959 -1.35)
			(stroke
				(width 0.05)
				(type solid)
			)
			(layer "F.CrtYd")
		)
		(fp_line
			(start -1.97 -1.75)
			(end -1.97 -1.35)
			(stroke
				(width 0.05)
				(type solid)
			)
			(layer "F.CrtYd")
		)
		(fp_line
			(start 2.399 -1.35)
			(end 1.959 -1.35)
			(stroke
				(width 0.05)
				(type solid)
			)
			(layer "F.CrtYd")
		)
		(fp_line
			(start 2.399 -1.35)
			(end 2.4 1.35)
			(stroke
				(width 0.05)
				(type solid)
			)
			(layer "F.CrtYd")
		)
		(fp_line
			(start -1.97 -1.35)
			(end -2.41 -1.35)
			(stroke
				(width 0.05)
				(type solid)
			)
			(layer "F.CrtYd")
		)
		(fp_line
			(start -2.411 -1.35)
			(end -2.41 1.35)
			(stroke
				(width 0.05)
				(type solid)
			)
			(layer "F.CrtYd")
		)
		(fp_line
			(start 2.4 1.35)
			(end 1.96 1.35)
			(stroke
				(width 0.05)
				(type solid)
			)
			(layer "F.CrtYd")
		)
		(fp_line
			(start 1.96 1.35)
			(end 1.96 1.75)
			(stroke
				(width 0.05)
				(type solid)
			)
			(layer "F.CrtYd")
		)
		(fp_line
			(start -1.97 1.35)
			(end -2.41 1.35)
			(stroke
				(width 0.05)
				(type solid)
			)
			(layer "F.CrtYd")
		)
		(fp_line
			(start -1.97 1.35)
			(end -1.97 1.75)
			(stroke
				(width 0.05)
				(type solid)
			)
			(layer "F.CrtYd")
		)
		(fp_line
			(start 1.96 1.75)
			(end -1.97 1.75)
			(stroke
				(width 0.05)
				(type solid)
			)
			(layer "F.CrtYd")
		)
		(fp_line
			(start -1.7 1.324)
			(end -1.551 1.475)
			(stroke
				(width 0.15)
				(type solid)
			)
			(layer "F.Fab")
		)
		(fp_rect
			(start -1.72 -1.5)
			(end 1.719 1.499)
			(stroke
				(width 0.15)
				(type solid)
			)
			(fill no)
			(layer "F.Fab")
		)
		(pad "1" smd roundrect
			(at -1.551 0 90)
			(size 1.2 2.2)
			(layers "F.Cu" "F.Mask" "F.Paste")
			(roundrect_rratio 0.1)
			(net 227 "+1V0")
			(pintype "passive")
		)
		(pad "2" smd roundrect
			(at 1.55 0 90)
			(size 1.2 2.2)
			(layers "F.Cu" "F.Mask" "F.Paste")
			(roundrect_rratio 0.1)
			(net 1 "GND")
			(pintype "passive")
		)
	)
	(footprint "antmicro-footprints:SC70-3"
		(layer "F.Cu")
		(at 192.65 144.45)
		(property "Reference" "Q17"
			(at 0 -1.6 0)
			(layer "F.SilkS")
			(hide yes)
			(effects
				(font
					(size 0.7 0.7)
					(thickness 0.15)
				)
				(justify left bottom)
			)
		)
		(property "Value" "BSS138PW,115"
			(at 0 2.3 0)
			(layer "F.Fab")
			(effects
				(font
					(size 0.7 0.7)
					(thickness 0.15)
				)
				(justify left bottom)
			)
		)
		(property "Datasheet" "https://assets.nexperia.com/documents/data-sheet/BSS138PW.pdf"
			(at 0 0 0)
			(layer "F.Fab")
			(hide yes)
			(effects
				(font
					(size 1.27 1.27)
					(thickness 0.15)
				)
			)
		)
		(property "Description" "Power MOSFET, N Channel, 60 V, 320 mA, 0.9 ohm, SOT-323, Surface Mount"
			(at 0 0 0)
			(layer "F.Fab")
			(hide yes)
			(effects
				(font
					(size 1.27 1.27)
					(thickness 0.15)
				)
			)
		)
		(property "Author" "Antmicro"
			(at 0 0 0)
			(layer "F.Fab")
			(hide yes)
			(effects
				(font
					(size 1 1)
					(thickness 0.15)
				)
			)
		)
		(property "License" "Apache-2.0"
			(at 0 0 0)
			(layer "F.Fab")
			(hide yes)
			(effects
				(font
					(size 1 1)
					(thickness 0.15)
				)
			)
		)
		(property "MPN" "BSS138PW,115"
			(at 0 0 0)
			(layer "F.Fab")
			(hide yes)
			(effects
				(font
					(size 1 1)
					(thickness 0.15)
				)
			)
		)
		(property "Manufacturer" "Nexperia"
			(at 0 0 0)
			(layer "F.Fab")
			(hide yes)
			(effects
				(font
					(size 1 1)
					(thickness 0.15)
				)
			)
		)
		(sheetname "/Supply/")
		(sheetfile "supply.kicad_sch")
		(attr smd)
		(fp_line
			(start -0.3 -1)
			(end 0.627 -0.999)
			(stroke
				(width 0.15)
				(type solid)
			)
			(layer "F.SilkS")
		)
		(fp_line
			(start -0.3 1)
			(end 0.627 1.001)
			(stroke
				(width 0.15)
				(type solid)
			)
			(layer "F.SilkS")
		)
		(fp_line
			(start 0.627 -0.6)
			(end 0.627 -0.999)
			(stroke
				(width 0.15)
				(type solid)
			)
			(layer "F.SilkS")
		)
		(fp_line
			(start 0.627 0.6)
			(end 0.627 1.001)
			(stroke
				(width 0.15)
				(type solid)
			)
			(layer "F.SilkS")
		)
		(fp_line
			(start -1.4 1)
			(end -1.4 -1)
			(stroke
				(width 0.05)
				(type solid)
			)
			(layer "F.CrtYd")
		)
		(fp_line
			(start -0.9 -1.3)
			(end -0.9 -1)
			(stroke
				(width 0.05)
				(type solid)
			)
			(layer "F.CrtYd")
		)
		(fp_line
			(start -0.9 -1.3)
			(end 0.9 -1.3)
			(stroke
				(width 0.05)
				(type solid)
			)
			(layer "F.CrtYd")
		)
		(fp_line
			(start -0.9 -1)
			(end -1.4 -1)
			(stroke
				(width 0.05)
				(type solid)
			)
			(layer "F.CrtYd")
		)
		(fp_line
			(start -0.9 1)
			(end -1.4 1)
			(stroke
				(width 0.05)
				(type solid)
			)
			(layer "F.CrtYd")
		)
		(fp_line
			(start -0.9 1.3)
			(end -0.9 1)
			(stroke
				(width 0.05)
				(type solid)
			)
			(layer "F.CrtYd")
		)
		(fp_line
			(start 0.9 -1.3)
			(end 0.9 -0.4)
			(stroke
				(width 0.05)
				(type solid)
			)
			(layer "F.CrtYd")
		)
		(fp_line
			(start 0.9 -0.4)
			(end 1.4 -0.4)
			(stroke
				(width 0.05)
				(type solid)
			)
			(layer "F.CrtYd")
		)
		(fp_line
			(start 0.9 0.4)
			(end 0.9 1.3)
			(stroke
				(width 0.05)
				(type solid)
			)
			(layer "F.CrtYd")
		)
		(fp_line
			(start 0.9 1.3)
			(end -0.9 1.3)
			(stroke
				(width 0.05)
				(type solid)
			)
			(layer "F.CrtYd")
		)
		(fp_line
			(start 1.4 -0.4)
			(end 1.4 0.4)
			(stroke
				(width 0.05)
				(type solid)
			)
			(layer "F.CrtYd")
		)
		(fp_line
			(start 1.4 0.4)
			(end 0.9 0.4)
			(stroke
				(width 0.05)
				(type solid)
			)
			(layer "F.CrtYd")
		)
		(fp_rect
			(start -0.623 -0.999)
			(end 0.627 1.001)
			(stroke
				(width 0.15)
				(type solid)
			)
			(fill no)
			(layer "F.Fab")
		)
		(pad "1" smd rect
			(at -1.051 -0.65 90)
			(size 0.6 0.6)
			(layers "F.Cu" "F.Mask" "F.Paste")
			(net 368 "Net-(Q17-G)")
			(pinfunction "G")
			(pintype "input")
		)
		(pad "2" smd rect
			(at -1.051 0.65 90)
			(size 0.6 0.6)
			(layers "F.Cu" "F.Mask" "F.Paste")
			(net 1 "GND")
			(pinfunction "S")
			(pintype "passive")
		)
		(pad "3" smd rect
			(at 1.05 0 90)
			(size 0.6 0.6)
			(layers "F.Cu" "F.Mask" "F.Paste")
			(net 62 "/Supply/SEQ_EN")
			(pinfunction "D")
			(pintype "passive")
		)
	)
	(footprint "antmicro-footprints:BarrelJack_Pin2mm_PJ-002AH"
		(layer "F.Cu")
		(at 192.883 128.135)
		(property "Reference" "J7"
			(at -0.4 -6.6 0)
			(layer "F.SilkS")
			(effects
				(font
					(size 0.7 0.7)
					(thickness 0.15)
				)
				(justify left bottom)
			)
		)
		(property "Value" "BarrelJack_Pin2mm_MJ-179PH"
			(at -1.85 6.5 0)
			(layer "F.Fab")
			(effects
				(font
					(size 0.7 0.7)
					(thickness 0.15)
				)
				(justify left bottom)
			)
		)
		(property "Datasheet" "https://www.cuidevices.com/product/resource/pj-002ah.pdf"
			(at 0 0 0)
			(layer "F.Fab")
			(hide yes)
			(effects
				(font
					(size 1.27 1.27)
					(thickness 0.15)
				)
			)
		)
		(property "Description" "Barrel power connector"
			(at 0 0 0)
			(layer "F.Fab")
			(hide yes)
			(effects
				(font
					(size 1.27 1.27)
					(thickness 0.15)
				)
			)
		)
		(property "MPN" "PJ-002AH"
			(at 0 0 0)
			(unlocked yes)
			(layer "F.Fab")
			(hide yes)
			(effects
				(font
					(size 1 1)
					(thickness 0.15)
				)
			)
		)
		(property "Manufacturer" "CUI Inc"
			(at 0 0 0)
			(unlocked yes)
			(layer "F.Fab")
			(hide yes)
			(effects
				(font
					(size 1 1)
					(thickness 0.15)
				)
			)
		)
		(property "Author" "Antmicro"
			(at 0 0 0)
			(unlocked yes)
			(layer "F.Fab")
			(hide yes)
			(effects
				(font
					(size 1 1)
					(thickness 0.15)
				)
			)
		)
		(property "License" "Apache-2.0"
			(at 0 0 0)
			(unlocked yes)
			(layer "F.Fab")
			(hide yes)
			(effects
				(font
					(size 1 1)
					(thickness 0.15)
				)
			)
		)
		(sheetname "/Supply/")
		(sheetfile "supply.kicad_sch")
		(attr through_hole)
		(fp_line
			(start -0.7 -4.55)
			(end 0.45 -4.55)
			(stroke
				(width 0.15)
				(type solid)
			)
			(layer "F.SilkS")
		)
		(fp_line
			(start -0.7 -2.6)
			(end -0.7 -4.55)
			(stroke
				(width 0.15)
				(type solid)
			)
			(layer "F.SilkS")
		)
		(fp_line
			(start -0.7 4.5)
			(end -0.7 2.65)
			(stroke
				(width 0.15)
				(type solid)
			)
			(layer "F.SilkS")
		)
		(fp_line
			(start 5.55 -4.5)
			(end 13.7 -4.5)
			(stroke
				(width 0.15)
				(type solid)
			)
			(layer "F.SilkS")
		)
		(fp_line
			(start 13.7 -4.5)
			(end 13.7 4.5)
			(stroke
				(width 0.15)
				(type solid)
			)
			(layer "F.SilkS")
		)
		(fp_line
			(start 13.7 4.5)
			(end -0.7 4.5)
			(stroke
				(width 0.15)
				(type solid)
			)
			(layer "F.SilkS")
		)
		(fp_circle
			(center -1.3 2.8)
			(end -1.2 2.9)
			(stroke
				(width 0.15)
				(type solid)
			)
			(fill yes)
			(layer "F.SilkS")
		)
		(fp_rect
			(start 14.1 5)
			(end -1.7 -6.2)
			(stroke
				(width 0.05)
				(type default)
			)
			(fill no)
			(layer "F.CrtYd")
		)
		(fp_line
			(start -0.7 -4.5)
			(end 13.7 -4.5)
			(stroke
				(width 0.15)
				(type solid)
			)
			(layer "F.Fab")
		)
		(fp_line
			(start -0.7 4.5)
			(end -0.7 -4.5)
			(stroke
				(width 0.15)
				(type solid)
			)
			(layer "F.Fab")
		)
		(fp_line
			(start 13.7 -4.5)
			(end 13.7 4.5)
			(stroke
				(width 0.15)
				(type solid)
			)
			(layer "F.Fab")
		)
		(fp_line
			(start 13.7 4.5)
			(end -0.7 4.5)
			(stroke
				(width 0.15)
				(type solid)
			)
			(layer "F.Fab")
		)
		(fp_circle
			(center -1.3 2.8)
			(end -1.159 2.8)
			(stroke
				(width 0.15)
				(type solid)
			)
			(fill yes)
			(layer "F.Fab")
		)
		(fp_text user "Author: Antmicro"
			(at -1.85 9.7 0)
			(layer "F.Fab")
			(effects
				(font
					(size 0.7 0.7)
					(thickness 0.15)
				)
				(justify left bottom)
			)
		)
		(fp_text user "License: Apache-2.0"
			(at -1.85 10.9 0)
			(layer "F.Fab")
			(effects
				(font
					(size 0.7 0.7)
					(thickness 0.15)
				)
				(justify left bottom)
			)
		)
		(fp_text user "${REFERENCE}"
			(at -1.85 8.5 0)
			(layer "F.Fab")
			(effects
				(font
					(size 0.7 0.7)
					(thickness 0.15)
				)
				(justify left bottom)
			)
		)
		(pad "1" thru_hole oval
			(at 0 0)
			(size 2.5 5)
			(drill oval 1 3.5)
			(layers "*.Cu" "*.Mask")
			(remove_unused_layers no)
			(net 597 "/Supply/12V_aux")
			(pintype "passive")
			(solder_mask_margin 0.102)
		)
		(pad "2" thru_hole oval
			(at 6 0)
			(size 2.25 4.5)
			(drill oval 1 3)
			(layers "*.Cu" "*.Mask")
			(remove_unused_layers no)
			(net 1 "GND")
			(pintype "passive")
			(solder_mask_margin 0.102)
		)
		(pad "3" thru_hole oval
			(at 3 -4.7)
			(size 4.5 2.25)
			(drill oval 3 1)
			(layers "*.Cu" "*.Mask")
			(remove_unused_layers no)
			(net 1 "GND")
			(pintype "passive")
			(solder_mask_margin 0.102)
		)
	)
	(footprint "antmicro-footprints:VSSOP-8_2.3x2mm_P0.5mm"
		(layer "F.Cu")
		(at 181.65 198.05)
		(property "Reference" "U23"
			(at -1.15 2.1 0)
			(layer "F.SilkS")
			(effects
				(font
					(size 0.7 0.7)
					(thickness 0.15)
				)
				(justify left bottom)
			)
		)
		(property "Value" "TS5A3359_VSSOP"
			(at 0 2.258 0)
			(layer "F.Fab")
			(effects
				(font
					(size 0.7 0.7)
					(thickness 0.15)
				)
				(justify left bottom)
			)
		)
		(property "Datasheet" "https://www.ti.com/general/docs/suppproductinfo.tsp?distId=26&gotoUrl=http%3A%2F%2Fwww.ti.com%2Flit%2Fgpn%2Fts5a3359"
			(at 0 0 0)
			(layer "F.Fab")
			(hide yes)
			(effects
				(font
					(size 1.27 1.27)
					(thickness 0.15)
				)
			)
		)
		(property "Author" "Antmicro"
			(at 0 0 0)
			(layer "F.Fab")
			(hide yes)
			(effects
				(font
					(size 1 1)
					(thickness 0.15)
				)
			)
		)
		(property "License" "Apache-2.0"
			(at 0 0 0)
			(layer "F.Fab")
			(hide yes)
			(effects
				(font
					(size 1 1)
					(thickness 0.15)
				)
			)
		)
		(property "MPN" "TS5A3359DCUR"
			(at 0 0 0)
			(layer "F.Fab")
			(hide yes)
			(effects
				(font
					(size 1 1)
					(thickness 0.15)
				)
			)
		)
		(property "Manufacturer" "Texas Instruments"
			(at 0 0 0)
			(layer "F.Fab")
			(hide yes)
			(effects
				(font
					(size 1 1)
					(thickness 0.15)
				)
			)
		)
		(sheetname "/I^{2}C/")
		(sheetfile "i2c.kicad_sch")
		(attr smd)
		(fp_line
			(start -0.82 -0.992)
			(end 0.825 -0.992)
			(stroke
				(width 0.15)
				(type solid)
			)
			(layer "F.SilkS")
		)
		(fp_line
			(start 0.825 1.007)
			(end -0.82 1.007)
			(stroke
				(width 0.15)
				(type solid)
			)
			(layer "F.SilkS")
		)
		(fp_circle
			(center -1.402 -1.192)
			(end -1.352 -1.192)
			(stroke
				(width 0.15)
				(type solid)
			)
			(fill yes)
			(layer "F.SilkS")
		)
		(fp_rect
			(start 1.8 1.35)
			(end -1.8 -1.35)
			(stroke
				(width 0.05)
				(type solid)
			)
			(fill no)
			(layer "F.CrtYd")
		)
		(fp_line
			(start -0.7 -0.99)
			(end -1.14 -0.55)
			(stroke
				(width 0.15)
				(type solid)
			)
			(layer "F.Fab")
		)
		(fp_rect
			(start -1.147 -0.992)
			(end 1.151 1.007)
			(stroke
				(width 0.15)
				(type solid)
			)
			(fill no)
			(layer "F.Fab")
		)
		(pad "1" smd rect
			(at -1.372 -0.742)
			(size 0.75 0.4)
			(layers "F.Cu" "F.Mask" "F.Paste")
			(net 683 "/FPGA bank 14/FPGA_DDR.SDA")
			(pinfunction "NO1")
			(pintype "passive")
		)
		(pad "2" smd rect
			(at -1.372 -0.244)
			(size 0.75 0.3)
			(layers "F.Cu" "F.Mask" "F.Paste")
			(net 688 "/FPGA bank 14/FPGA_PWR.SDA")
			(pinfunction "NO2")
			(pintype "passive")
		)
		(pad "3" smd rect
			(at -1.372 0.256)
			(size 0.75 0.3)
			(layers "F.Cu" "F.Mask" "F.Paste")
			(net 672 "/Debug FTDI/FTDI.SDA")
			(pinfunction "NO3")
			(pintype "passive")
		)
		(pad "4" smd rect
			(at -1.372 0.757)
			(size 0.75 0.4)
			(layers "F.Cu" "F.Mask" "F.Paste")
			(net 1 "GND")
			(pinfunction "GND")
			(pintype "passive")
		)
		(pad "5" smd rect
			(at 1.377 0.757)
			(size 0.75 0.4)
			(layers "F.Cu" "F.Mask" "F.Paste")
			(net 687 "IN2")
			(pinfunction "IN2")
			(pintype "passive")
		)
		(pad "6" smd rect
			(at 1.377 0.256)
			(size 0.75 0.3)
			(layers "F.Cu" "F.Mask" "F.Paste")
			(net 686 "IN1")
			(pinfunction "IN1")
			(pintype "passive")
		)
		(pad "7" smd rect
			(at 1.377 -0.244)
			(size 0.75 0.3)
			(layers "F.Cu" "F.Mask" "F.Paste")
			(net 690 "/I^{2}C/PWR.SDA")
			(pinfunction "COM")
			(pintype "passive")
		)
		(pad "8" smd rect
			(at 1.377 -0.742)
			(size 0.75 0.4)
			(layers "F.Cu" "F.Mask" "F.Paste")
			(net 41 "+3V3_AON")
			(pinfunction "VCC")
			(pintype "passive")
		)
	)
	(footprint "antmicro-footprints:R_0402_1005Metric"
		(layer "F.Cu")
		(at 98.360501 146.556)
		(descr "Resistor SMD 0402")
		(tags "resistor SMD 0402")
		(property "Reference" "R123"
			(at -1.122484 -0.772697 0)
			(layer "F.SilkS")
			(hide yes)
			(effects
				(font
					(size 0.7 0.7)
					(thickness 0.15)
				)
				(justify left bottom)
			)
		)
		(property "Value" "R_4k7_0402"
			(at -1.011843 1.772047 0)
			(layer "F.Fab")
			(effects
				(font
					(size 0.7 0.7)
					(thickness 0.15)
				)
				(justify left bottom)
			)
		)
		(property "Datasheet" "https://www.bourns.com/docs/product-datasheets/cr.pdf"
			(at 0 0 0)
			(layer "F.Fab")
			(hide yes)
			(effects
				(font
					(size 1.27 1.27)
					(thickness 0.15)
				)
			)
		)
		(property "Author" "Antmicro"
			(at 0 0 0)
			(layer "F.Fab")
			(hide yes)
			(effects
				(font
					(size 1 1)
					(thickness 0.15)
				)
			)
		)
		(property "License" "Apache-2.0"
			(at 0 0 0)
			(layer "F.Fab")
			(hide yes)
			(effects
				(font
					(size 1 1)
					(thickness 0.15)
				)
			)
		)
		(property "MPN" "CR0402-FX-4701GLF"
			(at 0 0 0)
			(layer "F.Fab")
			(hide yes)
			(effects
				(font
					(size 1 1)
					(thickness 0.15)
				)
			)
		)
		(property "Manufacturer" "Bourns"
			(at 0 0 0)
			(layer "F.Fab")
			(hide yes)
			(effects
				(font
					(size 1 1)
					(thickness 0.15)
				)
			)
		)
		(property "Tolerance" "1%"
			(at 0 0 0)
			(layer "F.Fab")
			(hide yes)
			(effects
				(font
					(size 1 1)
					(thickness 0.15)
				)
			)
		)
		(property "Val" "4k7"
			(at 0 0 0)
			(layer "F.Fab")
			(hide yes)
			(effects
				(font
					(size 1 1)
					(thickness 0.15)
				)
			)
		)
		(sheetname "/I^{2}C/")
		(sheetfile "i2c.kicad_sch")
		(attr smd)
		(fp_rect
			(start -0.93 -0.47)
			(end 0.93 0.47)
			(stroke
				(width 0.05)
				(type solid)
			)
			(fill no)
			(layer "F.CrtYd")
		)
		(fp_rect
			(start -0.5 -0.25)
			(end 0.5 0.25)
			(stroke
				(width 0.15)
				(type solid)
			)
			(fill no)
			(layer "F.Fab")
		)
		(pad "1" smd roundrect
			(at -0.485 0)
			(size 0.59 0.64)
			(layers "F.Cu" "F.Mask" "F.Paste")
			(roundrect_rratio 0.25)
			(net 200 "+3V3")
			(pintype "passive")
		)
		(pad "2" smd roundrect
			(at 0.485 0)
			(size 0.59 0.64)
			(layers "F.Cu" "F.Mask" "F.Paste")
			(roundrect_rratio 0.25)
			(net 683 "/FPGA bank 14/FPGA_DDR.SDA")
			(pintype "passive")
		)
	)
	(footprint "antmicro-footprints:C_0402_1005Metric"
		(layer "F.Cu")
		(at 177.219502 192.714502 -90)
		(descr "Capacitor SMD 0402")
		(tags "capacitor SMD 0402")
		(property "Reference" "C210"
			(at 0 -0.699 270)
			(layer "F.SilkS")
			(hide yes)
			(effects
				(font
					(size 0.7 0.7)
					(thickness 0.15)
				)
				(justify left bottom)
			)
		)
		(property "Value" "C_22n_0402"
			(at -1.022927 2.155213 270)
			(layer "F.Fab")
			(effects
				(font
					(size 0.7 0.7)
					(thickness 0.15)
				)
				(justify left bottom)
			)
		)
		(property "Datasheet" "https://www.murata.com/products/productdetail?partno=GCM155R71H223MA55%23"
			(at 0 0 270)
			(layer "F.Fab")
			(hide yes)
			(effects
				(font
					(size 1.27 1.27)
					(thickness 0.15)
				)
			)
		)
		(property "Author" "Antmicro"
			(at -15.495 369.934004 0)
			(layer "F.Fab")
			(hide yes)
			(effects
				(font
					(size 1 1)
					(thickness 0.15)
				)
			)
		)
		(property "Dielectric" ""
			(at -15.495 369.934004 0)
			(layer "F.Fab")
			(hide yes)
			(effects
				(font
					(size 1 1)
					(thickness 0.15)
				)
			)
		)
		(property "License" "Apache-2.0"
			(at -15.495 369.934004 0)
			(layer "F.Fab")
			(hide yes)
			(effects
				(font
					(size 1 1)
					(thickness 0.15)
				)
			)
		)
		(property "MPN" "GCM155R71H223MA55D"
			(at -15.495 369.934004 0)
			(layer "F.Fab")
			(hide yes)
			(effects
				(font
					(size 1 1)
					(thickness 0.15)
				)
			)
		)
		(property "Manufacturer" "Murata"
			(at -15.495 369.934004 0)
			(layer "F.Fab")
			(hide yes)
			(effects
				(font
					(size 1 1)
					(thickness 0.15)
				)
			)
		)
		(property "Val" "22n"
			(at -15.495 369.934004 0)
			(layer "F.Fab")
			(hide yes)
			(effects
				(font
					(size 1 1)
					(thickness 0.15)
				)
			)
		)
		(property "Voltage" ""
			(at -15.495 369.934004 0)
			(layer "F.Fab")
			(hide yes)
			(effects
				(font
					(size 1 1)
					(thickness 0.15)
				)
			)
		)
		(sheetname "/Supply/")
		(sheetfile "supply.kicad_sch")
		(attr smd)
		(fp_rect
			(start -0.9659 -0.481258)
			(end 0.9649 0.458742)
			(stroke
				(width 0.05)
				(type solid)
			)
			(fill no)
			(layer "F.CrtYd")
		)
		(fp_line
			(start -0.499 0.248)
			(end -0.499 -0.25)
			(stroke
				(width 0.15)
				(type solid)
			)
			(layer "F.Fab")
		)
		(fp_line
			(start 0.499 0.248)
			(end -0.499 0.248)
			(stroke
				(width 0.15)
				(type solid)
			)
			(layer "F.Fab")
		)
		(fp_line
			(start -0.499 -0.25)
			(end 0.499 -0.25)
			(stroke
				(width 0.15)
				(type solid)
			)
			(layer "F.Fab")
		)
		(fp_line
			(start 0.499 -0.25)
			(end 0.499 0.248)
			(stroke
				(width 0.15)
				(type solid)
			)
			(layer "F.Fab")
		)
		(pad "1" smd roundrect
			(at -0.484 0 270)
			(size 0.59 0.64)
			(layers "F.Cu" "F.Mask" "F.Paste")
			(roundrect_rratio 0.25)
			(net 1 "GND")
			(pintype "passive")
		)
		(pad "2" smd roundrect
			(at 0.484 0 270)
			(size 0.59 0.64)
			(layers "F.Cu" "F.Mask" "F.Paste")
			(roundrect_rratio 0.25)
			(net 75 "/Supply/1V0_SS")
			(pintype "passive")
		)
	)
	(footprint "antmicro-footprints:Mech_Lightpipe_Mentor_1296.2013"
		(layer "F.Cu")
		(at 76.060501 126.276 90)
		(property "Reference" "H2"
			(at 0 -0.5 180)
			(unlocked yes)
			(layer "F.SilkS")
			(hide yes)
			(effects
				(font
					(size 0.7 0.7)
					(thickness 0.15)
				)
				(justify left bottom)
			)
		)
		(property "Value" "Lightpipe_Mentor_1296.2013"
			(at -1.75 6.25 90)
			(unlocked yes)
			(layer "F.Fab")
			(effects
				(font
					(size 0.7 0.7)
					(thickness 0.15)
				)
				(justify left bottom)
			)
		)
		(property "Datasheet" "https://docs.rs-online.com/e47b/0900766b813f6efb.pdf"
			(at 0 0 90)
			(layer "F.Fab")
			(hide yes)
			(effects
				(font
					(size 1.27 1.27)
					(thickness 0.15)
				)
			)
		)
		(property "Author" "Antmicro"
			(at 202.336501 50.215499 0)
			(layer "F.Fab")
			(hide yes)
			(effects
				(font
					(size 1 1)
					(thickness 0.15)
				)
			)
		)
		(property "License" "Apache-2.0"
			(at 202.336501 50.215499 0)
			(layer "F.Fab")
			(hide yes)
			(effects
				(font
					(size 1 1)
					(thickness 0.15)
				)
			)
		)
		(property "MPN" "1296.2013"
			(at 202.336501 50.215499 0)
			(layer "F.Fab")
			(hide yes)
			(effects
				(font
					(size 1 1)
					(thickness 0.15)
				)
			)
		)
		(property "Manufacturer" "Mentor Worldwide"
			(at 202.336501 50.215499 0)
			(layer "F.Fab")
			(hide yes)
			(effects
				(font
					(size 1 1)
					(thickness 0.15)
				)
			)
		)
		(sheetname "/")
		(sheetfile "sodimm-ddr5-tester.kicad_sch")
		(fp_rect
			(start -1.508 -6.335)
			(end 1.507 5.289)
			(stroke
				(width 0.15)
				(type solid)
			)
			(fill no)
			(layer "F.SilkS")
		)
		(pad "" np_thru_hole circle
			(at 0 -4.96 90)
			(size 1.2 1.2)
			(drill 1.2)
			(layers "*.Cu" "*.Mask")
		)
		(pad "" np_thru_hole circle
			(at 0 4.24 90)
			(size 1.2 1.2)
			(drill 1.2)
			(layers "*.Cu" "*.Mask")
		)
	)
	(footprint "antmicro-footprints:R_0402_1005Metric"
		(layer "F.Cu")
		(at 77.7 157.5)
		(descr "Resistor SMD 0402")
		(tags "resistor SMD 0402")
		(property "Reference" "R69"
			(at -1.122484 -0.772697 0)
			(layer "F.SilkS")
			(hide yes)
			(effects
				(font
					(size 0.7 0.7)
					(thickness 0.15)
				)
				(justify left bottom)
			)
		)
		(property "Value" "R_5k11_0402"
			(at -1.011843 1.772047 0)
			(layer "F.Fab")
			(effects
				(font
					(size 0.7 0.7)
					(thickness 0.15)
				)
				(justify left bottom)
			)
		)
		(property "Datasheet" "https://www.bourns.com/docs/product-datasheets/cr.pdf"
			(at 0 0 0)
			(layer "F.Fab")
			(hide yes)
			(effects
				(font
					(size 1.27 1.27)
					(thickness 0.15)
				)
			)
		)
		(property "Author" "Antmicro"
			(at 0 0 0)
			(layer "F.Fab")
			(hide yes)
			(effects
				(font
					(size 1 1)
					(thickness 0.15)
				)
			)
		)
		(property "License" "Apache-2.0"
			(at 0 0 0)
			(layer "F.Fab")
			(hide yes)
			(effects
				(font
					(size 1 1)
					(thickness 0.15)
				)
			)
		)
		(property "MPN" "CR0402-FX-5111GLF"
			(at 0 0 0)
			(layer "F.Fab")
			(hide yes)
			(effects
				(font
					(size 1 1)
					(thickness 0.15)
				)
			)
		)
		(property "Manufacturer" "Bourns"
			(at 0 0 0)
			(layer "F.Fab")
			(hide yes)
			(effects
				(font
					(size 1 1)
					(thickness 0.15)
				)
			)
		)
		(property "Tolerance" "1%"
			(at 0 0 0)
			(layer "F.Fab")
			(hide yes)
			(effects
				(font
					(size 1 1)
					(thickness 0.15)
				)
			)
		)
		(property "Val" "5k11"
			(at 0 0 0)
			(layer "F.Fab")
			(hide yes)
			(effects
				(font
					(size 1 1)
					(thickness 0.15)
				)
			)
		)
		(sheetname "/Debug FTDI/")
		(sheetfile "debug-ftdi.kicad_sch")
		(attr smd)
		(fp_rect
			(start -0.93 -0.47)
			(end 0.93 0.47)
			(stroke
				(width 0.05)
				(type solid)
			)
			(fill no)
			(layer "F.CrtYd")
		)
		(fp_rect
			(start -0.5 -0.25)
			(end 0.5 0.25)
			(stroke
				(width 0.15)
				(type solid)
			)
			(fill no)
			(layer "F.Fab")
		)
		(pad "1" smd roundrect
			(at -0.485 0)
			(size 0.59 0.64)
			(layers "F.Cu" "F.Mask" "F.Paste")
			(roundrect_rratio 0.25)
			(net 323 "Net-(J3-CC_{2})")
			(pintype "passive")
		)
		(pad "2" smd roundrect
			(at 0.485 0)
			(size 0.59 0.64)
			(layers "F.Cu" "F.Mask" "F.Paste")
			(roundrect_rratio 0.25)
			(net 1 "GND")
			(pintype "passive")
		)
	)
	(footprint "antmicro-footprints:R_1206_3216Metric"
		(layer "F.Cu")
		(at 199.051501 159.699 180)
		(property "Reference" "R147"
			(at 5.101501 -1.001 180)
			(layer "F.SilkS")
			(effects
				(font
					(size 0.7 0.7)
					(thickness 0.15)
				)
				(justify left bottom)
			)
		)
		(property "Value" "R_0R01_1206"
			(at -2.422356 2.103591 180)
			(layer "F.Fab")
			(effects
				(font
					(size 0.7 0.7)
					(thickness 0.15)
				)
				(justify left bottom)
			)
		)
		(property "Datasheet" "https://www.yageo.com/upload/media/product/productsearch/datasheet/rchip/PYu-RL_Group_521_RoHS_L_2.pdf"
			(at 0 0 180)
			(layer "F.Fab")
			(hide yes)
			(effects
				(font
					(size 1.27 1.27)
					(thickness 0.15)
				)
			)
		)
		(property "Author" "Antmicro"
			(at 398.103002 319.398 0)
			(layer "F.Fab")
			(hide yes)
			(effects
				(font
					(size 1 1)
					(thickness 0.15)
				)
			)
		)
		(property "License" "Apache-2.0"
			(at 398.103002 319.398 0)
			(layer "F.Fab")
			(hide yes)
			(effects
				(font
					(size 1 1)
					(thickness 0.15)
				)
			)
		)
		(property "MPN" "RL1206FR-7W0R01L"
			(at 398.103002 319.398 0)
			(layer "F.Fab")
			(hide yes)
			(effects
				(font
					(size 1 1)
					(thickness 0.15)
				)
			)
		)
		(property "Manufacturer" "YAGEO"
			(at 398.103002 319.398 0)
			(layer "F.Fab")
			(hide yes)
			(effects
				(font
					(size 1 1)
					(thickness 0.15)
				)
			)
		)
		(property "Tolerance" "1%"
			(at 398.103002 319.398 0)
			(layer "F.Fab")
			(hide yes)
			(effects
				(font
					(size 1 1)
					(thickness 0.15)
				)
			)
		)
		(property "Val" "0R01"
			(at 398.103002 319.398 0)
			(layer "F.Fab")
			(hide yes)
			(effects
				(font
					(size 1 1)
					(thickness 0.15)
				)
			)
		)
		(sheetname "/Supply/")
		(sheetfile "supply.kicad_sch")
		(attr smd)
		(fp_line
			(start 0 0.9)
			(end 0.498 0.9)
			(stroke
				(width 0.15)
				(type solid)
			)
			(layer "F.SilkS")
		)
		(fp_line
			(start 0 0.9)
			(end -0.5 0.9)
			(stroke
				(width 0.15)
				(type solid)
			)
			(layer "F.SilkS")
		)
		(fp_line
			(start 0 -0.902)
			(end 0.498 -0.902)
			(stroke
				(width 0.15)
				(type solid)
			)
			(layer "F.SilkS")
		)
		(fp_line
			(start 0 -0.902)
			(end -0.5 -0.902)
			(stroke
				(width 0.15)
				(type solid)
			)
			(layer "F.SilkS")
		)
		(fp_rect
			(start -2.25 -1.05)
			(end 2.25 1.05)
			(stroke
				(width 0.05)
				(type solid)
			)
			(fill no)
			(layer "F.CrtYd")
		)
		(fp_line
			(start 1.6 -0.802)
			(end 1.6 0.8)
			(stroke
				(width 0.15)
				(type solid)
			)
			(layer "F.Fab")
		)
		(fp_line
			(start -1.601 0.8)
			(end 1.6 0.8)
			(stroke
				(width 0.15)
				(type solid)
			)
			(layer "F.Fab")
		)
		(fp_line
			(start -1.601 -0.802)
			(end 1.6 -0.802)
			(stroke
				(width 0.15)
				(type solid)
			)
			(layer "F.Fab")
		)
		(fp_line
			(start -1.601 -0.802)
			(end -1.601 0.8)
			(stroke
				(width 0.15)
				(type solid)
			)
			(layer "F.Fab")
		)
		(pad "1" smd roundrect
			(at -1.5 0 180)
			(size 1.2 1.8)
			(layers "F.Cu" "F.Mask" "F.Paste")
			(roundrect_rratio 0.15)
			(net 53 "/Supply/1V1_local")
			(pintype "passive")
		)
		(pad "2" smd roundrect
			(at 1.499 0 180)
			(size 1.2 1.8)
			(layers "F.Cu" "F.Mask" "F.Paste")
			(roundrect_rratio 0.15)
			(net 206 "+1V1")
			(pintype "passive")
		)
	)
	(footprint "antmicro-footprints:C_0402_1005Metric"
		(layer "F.Cu")
		(at 195.15 193.075)
		(descr "Capacitor SMD 0402")
		(tags "capacitor SMD 0402")
		(property "Reference" "C206"
			(at 0 -0.699 0)
			(layer "F.SilkS")
			(hide yes)
			(effects
				(font
					(size 0.7 0.7)
					(thickness 0.15)
				)
				(justify left bottom)
			)
		)
		(property "Value" "C_1u_0402"
			(at -1.022927 2.155213 0)
			(layer "F.Fab")
			(effects
				(font
					(size 0.7 0.7)
					(thickness 0.15)
				)
				(justify left bottom)
			)
		)
		(property "Datasheet" "https://product.tdk.com/en/search/capacitor/ceramic/mlcc/info?part_no=C1005X6S1A105K050BC"
			(at 0 0 0)
			(layer "F.Fab")
			(hide yes)
			(effects
				(font
					(size 1.27 1.27)
					(thickness 0.15)
				)
			)
		)
		(property "Author" "Antmicro"
			(at 0 0 0)
			(layer "F.Fab")
			(hide yes)
			(effects
				(font
					(size 1 1)
					(thickness 0.15)
				)
			)
		)
		(property "Dielectric" ""
			(at 0 0 0)
			(layer "F.Fab")
			(hide yes)
			(effects
				(font
					(size 1 1)
					(thickness 0.15)
				)
			)
		)
		(property "License" "Apache-2.0"
			(at 0 0 0)
			(layer "F.Fab")
			(hide yes)
			(effects
				(font
					(size 1 1)
					(thickness 0.15)
				)
			)
		)
		(property "MPN" "C1005X6S1A105K050BC"
			(at 0 0 0)
			(layer "F.Fab")
			(hide yes)
			(effects
				(font
					(size 1 1)
					(thickness 0.15)
				)
			)
		)
		(property "Manufacturer" "TDK"
			(at 0 0 0)
			(layer "F.Fab")
			(hide yes)
			(effects
				(font
					(size 1 1)
					(thickness 0.15)
				)
			)
		)
		(property "Val" "1u"
			(at 0 0 0)
			(layer "F.Fab")
			(hide yes)
			(effects
				(font
					(size 1 1)
					(thickness 0.15)
				)
			)
		)
		(property "Voltage" ""
			(at 0 0 0)
			(layer "F.Fab")
			(hide yes)
			(effects
				(font
					(size 1 1)
					(thickness 0.15)
				)
			)
		)
		(sheetname "/Supply/")
		(sheetfile "supply.kicad_sch")
		(attr smd)
		(fp_rect
			(start -0.9659 -0.481258)
			(end 0.9649 0.458742)
			(stroke
				(width 0.05)
				(type solid)
			)
			(fill no)
			(layer "F.CrtYd")
		)
		(fp_line
			(start -0.499 -0.25)
			(end 0.499 -0.25)
			(stroke
				(width 0.15)
				(type solid)
			)
			(layer "F.Fab")
		)
		(fp_line
			(start -0.499 0.248)
			(end -0.499 -0.25)
			(stroke
				(width 0.15)
				(type solid)
			)
			(layer "F.Fab")
		)
		(fp_line
			(start 0.499 -0.25)
			(end 0.499 0.248)
			(stroke
				(width 0.15)
				(type solid)
			)
			(layer "F.Fab")
		)
		(fp_line
			(start 0.499 0.248)
			(end -0.499 0.248)
			(stroke
				(width 0.15)
				(type solid)
			)
			(layer "F.Fab")
		)
		(pad "1" smd roundrect
			(at -0.484 0)
			(size 0.59 0.64)
			(layers "F.Cu" "F.Mask" "F.Paste")
			(roundrect_rratio 0.25)
			(net 1 "GND")
			(pintype "passive")
		)
		(pad "2" smd roundrect
			(at 0.484 0)
			(size 0.59 0.64)
			(layers "F.Cu" "F.Mask" "F.Paste")
			(roundrect_rratio 0.25)
			(net 64 "/Supply/1V7")
			(pintype "passive")
		)
	)
	(footprint "antmicro-footprints:C_0603_1608Metric"
		(layer "F.Cu")
		(at 192.668501 165.472 90)
		(descr "Capacitor SMD 0603")
		(tags "capacitor 0603")
		(property "Reference" "C185"
			(at -1.42757 -1.000252 90)
			(layer "F.SilkS")
			(hide yes)
			(effects
				(font
					(size 0.7 0.7)
					(thickness 0.15)
				)
				(justify left bottom)
			)
		)
		(property "Value" "C_22u_0603"
			(at -1.42757 1.770288 90)
			(layer "F.Fab")
			(effects
				(font
					(size 0.7 0.7)
					(thickness 0.15)
				)
				(justify left bottom)
			)
		)
		(property "Datasheet" "https://www.murata.com/products/productdetail?partno=GRM188R60J226MEA0%23"
			(at 0 0 90)
			(layer "F.Fab")
			(hide yes)
			(effects
				(font
					(size 1.27 1.27)
					(thickness 0.15)
				)
			)
		)
		(property "Author" "Antmicro"
			(at 358.140501 -27.196501 0)
			(layer "F.Fab")
			(hide yes)
			(effects
				(font
					(size 1 1)
					(thickness 0.15)
				)
			)
		)
		(property "Dielectric" ""
			(at 358.140501 -27.196501 0)
			(layer "F.Fab")
			(hide yes)
			(effects
				(font
					(size 1 1)
					(thickness 0.15)
				)
			)
		)
		(property "License" "Apache-2.0"
			(at 358.140501 -27.196501 0)
			(layer "F.Fab")
			(hide yes)
			(effects
				(font
					(size 1 1)
					(thickness 0.15)
				)
			)
		)
		(property "MPN" "GRM188R60J226MEA0D"
			(at 358.140501 -27.196501 0)
			(layer "F.Fab")
			(hide yes)
			(effects
				(font
					(size 1 1)
					(thickness 0.15)
				)
			)
		)
		(property "Manufacturer" "Murata"
			(at 358.140501 -27.196501 0)
			(layer "F.Fab")
			(hide yes)
			(effects
				(font
					(size 1 1)
					(thickness 0.15)
				)
			)
		)
		(property "Val" "22u"
			(at 358.140501 -27.196501 0)
			(layer "F.Fab")
			(hide yes)
			(effects
				(font
					(size 1 1)
					(thickness 0.15)
				)
			)
		)
		(property "Voltage" ""
			(at 358.140501 -27.196501 0)
			(layer "F.Fab")
			(hide yes)
			(effects
				(font
					(size 1 1)
					(thickness 0.15)
				)
			)
		)
		(sheetname "/Supply/")
		(sheetfile "supply.kicad_sch")
		(attr smd)
		(fp_line
			(start -0.3 -0.3)
			(end 0.3 -0.3)
			(stroke
				(width 0.15)
				(type solid)
			)
			(layer "F.SilkS")
		)
		(fp_line
			(start -0.3 0.3)
			(end 0.3 0.3)
			(stroke
				(width 0.15)
				(type solid)
			)
			(layer "F.SilkS")
		)
		(fp_rect
			(start -1.24 -0.7)
			(end 1.24 0.7)
			(stroke
				(width 0.05)
				(type solid)
			)
			(fill no)
			(layer "F.CrtYd")
		)
		(fp_rect
			(start -0.8 -0.4)
			(end 0.8 0.4)
			(stroke
				(width 0.15)
				(type solid)
			)
			(fill no)
			(layer "F.Fab")
		)
		(pad "1" smd roundrect
			(at -0.7 0 90)
			(size 0.6 0.8)
			(layers "F.Cu" "F.Mask" "F.Paste")
			(roundrect_rratio 0.2)
			(net 1 "GND")
			(pintype "passive")
		)
		(pad "2" smd roundrect
			(at 0.7 0 90)
			(size 0.6 0.8)
			(layers "F.Cu" "F.Mask" "F.Paste")
			(roundrect_rratio 0.2)
			(net 60 "/Supply/5V_local")
			(pintype "passive")
		)
	)
	(footprint "antmicro-footprints:R_0402_1005Metric"
		(layer "F.Cu")
		(at 180.915 128.2)
		(descr "Resistor SMD 0402")
		(tags "resistor SMD 0402")
		(property "Reference" "R78"
			(at -1.122484 -0.772697 0)
			(layer "F.SilkS")
			(hide yes)
			(effects
				(font
					(size 0.7 0.7)
					(thickness 0.15)
				)
				(justify left bottom)
			)
		)
		(property "Value" "R_4k7_0402"
			(at -1.011843 1.772047 0)
			(layer "F.Fab")
			(effects
				(font
					(size 0.7 0.7)
					(thickness 0.15)
				)
				(justify left bottom)
			)
		)
		(property "Datasheet" "https://www.bourns.com/docs/product-datasheets/cr.pdf"
			(at 0 0 0)
			(layer "F.Fab")
			(hide yes)
			(effects
				(font
					(size 1.27 1.27)
					(thickness 0.15)
				)
			)
		)
		(property "Author" "Antmicro"
			(at 0 0 0)
			(layer "F.Fab")
			(hide yes)
			(effects
				(font
					(size 1 1)
					(thickness 0.15)
				)
			)
		)
		(property "License" "Apache-2.0"
			(at 0 0 0)
			(layer "F.Fab")
			(hide yes)
			(effects
				(font
					(size 1 1)
					(thickness 0.15)
				)
			)
		)
		(property "MPN" "CR0402-FX-4701GLF"
			(at 0 0 0)
			(layer "F.Fab")
			(hide yes)
			(effects
				(font
					(size 1 1)
					(thickness 0.15)
				)
			)
		)
		(property "Manufacturer" "Bourns"
			(at 0 0 0)
			(layer "F.Fab")
			(hide yes)
			(effects
				(font
					(size 1 1)
					(thickness 0.15)
				)
			)
		)
		(property "Tolerance" "1%"
			(at 0 0 0)
			(layer "F.Fab")
			(hide yes)
			(effects
				(font
					(size 1 1)
					(thickness 0.15)
				)
			)
		)
		(property "Val" "4k7"
			(at 0 0 0)
			(layer "F.Fab")
			(hide yes)
			(effects
				(font
					(size 1 1)
					(thickness 0.15)
				)
			)
		)
		(sheetname "/DDR5 SODIMM/")
		(sheetfile "ddr5-sodimm.kicad_sch")
		(attr smd)
		(fp_rect
			(start -0.93 -0.47)
			(end 0.93 0.47)
			(stroke
				(width 0.05)
				(type solid)
			)
			(fill no)
			(layer "F.CrtYd")
		)
		(fp_rect
			(start -0.5 -0.25)
			(end 0.5 0.25)
			(stroke
				(width 0.15)
				(type solid)
			)
			(fill no)
			(layer "F.Fab")
		)
		(pad "1" smd roundrect
			(at -0.485 0)
			(size 0.59 0.64)
			(layers "F.Cu" "F.Mask" "F.Paste")
			(roundrect_rratio 0.25)
			(net 200 "+3V3")
			(pintype "passive")
		)
		(pad "2" smd roundrect
			(at 0.485 0)
			(size 0.59 0.64)
			(layers "F.Cu" "F.Mask" "F.Paste")
			(roundrect_rratio 0.25)
			(net 106 "HOT_SWAP_BUTTON")
			(pintype "passive")
		)
	)
	(footprint "antmicro-footprints:SC70-3"
		(layer "F.Cu")
		(at 94.750501 129.249 90)
		(property "Reference" "Q2"
			(at 0 -1.6 90)
			(layer "F.SilkS")
			(hide yes)
			(effects
				(font
					(size 0.7 0.7)
					(thickness 0.15)
				)
				(justify left bottom)
			)
		)
		(property "Value" "BSS138PW,115"
			(at 0 2.3 90)
			(layer "F.Fab")
			(effects
				(font
					(size 0.7 0.7)
					(thickness 0.15)
				)
				(justify left bottom)
			)
		)
		(property "Datasheet" "https://assets.nexperia.com/documents/data-sheet/BSS138PW.pdf"
			(at 0 0 90)
			(layer "F.Fab")
			(hide yes)
			(effects
				(font
					(size 1.27 1.27)
					(thickness 0.15)
				)
			)
		)
		(property "Description" "Power MOSFET, N Channel, 60 V, 320 mA, 0.9 ohm, SOT-323, Surface Mount"
			(at 0 0 90)
			(layer "F.Fab")
			(hide yes)
			(effects
				(font
					(size 1.27 1.27)
					(thickness 0.15)
				)
			)
		)
		(property "Author" "Antmicro"
			(at 223.999501 34.498499 0)
			(layer "F.Fab")
			(hide yes)
			(effects
				(font
					(size 1 1)
					(thickness 0.15)
				)
			)
		)
		(property "License" "Apache-2.0"
			(at 223.999501 34.498499 0)
			(layer "F.Fab")
			(hide yes)
			(effects
				(font
					(size 1 1)
					(thickness 0.15)
				)
			)
		)
		(property "MPN" "BSS138PW,115"
			(at 223.999501 34.498499 0)
			(layer "F.Fab")
			(hide yes)
			(effects
				(font
					(size 1 1)
					(thickness 0.15)
				)
			)
		)
		(property "Manufacturer" "Nexperia"
			(at 223.999501 34.498499 0)
			(layer "F.Fab")
			(hide yes)
			(effects
				(font
					(size 1 1)
					(thickness 0.15)
				)
			)
		)
		(sheetname "/FPGA Config/")
		(sheetfile "fpga-config.kicad_sch")
		(attr smd)
		(fp_line
			(start -0.3 -1)
			(end 0.627 -0.999)
			(stroke
				(width 0.15)
				(type solid)
			)
			(layer "F.SilkS")
		)
		(fp_line
			(start 0.627 -0.6)
			(end 0.627 -0.999)
			(stroke
				(width 0.15)
				(type solid)
			)
			(layer "F.SilkS")
		)
		(fp_line
			(start 0.627 0.6)
			(end 0.627 1.001)
			(stroke
				(width 0.15)
				(type solid)
			)
			(layer "F.SilkS")
		)
		(fp_line
			(start -0.3 1)
			(end 0.627 1.001)
			(stroke
				(width 0.15)
				(type solid)
			)
			(layer "F.SilkS")
		)
		(fp_line
			(start 0.9 -1.3)
			(end 0.9 -0.4)
			(stroke
				(width 0.05)
				(type solid)
			)
			(layer "F.CrtYd")
		)
		(fp_line
			(start -0.9 -1.3)
			(end 0.9 -1.3)
			(stroke
				(width 0.05)
				(type solid)
			)
			(layer "F.CrtYd")
		)
		(fp_line
			(start -0.9 -1.3)
			(end -0.9 -1)
			(stroke
				(width 0.05)
				(type solid)
			)
			(layer "F.CrtYd")
		)
		(fp_line
			(start -0.9 -1)
			(end -1.4 -1)
			(stroke
				(width 0.05)
				(type solid)
			)
			(layer "F.CrtYd")
		)
		(fp_line
			(start 1.4 -0.4)
			(end 1.4 0.4)
			(stroke
				(width 0.05)
				(type solid)
			)
			(layer "F.CrtYd")
		)
		(fp_line
			(start 0.9 -0.4)
			(end 1.4 -0.4)
			(stroke
				(width 0.05)
				(type solid)
			)
			(layer "F.CrtYd")
		)
		(fp_line
			(start 1.4 0.4)
			(end 0.9 0.4)
			(stroke
				(width 0.05)
				(type solid)
			)
			(layer "F.CrtYd")
		)
		(fp_line
			(start 0.9 0.4)
			(end 0.9 1.3)
			(stroke
				(width 0.05)
				(type solid)
			)
			(layer "F.CrtYd")
		)
		(fp_line
			(start -0.9 1)
			(end -1.4 1)
			(stroke
				(width 0.05)
				(type solid)
			)
			(layer "F.CrtYd")
		)
		(fp_line
			(start -1.4 1)
			(end -1.4 -1)
			(stroke
				(width 0.05)
				(type solid)
			)
			(layer "F.CrtYd")
		)
		(fp_line
			(start 0.9 1.3)
			(end -0.9 1.3)
			(stroke
				(width 0.05)
				(type solid)
			)
			(layer "F.CrtYd")
		)
		(fp_line
			(start -0.9 1.3)
			(end -0.9 1)
			(stroke
				(width 0.05)
				(type solid)
			)
			(layer "F.CrtYd")
		)
		(fp_rect
			(start -0.623 -0.999)
			(end 0.627 1.001)
			(stroke
				(width 0.15)
				(type solid)
			)
			(fill no)
			(layer "F.Fab")
		)
		(pad "1" smd rect
			(at -1.051 -0.65 180)
			(size 0.6 0.6)
			(layers "F.Cu" "F.Mask" "F.Paste")
			(net 613 "/FPGA Config/DONE")
			(pinfunction "G")
			(pintype "input")
		)
		(pad "2" smd rect
			(at -1.051 0.65 180)
			(size 0.6 0.6)
			(layers "F.Cu" "F.Mask" "F.Paste")
			(net 1 "GND")
			(pinfunction "S")
			(pintype "passive")
		)
		(pad "3" smd rect
			(at 1.05 0 180)
			(size 0.6 0.6)
			(layers "F.Cu" "F.Mask" "F.Paste")
			(net 351 "Net-(Q2-D)")
			(pinfunction "D")
			(pintype "passive")
		)
	)
	(footprint "antmicro-footprints:R_0402_1005Metric"
		(layer "F.Cu")
		(at 83.650501 119.926 -90)
		(descr "Resistor SMD 0402")
		(tags "resistor SMD 0402")
		(property "Reference" "R40"
			(at -1.122484 -0.772697 270)
			(layer "F.SilkS")
			(hide yes)
			(effects
				(font
					(size 0.7 0.7)
					(thickness 0.15)
				)
				(justify left bottom)
			)
		)
		(property "Value" "R_330R_0402"
			(at -1.011843 1.772047 270)
			(layer "F.Fab")
			(effects
				(font
					(size 0.7 0.7)
					(thickness 0.15)
				)
				(justify left bottom)
			)
		)
		(property "Datasheet" "https://www.bourns.com/docs/product-datasheets/cr.pdf"
			(at 0 0 270)
			(layer "F.Fab")
			(hide yes)
			(effects
				(font
					(size 1.27 1.27)
					(thickness 0.15)
				)
			)
		)
		(property "Author" "Antmicro"
			(at -36.275499 203.576501 0)
			(layer "F.Fab")
			(hide yes)
			(effects
				(font
					(size 1 1)
					(thickness 0.15)
				)
			)
		)
		(property "License" "Apache-2.0"
			(at -36.275499 203.576501 0)
			(layer "F.Fab")
			(hide yes)
			(effects
				(font
					(size 1 1)
					(thickness 0.15)
				)
			)
		)
		(property "MPN" "CR0402-FX-3300GLF"
			(at -36.275499 203.576501 0)
			(layer "F.Fab")
			(hide yes)
			(effects
				(font
					(size 1 1)
					(thickness 0.15)
				)
			)
		)
		(property "Manufacturer" "Bourns"
			(at -36.275499 203.576501 0)
			(layer "F.Fab")
			(hide yes)
			(effects
				(font
					(size 1 1)
					(thickness 0.15)
				)
			)
		)
		(property "Tolerance" "1%"
			(at -36.275499 203.576501 0)
			(layer "F.Fab")
			(hide yes)
			(effects
				(font
					(size 1 1)
					(thickness 0.15)
				)
			)
		)
		(property "Val" "330R"
			(at -36.275499 203.576501 0)
			(layer "F.Fab")
			(hide yes)
			(effects
				(font
					(size 1 1)
					(thickness 0.15)
				)
			)
		)
		(sheetname "/FPGA bank 14/")
		(sheetfile "fpga-bank-14.kicad_sch")
		(attr smd)
		(fp_rect
			(start -0.93 -0.47)
			(end 0.93 0.47)
			(stroke
				(width 0.05)
				(type solid)
			)
			(fill no)
			(layer "F.CrtYd")
		)
		(fp_rect
			(start -0.5 -0.25)
			(end 0.5 0.25)
			(stroke
				(width 0.15)
				(type solid)
			)
			(fill no)
			(layer "F.Fab")
		)
		(pad "1" smd roundrect
			(at -0.485 0 270)
			(size 0.59 0.64)
			(layers "F.Cu" "F.Mask" "F.Paste")
			(roundrect_rratio 0.25)
			(net 307 "Net-(D4-Pad2)")
			(pintype "passive")
		)
		(pad "2" smd roundrect
			(at 0.485 0 270)
			(size 0.59 0.64)
			(layers "F.Cu" "F.Mask" "F.Paste")
			(roundrect_rratio 0.25)
			(net 353 "Net-(Q4-D)")
			(pintype "passive")
		)
	)
	(footprint "antmicro-footprints:WSON-8_6x8x0.5mm_P1.27mm"
		(layer "F.Cu")
		(at 118.65 181.9 180)
		(property "Reference" "U3"
			(at -4.3 -3.2 180)
			(layer "F.SilkS")
			(effects
				(font
					(size 0.7 0.7)
					(thickness 0.15)
				)
				(justify left bottom)
			)
		)
		(property "Value" "S25FL128SAGNFI000"
			(at 0 4.3 180)
			(layer "F.Fab")
			(effects
				(font
					(size 0.7 0.7)
					(thickness 0.15)
				)
				(justify left bottom)
			)
		)
		(property "Datasheet" "https://www.farnell.com/datasheets/2309615.pdf"
			(at 0 0 180)
			(layer "F.Fab")
			(hide yes)
			(effects
				(font
					(size 1.27 1.27)
					(thickness 0.15)
				)
			)
		)
		(property "Author" "Antmicro"
			(at 237.3 363.8 0)
			(layer "F.Fab")
			(hide yes)
			(effects
				(font
					(size 1 1)
					(thickness 0.15)
				)
			)
		)
		(property "License" "Apache-2.0"
			(at 237.3 363.8 0)
			(layer "F.Fab")
			(hide yes)
			(effects
				(font
					(size 1 1)
					(thickness 0.15)
				)
			)
		)
		(property "MPN" "S25FL128SAGNFI000"
			(at 237.3 363.8 0)
			(layer "F.Fab")
			(hide yes)
			(effects
				(font
					(size 1 1)
					(thickness 0.15)
				)
			)
		)
		(property "Manufacturer" "Cypress Semiconductor"
			(at 237.3 363.8 0)
			(layer "F.Fab")
			(hide yes)
			(effects
				(font
					(size 1 1)
					(thickness 0.15)
				)
			)
		)
		(sheetname "/HyperRAM + QSPI Flash/")
		(sheetfile "hyperram-flash.kicad_sch")
		(attr smd)
		(fp_line
			(start 4.0005 3.2)
			(end -3.9995 3.2)
			(stroke
				(width 0.15)
				(type solid)
			)
			(layer "F.SilkS")
		)
		(fp_line
			(start 4 -3.2)
			(end -3.975 -3.2)
			(stroke
				(width 0.15)
				(type solid)
			)
			(layer "F.SilkS")
		)
		(fp_circle
			(center -4.2 -2.4)
			(end -4.149 -2.4)
			(stroke
				(width 0.15)
				(type solid)
			)
			(fill yes)
			(layer "F.SilkS")
		)
		(fp_rect
			(start -4.7 -3.25)
			(end 4.7 3.25)
			(stroke
				(width 0.05)
				(type solid)
			)
			(fill no)
			(layer "F.CrtYd")
		)
		(fp_line
			(start 3.9995 3.0005)
			(end -3.9995 3.0005)
			(stroke
				(width 0.15)
				(type solid)
			)
			(layer "F.Fab")
		)
		(fp_line
			(start 3.9995 -2.9995)
			(end 3.9995 3.0005)
			(stroke
				(width 0.15)
				(type solid)
			)
			(layer "F.Fab")
		)
		(fp_line
			(start -3.0015 -2.9995)
			(end 3.9995 -2.9995)
			(stroke
				(width 0.15)
				(type solid)
			)
			(layer "F.Fab")
		)
		(fp_line
			(start -3.0015 -2.9995)
			(end -3.9995 -1.9995)
			(stroke
				(width 0.15)
				(type solid)
			)
			(layer "F.Fab")
		)
		(fp_line
			(start -3.9995 3.0005)
			(end -3.9995 -1.9995)
			(stroke
				(width 0.15)
				(type solid)
			)
			(layer "F.Fab")
		)
		(pad "1" smd roundrect
			(at -3.9995 -1.9045 90)
			(size 0.4 1.3)
			(layers "F.Cu" "F.Mask" "F.Paste")
			(roundrect_rratio 0.25)
			(net 625 "/FPGA Config/FLASH.~{CS}")
			(pinfunction "~{CS}")
			(pintype "input")
		)
		(pad "2" smd roundrect
			(at -3.9995 -0.6355 90)
			(size 0.4 1.3)
			(layers "F.Cu" "F.Mask" "F.Paste")
			(roundrect_rratio 0.25)
			(net 363 "/HyperRAM + QSPI Flash/IO1")
			(pinfunction "SO/IO1")
			(pintype "bidirectional")
		)
		(pad "3" smd roundrect
			(at -3.9995 0.6345 90)
			(size 0.4 1.3)
			(layers "F.Cu" "F.Mask" "F.Paste")
			(roundrect_rratio 0.25)
			(net 361 "/HyperRAM + QSPI Flash/IO2")
			(pinfunction "~{WP}/IO2")
			(pintype "bidirectional")
		)
		(pad "4" smd roundrect
			(at -3.9995 1.9045 90)
			(size 0.4 1.3)
			(layers "F.Cu" "F.Mask" "F.Paste")
			(roundrect_rratio 0.25)
			(net 1 "GND")
			(pinfunction "V_{SS}")
			(pintype "power_in")
		)
		(pad "5" smd roundrect
			(at 3.9995 1.8755 90)
			(size 0.4 1.3)
			(layers "F.Cu" "F.Mask" "F.Paste")
			(roundrect_rratio 0.25)
			(net 362 "/HyperRAM + QSPI Flash/IO0")
			(pinfunction "SI/IO0")
			(pintype "bidirectional")
		)
		(pad "6" smd roundrect
			(at 3.9995 0.6035 90)
			(size 0.4 1.3)
			(layers "F.Cu" "F.Mask" "F.Paste")
			(roundrect_rratio 0.25)
			(net 630 "/FPGA Config/FLASH.SCK")
			(pinfunction "SCK")
			(pintype "input")
		)
		(pad "7" smd roundrect
			(at 3.9995 -0.6655 90)
			(size 0.4 1.3)
			(layers "F.Cu" "F.Mask" "F.Paste")
			(roundrect_rratio 0.25)
			(net 360 "/HyperRAM + QSPI Flash/IO3")
			(pinfunction "~{HOLD}/IO3")
			(pintype "bidirectional")
		)
		(pad "8" smd roundrect
			(at 3.9995 -1.9355 90)
			(size 0.4 1.3)
			(layers "F.Cu" "F.Mask" "F.Paste")
			(roundrect_rratio 0.25)
			(net 200 "+3V3")
			(pinfunction "V_{CC}")
			(pintype "power_in")
		)
		(pad "9" smd roundrect
			(at -0.0005 -0.0005 180)
			(size 4.8 4.65)
			(layers "F.Cu" "F.Mask" "F.Paste")
			(roundrect_rratio 0.05)
			(chamfer_ratio 0.1)
			(chamfer top_left)
			(net 393 "unconnected-(U3-EP-Pad9)")
			(pinfunction "EP")
			(pintype "no_connect")
		)
	)
	(footprint "antmicro-footprints:SOT-23-5"
		(layer "F.Cu")
		(at 81 151.1)
		(property "Reference" "U5"
			(at 0.4 2.7 0)
			(layer "F.SilkS")
			(effects
				(font
					(size 0.7 0.7)
					(thickness 0.15)
				)
				(justify left bottom)
			)
		)
		(property "Value" "NCP718BSN330T1G"
			(at 0.002 2.799 0)
			(layer "F.Fab")
			(effects
				(font
					(size 0.7 0.7)
					(thickness 0.15)
				)
				(justify left bottom)
			)
		)
		(property "Datasheet" "https://www.mouser.com/datasheet/2/308/NCP718_D-1224359.pdf"
			(at 0 0 0)
			(layer "F.Fab")
			(hide yes)
			(effects
				(font
					(size 1.27 1.27)
					(thickness 0.15)
				)
			)
		)
		(property "Author" "Antmicro"
			(at 0 0 0)
			(layer "F.Fab")
			(hide yes)
			(effects
				(font
					(size 1 1)
					(thickness 0.15)
				)
			)
		)
		(property "License" "Apache-2.0"
			(at 0 0 0)
			(layer "F.Fab")
			(hide yes)
			(effects
				(font
					(size 1 1)
					(thickness 0.15)
				)
			)
		)
		(property "MPN" "NCP718BSN330T1G"
			(at 0 0 0)
			(layer "F.Fab")
			(hide yes)
			(effects
				(font
					(size 1 1)
					(thickness 0.15)
				)
			)
		)
		(property "Manufacturer" "ON Semiconductor"
			(at 0 0 0)
			(layer "F.Fab")
			(hide yes)
			(effects
				(font
					(size 1 1)
					(thickness 0.15)
				)
			)
		)
		(sheetname "/Debug FTDI/")
		(sheetfile "debug-ftdi.kicad_sch")
		(attr smd)
		(fp_line
			(start -0.85 1.6)
			(end -0.85 1.301)
			(stroke
				(width 0.15)
				(type solid)
			)
			(layer "F.SilkS")
		)
		(fp_line
			(start -0.8 -1.6)
			(end -0.8 -1.3)
			(stroke
				(width 0.15)
				(type solid)
			)
			(layer "F.SilkS")
		)
		(fp_line
			(start -0.8 -1.6)
			(end -0.5 -1.6)
			(stroke
				(width 0.15)
				(type solid)
			)
			(layer "F.SilkS")
		)
		(fp_line
			(start -0.55 1.6)
			(end -0.85 1.6)
			(stroke
				(width 0.15)
				(type solid)
			)
			(layer "F.SilkS")
		)
		(fp_line
			(start 0.8 -1.6)
			(end 0.5 -1.6)
			(stroke
				(width 0.15)
				(type solid)
			)
			(layer "F.SilkS")
		)
		(fp_line
			(start 0.8 -1.3)
			(end 0.8 -1.6)
			(stroke
				(width 0.15)
				(type solid)
			)
			(layer "F.SilkS")
		)
		(fp_line
			(start 0.8 0.55)
			(end 0.8 -0.55)
			(stroke
				(width 0.15)
				(type solid)
			)
			(layer "F.SilkS")
		)
		(fp_line
			(start 0.8 1.3)
			(end 0.8 1.599)
			(stroke
				(width 0.15)
				(type solid)
			)
			(layer "F.SilkS")
		)
		(fp_line
			(start 0.8 1.599)
			(end 0.549 1.599)
			(stroke
				(width 0.15)
				(type solid)
			)
			(layer "F.SilkS")
		)
		(fp_circle
			(center -1.25 -1.5)
			(end -1.2 -1.5)
			(stroke
				(width 0.15)
				(type solid)
			)
			(fill yes)
			(layer "F.SilkS")
		)
		(fp_rect
			(start 1.9 -1.76)
			(end -1.9 1.75)
			(stroke
				(width 0.05)
				(type solid)
			)
			(fill no)
			(layer "F.CrtYd")
		)
		(fp_line
			(start -0.398 -1.526)
			(end -0.874 -1.05)
			(stroke
				(width 0.15)
				(type solid)
			)
			(layer "F.Fab")
		)
		(fp_rect
			(start 0.874 1.523)
			(end -0.873 -1.525)
			(stroke
				(width 0.15)
				(type solid)
			)
			(fill no)
			(layer "F.Fab")
		)
		(pad "1" smd rect
			(at -1.351 -0.951 270)
			(size 0.55 1)
			(layers "F.Cu" "F.Mask" "F.Paste")
			(net 2 "/Debug FTDI/VBUS")
			(pinfunction "VIN")
			(pintype "passive")
		)
		(pad "2" smd rect
			(at -1.351 0 270)
			(size 0.55 1)
			(layers "F.Cu" "F.Mask" "F.Paste")
			(net 1 "GND")
			(pinfunction "GND")
			(pintype "passive")
		)
		(pad "3" smd rect
			(at -1.351 0.949 270)
			(size 0.55 1)
			(layers "F.Cu" "F.Mask" "F.Paste")
			(net 2 "/Debug FTDI/VBUS")
			(pinfunction "EN")
			(pintype "passive")
		)
		(pad "4" smd rect
			(at 1.35 0.949 270)
			(size 0.55 1)
			(layers "F.Cu" "F.Mask" "F.Paste")
			(net 583 "unconnected-(U5-NC-Pad4)")
			(pinfunction "NC")
			(pintype "no_connect")
		)
		(pad "5" smd rect
			(at 1.35 -0.951 270)
			(size 0.55 1)
			(layers "F.Cu" "F.Mask" "F.Paste")
			(net 6 "/Debug FTDI/FTDI_3V3")
			(pinfunction "VOUT")
			(pintype "passive")
		)
	)
	(footprint "antmicro-footprints:RJ45_ARJM11B1-502-AB-EW2_Horizontal"
		(layer "F.Cu")
		(at 86.9805 131.804037 -90)
		(descr "ARJM11B1-502-AB-EW2 RJ45 JACK")
		(property "Reference" "J6"
			(at -2.214037 -2.1095 90)
			(layer "F.SilkS")
			(effects
				(font
					(size 0.7 0.7)
					(thickness 0.15)
				)
				(justify right top)
			)
		)
		(property "Value" "RJ45_Abracon_ARJM11B1-502-AB-EW2"
			(at -4.3 22.78 90)
			(layer "F.Fab")
			(effects
				(font
					(size 0.7 0.7)
					(thickness 0.15)
				)
				(justify right top)
			)
		)
		(property "Datasheet" "https://www.mouser.com/datasheet/3/184/1/ARJM11.pdf"
			(at -0.035 -0.01 90)
			(layer "F.Fab")
			(effects
				(font
					(size 0.7 0.7)
					(thickness 0.15)
				)
				(justify right top)
			)
		)
		(property "Description" "Modular Connectors / Ethernet Connectors RJ45 JACK W/MAG 1X1 1000BASE-T"
			(at -0.035 -0.01 90)
			(layer "F.Fab")
			(effects
				(font
					(size 0.7 0.7)
					(thickness 0.15)
				)
				(justify right top)
			)
		)
		(property "MPN" "ARJM11B1-502-AB-EW2"
			(at 0 0 270)
			(unlocked yes)
			(layer "F.Fab")
			(hide yes)
			(effects
				(font
					(size 1 1)
					(thickness 0.15)
				)
			)
		)
		(property "Manufacturer" "Abracon"
			(at 0 0 270)
			(unlocked yes)
			(layer "F.Fab")
			(hide yes)
			(effects
				(font
					(size 1 1)
					(thickness 0.15)
				)
			)
		)
		(property "Author" "Antmicro"
			(at 0 0 270)
			(unlocked yes)
			(layer "F.Fab")
			(hide yes)
			(effects
				(font
					(size 1 1)
					(thickness 0.15)
				)
			)
		)
		(property "License" "Apache-2.0"
			(at 0 0 270)
			(unlocked yes)
			(layer "F.Fab")
			(hide yes)
			(effects
				(font
					(size 1 1)
					(thickness 0.15)
				)
			)
		)
		(sheetname "/Ethernet/")
		(sheetfile "ethernet.kicad_sch")
		(attr through_hole)
		(fp_line
			(start -2.235 19.69)
			(end 13.665 19.69)
			(stroke
				(width 0.15)
				(type solid)
			)
			(layer "F.SilkS")
		)
		(fp_line
			(start -2.235 19.69)
			(end -2.235 7.48)
			(stroke
				(width 0.15)
				(type solid)
			)
			(layer "F.SilkS")
		)
		(fp_line
			(start 13.665 19.69)
			(end 13.665 7.48)
			(stroke
				(width 0.15)
				(type solid)
			)
			(layer "F.SilkS")
		)
		(fp_line
			(start 13.665 4.19)
			(end 13.665 -1.51)
			(stroke
				(width 0.15)
				(type solid)
			)
			(layer "F.SilkS")
		)
		(fp_line
			(start -2.235 -1.51)
			(end -2.235 4.19)
			(stroke
				(width 0.15)
				(type solid)
			)
			(layer "F.SilkS")
		)
		(fp_line
			(start 13.665 -1.51)
			(end -2.235 -1.51)
			(stroke
				(width 0.15)
				(type solid)
			)
			(layer "F.SilkS")
		)
		(fp_line
			(start -3.7 19.94)
			(end 15.12 19.94)
			(stroke
				(width 0.05)
				(type solid)
			)
			(layer "F.CrtYd")
		)
		(fp_line
			(start 15.12 19.94)
			(end 15.12 -1.76)
			(stroke
				(width 0.05)
				(type solid)
			)
			(layer "F.CrtYd")
		)
		(fp_line
			(start -3.7 -1.76)
			(end -3.7 19.94)
			(stroke
				(width 0.05)
				(type solid)
			)
			(layer "F.CrtYd")
		)
		(fp_line
			(start 15.12 -1.76)
			(end -3.7 -1.76)
			(stroke
				(width 0.05)
				(type solid)
			)
			(layer "F.CrtYd")
		)
		(fp_line
			(start -2.235 19.69)
			(end 13.665 19.69)
			(stroke
				(width 0.15)
				(type solid)
			)
			(layer "F.Fab")
		)
		(fp_line
			(start 13.665 19.69)
			(end 13.665 -1.51)
			(stroke
				(width 0.15)
				(type solid)
			)
			(layer "F.Fab")
		)
		(fp_line
			(start -2.235 -1.51)
			(end -2.235 19.69)
			(stroke
				(width 0.15)
				(type solid)
			)
			(layer "F.Fab")
		)
		(fp_line
			(start 13.665 -1.51)
			(end -2.235 -1.51)
			(stroke
				(width 0.15)
				(type solid)
			)
			(layer "F.Fab")
		)
		(fp_text user "License: Apache-2.0"
			(at -4.3 25.18 90)
			(layer "F.Fab")
			(effects
				(font
					(size 0.7 0.7)
					(thickness 0.15)
				)
				(justify right top)
			)
		)
		(fp_text user "Author: Antmicro"
			(at -4.3 23.98 90)
			(layer "F.Fab")
			(effects
				(font
					(size 0.7 0.7)
					(thickness 0.15)
				)
				(justify right top)
			)
		)
		(fp_text user "${REFERENCE}"
			(at -4.26 21.29 90)
			(layer "F.Fab")
			(effects
				(font
					(size 0.7 0.7)
					(thickness 0.15)
				)
				(justify right top)
			)
		)
		(pad "" np_thru_hole circle
			(at 0 8.89 270)
			(size 3.2 3.2)
			(drill 3.25)
			(layers "*.Cu" "*.Mask")
		)
		(pad "" np_thru_hole circle
			(at 11.43 8.89 270)
			(size 3.2 3.2)
			(drill 3.25)
			(layers "*.Cu" "*.Mask")
		)
		(pad "1" thru_hole circle
			(at 0 0 270)
			(size 1.458 1.458)
			(drill 0.9)
			(layers "*.Cu" "*.Mask")
			(remove_unused_layers no)
			(net 125 "/Ethernet/ETH1_P")
			(pinfunction "1")
			(pintype "bidirectional")
			(solder_mask_margin 0)
		)
		(pad "2" thru_hole circle
			(at 1.27 2.54 270)
			(size 1.458 1.458)
			(drill 0.9)
			(layers "*.Cu" "*.Mask")
			(remove_unused_layers no)
			(net 128 "/Ethernet/ETH1_N")
			(pinfunction "2")
			(pintype "bidirectional")
			(solder_mask_margin 0)
		)
		(pad "3" thru_hole circle
			(at 2.54 0 270)
			(size 1.458 1.458)
			(drill 0.9)
			(layers "*.Cu" "*.Mask")
			(remove_unused_layers no)
			(net 124 "/Ethernet/ETH2_P")
			(pinfunction "3")
			(pintype "bidirectional")
			(solder_mask_margin 0)
		)
		(pad "4" thru_hole circle
			(at 3.81 2.54 270)
			(size 1.458 1.458)
			(drill 0.9)
			(layers "*.Cu" "*.Mask")
			(remove_unused_layers no)
			(net 127 "/Ethernet/ETH2_N")
			(pinfunction "4")
			(pintype "bidirectional")
			(solder_mask_margin 0)
		)
		(pad "5" thru_hole circle
			(at 5.08 0 270)
			(size 1.458 1.458)
			(drill 0.9)
			(layers "*.Cu" "*.Mask")
			(remove_unused_layers no)
			(net 215 "Net-(C137-Pad2)")
			(pinfunction "5")
			(pintype "passive")
			(solder_mask_margin 0)
		)
		(pad "6" thru_hole circle
			(at 6.35 2.54 270)
			(size 1.458 1.458)
			(drill 0.9)
			(layers "*.Cu" "*.Mask")
			(remove_unused_layers no)
			(net 214 "Net-(C135-Pad2)")
			(pinfunction "6")
			(pintype "passive")
			(solder_mask_margin 0)
		)
		(pad "7" thru_hole circle
			(at 7.62 0 270)
			(size 1.458 1.458)
			(drill 0.9)
			(layers "*.Cu" "*.Mask")
			(remove_unused_layers no)
			(net 123 "/Ethernet/ETH3_P")
			(pinfunction "7")
			(pintype "bidirectional")
			(solder_mask_margin 0)
		)
		(pad "8" thru_hole circle
			(at 8.89 2.54 270)
			(size 1.458 1.458)
			(drill 0.9)
			(layers "*.Cu" "*.Mask")
			(remove_unused_layers no)
			(net 129 "/Ethernet/ETH3_N")
			(pinfunction "8")
			(pintype "bidirectional")
			(solder_mask_margin 0)
		)
		(pad "9" thru_hole circle
			(at 10.16 0 270)
			(size 1.458 1.458)
			(drill 0.9)
			(layers "*.Cu" "*.Mask")
			(remove_unused_layers no)
			(net 126 "/Ethernet/ETH4_P")
			(pinfunction "9")
			(pintype "bidirectional")
			(solder_mask_margin 0)
		)
		(pad "10" thru_hole circle
			(at 11.43 2.54 270)
			(size 1.458 1.458)
			(drill 0.9)
			(layers "*.Cu" "*.Mask")
			(remove_unused_layers no)
			(net 130 "/Ethernet/ETH4_N")
			(pinfunction "10")
			(pintype "bidirectional")
			(solder_mask_margin 0)
		)
		(pad "11" thru_hole circle
			(at -0.96 12.95 270)
			(size 1.605 1.605)
			(drill 1.02)
			(layers "*.Cu" "*.Mask")
			(remove_unused_layers no)
			(net 758 "Net-(J6-LED_G+)")
			(pinfunction "LED_G+")
			(pintype "passive")
			(solder_mask_margin 0)
		)
		(pad "12" thru_hole circle
			(at 1.58 12.95 270)
			(size 1.605 1.605)
			(drill 1.02)
			(layers "*.Cu" "*.Mask")
			(remove_unused_layers no)
			(net 602 "/Ethernet/LED_SPD")
			(pinfunction "LED_G-")
			(pintype "passive")
			(solder_mask_margin 0)
		)
		(pad "13" thru_hole circle
			(at 9.85 12.95 270)
			(size 1.605 1.605)
			(drill 1.02)
			(layers "*.Cu" "*.Mask")
			(remove_unused_layers no)
			(net 757 "Net-(J6-LED_Y+)")
			(pinfunction "LED_Y+")
			(pintype "passive")
			(solder_mask_margin 0)
		)
		(pad "14" thru_hole circle
			(at 12.39 12.95 270)
			(size 1.605 1.605)
			(drill 1.02)
			(layers "*.Cu" "*.Mask")
			(remove_unused_layers no)
			(net 603 "/Ethernet/LED_LINK")
			(pinfunction "LED_Y-")
			(pintype "passive")
			(solder_mask_margin 0)
		)
		(pad "SH" thru_hole circle
			(at -2.135 5.84 270)
			(size 2.625 2.625)
			(drill 1.7)
			(layers "*.Cu" "*.Mask")
			(remove_unused_layers no)
			(net 32 "Net-(C234-Pad1)")
			(pinfunction "SH")
			(pintype "passive")
			(solder_mask_margin 0)
		)
		(pad "SH" thru_hole circle
			(at 13.565 5.84 270)
			(size 2.625 2.625)
			(drill 1.7)
			(layers "*.Cu" "*.Mask")
			(remove_unused_layers no)
			(net 32 "Net-(C234-Pad1)")
			(pinfunction "SH")
			(pintype "passive")
			(solder_mask_margin 0)
		)
	)
	(footprint "antmicro-footprints:Torex_USP-6C"
		(layer "F.Cu")
		(at 194.175 194.85)
		(tags "Integrated Circuit")
		(property "Reference" "U28"
			(at -0.575 2.35 0)
			(layer "F.SilkS")
			(effects
				(font
					(size 0.7 0.7)
					(thickness 0.15)
				)
				(justify left bottom)
			)
		)
		(property "Value" "XC6230H001ER-G"
			(at -3.492 1.929 0)
			(layer "F.Fab")
			(effects
				(font
					(size 0.7 0.7)
					(thickness 0.15)
				)
				(justify left bottom)
			)
		)
		(property "Datasheet" "https://www.torexsemi.com/file/xc6230/XC6230.pdf"
			(at 0 0 0)
			(layer "F.Fab")
			(hide yes)
			(effects
				(font
					(size 1.27 1.27)
					(thickness 0.15)
				)
			)
		)
		(property "Author" "Antmicro"
			(at 0 0 0)
			(layer "F.Fab")
			(hide yes)
			(effects
				(font
					(size 1 1)
					(thickness 0.15)
				)
			)
		)
		(property "License" "Apache-2.0"
			(at 0 0 0)
			(layer "F.Fab")
			(hide yes)
			(effects
				(font
					(size 1 1)
					(thickness 0.15)
				)
			)
		)
		(property "MPN" "XC6230H001ER-G"
			(at 0 0 0)
			(layer "F.Fab")
			(hide yes)
			(effects
				(font
					(size 1 1)
					(thickness 0.15)
				)
			)
		)
		(property "Manufacturer" "Torex Semiconductor"
			(at 0 0 0)
			(layer "F.Fab")
			(hide yes)
			(effects
				(font
					(size 1 1)
					(thickness 0.15)
				)
			)
		)
		(sheetname "/Supply/")
		(sheetfile "supply.kicad_sch")
		(attr smd)
		(fp_circle
			(center -1.801 -0.554)
			(end -1.751 -0.554)
			(stroke
				(width 0.15)
				(type solid)
			)
			(fill yes)
			(layer "F.SilkS")
		)
		(fp_rect
			(start -0.403 -0.701)
			(end 0.4 -0.203)
			(stroke
				(width 0.01)
				(type solid)
			)
			(fill yes)
			(layer "F.Paste")
		)
		(fp_rect
			(start -0.403 0.2)
			(end 0.4 0.698)
			(stroke
				(width 0.01)
				(type solid)
			)
			(fill yes)
			(layer "F.Paste")
		)
		(fp_rect
			(start -1.5 -1.402)
			(end 1.498 1.4)
			(stroke
				(width 0.05)
				(type solid)
			)
			(fill no)
			(layer "F.CrtYd")
		)
		(fp_line
			(start -1 -0.903)
			(end 0.997 -0.903)
			(stroke
				(width 0.15)
				(type solid)
			)
			(layer "F.Fab")
		)
		(fp_line
			(start -1 -0.7)
			(end -0.8 -0.9)
			(stroke
				(width 0.15)
				(type solid)
			)
			(layer "F.Fab")
		)
		(fp_line
			(start -1 0.9)
			(end -1 -0.903)
			(stroke
				(width 0.15)
				(type solid)
			)
			(layer "F.Fab")
		)
		(fp_line
			(start 0.997 -0.903)
			(end 0.997 0.9)
			(stroke
				(width 0.15)
				(type solid)
			)
			(layer "F.Fab")
		)
		(fp_line
			(start 0.997 0.9)
			(end -1 0.9)
			(stroke
				(width 0.15)
				(type solid)
			)
			(layer "F.Fab")
		)
		(pad "1" smd rect
			(at -0.975 -0.553 90)
			(size 0.35 0.45)
			(layers "F.Cu" "F.Mask" "F.Paste")
			(net 76 "/Supply/MGTAVTT_OUT")
			(pinfunction "OUT")
			(pintype "power_out")
		)
		(pad "2" smd rect
			(at -0.975 0 90)
			(size 0.25 0.45)
			(layers "F.Cu" "F.Mask" "F.Paste")
			(net 224 "/Supply/MGTAVTT_ILIM")
			(pinfunction "ILIM")
			(pintype "output")
		)
		(pad "3" smd rect
			(at -0.975 0.497 90)
			(size 0.25 0.45)
			(layers "F.Cu" "F.Mask" "F.Paste")
			(net 76 "/Supply/MGTAVTT_OUT")
			(pinfunction "FB")
			(pintype "open_collector")
		)
		(pad "4" smd rect
			(at 0.972 0.497 90)
			(size 0.25 0.45)
			(layers "F.Cu" "F.Mask" "F.Paste")
			(net 64 "/Supply/1V7")
			(pinfunction "EN")
			(pintype "input")
		)
		(pad "5" smd rect
			(at 0.972 0 90)
			(size 0.25 0.45)
			(layers "F.Cu" "F.Mask" "F.Paste")
			(net 1 "GND")
			(pinfunction "GND")
			(pintype "power_in")
		)
		(pad "6" smd rect
			(at 0.972 -0.5 90)
			(size 0.25 0.45)
			(layers "F.Cu" "F.Mask" "F.Paste")
			(net 64 "/Supply/1V7")
			(pinfunction "IN")
			(pintype "power_out")
		)
		(pad "7" smd rect
			(at 0 0)
			(size 1 1.6)
			(layers "F.Cu" "F.Mask")
			(net 1 "GND")
			(pinfunction "EP")
			(pintype "passive")
		)
		(pad "7" smd rect
			(at 0 0 90)
			(size 1.8 0.9)
			(layers "F.Cu" "F.Mask")
			(net 1 "GND")
			(pinfunction "EP")
			(pintype "passive")
		)
	)
	(footprint "antmicro-footprints:R_0402_1005Metric"
		(layer "F.Cu")
		(at 177.9 179.115)
		(descr "Resistor SMD 0402")
		(tags "resistor SMD 0402")
		(property "Reference" "R135"
			(at -1.122484 -0.772697 0)
			(layer "F.SilkS")
			(hide yes)
			(effects
				(font
					(size 0.7 0.7)
					(thickness 0.15)
				)
				(justify left bottom)
			)
		)
		(property "Value" "R_47k_0402"
			(at -1.011843 1.772047 0)
			(layer "F.Fab")
			(effects
				(font
					(size 0.7 0.7)
					(thickness 0.15)
				)
				(justify left bottom)
			)
		)
		(property "Datasheet" "https://www.bourns.com/docs/product-datasheets/cr.pdf"
			(at 0 0 0)
			(layer "F.Fab")
			(hide yes)
			(effects
				(font
					(size 1.27 1.27)
					(thickness 0.15)
				)
			)
		)
		(property "Author" "Antmicro"
			(at 0 0 0)
			(layer "F.Fab")
			(hide yes)
			(effects
				(font
					(size 1 1)
					(thickness 0.15)
				)
			)
		)
		(property "License" "Apache-2.0"
			(at 0 0 0)
			(layer "F.Fab")
			(hide yes)
			(effects
				(font
					(size 1 1)
					(thickness 0.15)
				)
			)
		)
		(property "MPN" "CR0402-FX-4702GLF"
			(at 0 0 0)
			(layer "F.Fab")
			(hide yes)
			(effects
				(font
					(size 1 1)
					(thickness 0.15)
				)
			)
		)
		(property "Manufacturer" "Bourns"
			(at 0 0 0)
			(layer "F.Fab")
			(hide yes)
			(effects
				(font
					(size 1 1)
					(thickness 0.15)
				)
			)
		)
		(property "Tolerance" "1%"
			(at 0 0 0)
			(layer "F.Fab")
			(hide yes)
			(effects
				(font
					(size 1 1)
					(thickness 0.15)
				)
			)
		)
		(property "Val" "47k"
			(at 0 0 0)
			(layer "F.Fab")
			(hide yes)
			(effects
				(font
					(size 1 1)
					(thickness 0.15)
				)
			)
		)
		(sheetname "/Supply/")
		(sheetfile "supply.kicad_sch")
		(attr smd)
		(fp_rect
			(start -0.93 -0.47)
			(end 0.93 0.47)
			(stroke
				(width 0.05)
				(type solid)
			)
			(fill no)
			(layer "F.CrtYd")
		)
		(fp_rect
			(start -0.5 -0.25)
			(end 0.5 0.25)
			(stroke
				(width 0.15)
				(type solid)
			)
			(fill no)
			(layer "F.Fab")
		)
		(pad "1" smd roundrect
			(at -0.485 0)
			(size 0.59 0.64)
			(layers "F.Cu" "F.Mask" "F.Paste")
			(roundrect_rratio 0.25)
			(net 240 "POWER")
			(pintype "passive")
		)
		(pad "2" smd roundrect
			(at 0.485 0)
			(size 0.59 0.64)
			(layers "F.Cu" "F.Mask" "F.Paste")
			(roundrect_rratio 0.25)
			(net 200 "+3V3")
			(pintype "passive")
		)
	)
	(footprint "antmicro-footprints:R_0402_1005Metric"
		(layer "F.Cu")
		(at 94.450501 119.926 -90)
		(descr "Resistor SMD 0402")
		(tags "resistor SMD 0402")
		(property "Reference" "R46"
			(at -1.122484 -0.772697 270)
			(layer "F.SilkS")
			(hide yes)
			(effects
				(font
					(size 0.7 0.7)
					(thickness 0.15)
				)
				(justify left bottom)
			)
		)
		(property "Value" "R_330R_0402"
			(at -1.011843 1.772047 270)
			(layer "F.Fab")
			(effects
				(font
					(size 0.7 0.7)
					(thickness 0.15)
				)
				(justify left bottom)
			)
		)
		(property "Datasheet" "https://www.bourns.com/docs/product-datasheets/cr.pdf"
			(at 0 0 270)
			(layer "F.Fab")
			(hide yes)
			(effects
				(font
					(size 1.27 1.27)
					(thickness 0.15)
				)
			)
		)
		(property "Author" "Antmicro"
			(at -25.475499 214.376501 0)
			(layer "F.Fab")
			(hide yes)
			(effects
				(font
					(size 1 1)
					(thickness 0.15)
				)
			)
		)
		(property "License" "Apache-2.0"
			(at -25.475499 214.376501 0)
			(layer "F.Fab")
			(hide yes)
			(effects
				(font
					(size 1 1)
					(thickness 0.15)
				)
			)
		)
		(property "MPN" "CR0402-FX-3300GLF"
			(at -25.475499 214.376501 0)
			(layer "F.Fab")
			(hide yes)
			(effects
				(font
					(size 1 1)
					(thickness 0.15)
				)
			)
		)
		(property "Manufacturer" "Bourns"
			(at -25.475499 214.376501 0)
			(layer "F.Fab")
			(hide yes)
			(effects
				(font
					(size 1 1)
					(thickness 0.15)
				)
			)
		)
		(property "Tolerance" "1%"
			(at -25.475499 214.376501 0)
			(layer "F.Fab")
			(hide yes)
			(effects
				(font
					(size 1 1)
					(thickness 0.15)
				)
			)
		)
		(property "Val" "330R"
			(at -25.475499 214.376501 0)
			(layer "F.Fab")
			(hide yes)
			(effects
				(font
					(size 1 1)
					(thickness 0.15)
				)
			)
		)
		(sheetname "/FPGA bank 14/")
		(sheetfile "fpga-bank-14.kicad_sch")
		(attr smd)
		(fp_rect
			(start -0.93 -0.47)
			(end 0.93 0.47)
			(stroke
				(width 0.05)
				(type solid)
			)
			(fill no)
			(layer "F.CrtYd")
		)
		(fp_rect
			(start -0.5 -0.25)
			(end 0.5 0.25)
			(stroke
				(width 0.15)
				(type solid)
			)
			(fill no)
			(layer "F.Fab")
		)
		(pad "1" smd roundrect
			(at -0.485 0 270)
			(size 0.59 0.64)
			(layers "F.Cu" "F.Mask" "F.Paste")
			(roundrect_rratio 0.25)
			(net 33 "Net-(D8-Pad2)")
			(pintype "passive")
		)
		(pad "2" smd roundrect
			(at 0.485 0 270)
			(size 0.59 0.64)
			(layers "F.Cu" "F.Mask" "F.Paste")
			(roundrect_rratio 0.25)
			(net 357 "Net-(Q8-D)")
			(pintype "passive")
		)
	)
	(footprint "antmicro-footprints:Bus_DDR5_SODIMM_Amphenol_10161033-002RHLF"
		(layer "F.Cu")
		(at 139.780001 134.8375 180)
		(property "Reference" "J2"
			(at -35.119999 -13.0625 180)
			(layer "F.SilkS")
			(effects
				(font
					(size 0.7 0.7)
					(thickness 0.15)
				)
				(justify left bottom)
			)
		)
		(property "Value" "Bus_DDR5_SODIMM_Amphenol_10161033-002RHLF_CUSTOM_2xDetectPin"
			(at 0 13.5 180)
			(layer "F.Fab")
			(effects
				(font
					(size 0.7 0.7)
					(thickness 0.15)
				)
				(justify left bottom)
			)
		)
		(property "Datasheet" "https://cdn.amphenol-cs.com/media/wysiwyg/files/documentation/datasheet/ssio/ssio_ddr5_sodimm.pdf"
			(at 0 0 180)
			(layer "F.Fab")
			(hide yes)
			(effects
				(font
					(size 1.27 1.27)
					(thickness 0.15)
				)
			)
		)
		(property "Author" "Antmicro"
			(at 279.560002 269.675 0)
			(layer "F.Fab")
			(hide yes)
			(effects
				(font
					(size 1 1)
					(thickness 0.15)
				)
			)
		)
		(property "License" "Apache-2.0"
			(at 279.560002 269.675 0)
			(layer "F.Fab")
			(hide yes)
			(effects
				(font
					(size 1 1)
					(thickness 0.15)
				)
			)
		)
		(property "MPN" "10161033-002RHLF"
			(at 279.560002 269.675 0)
			(layer "F.Fab")
			(hide yes)
			(effects
				(font
					(size 1 1)
					(thickness 0.15)
				)
			)
		)
		(property "Manufacturer" "Amphenol"
			(at 279.560002 269.675 0)
			(layer "F.Fab")
			(hide yes)
			(effects
				(font
					(size 1 1)
					(thickness 0.15)
				)
			)
		)
		(sheetname "/DDR5 SODIMM/")
		(sheetfile "ddr5-sodimm.kicad_sch")
		(attr smd)
		(fp_line
			(start 36.603 -3.695)
			(end 36.203 -3.695)
			(stroke
				(width 0.15)
				(type solid)
			)
			(layer "F.SilkS")
		)
		(fp_line
			(start 36.603 -11.865)
			(end 36.603 -3.695)
			(stroke
				(width 0.15)
				(type solid)
			)
			(layer "F.SilkS")
		)
		(fp_line
			(start 36.203 12.085)
			(end 36.203 -3.695)
			(stroke
				(width 0.15)
				(type solid)
			)
			(layer "F.SilkS")
		)
		(fp_line
			(start 36.203 12.085)
			(end 33.703 12.085)
			(stroke
				(width 0.15)
				(type solid)
			)
			(layer "F.SilkS")
		)
		(fp_line
			(start 33.878 -11.865)
			(end 36.603 -11.865)
			(stroke
				(width 0.15)
				(type solid)
			)
			(layer "F.SilkS")
		)
		(fp_line
			(start 33.703 12.085)
			(end 33.703 6.355)
			(stroke
				(width 0.15)
				(type solid)
			)
			(layer "F.SilkS")
		)
		(fp_line
			(start 33.703 -4.295)
			(end 33.703 1.115)
			(stroke
				(width 0.15)
				(type solid)
			)
			(layer "F.SilkS")
		)
		(fp_line
			(start 1.665 -4.295)
			(end 0.591 -4.295)
			(stroke
				(width 0.15)
				(type solid)
			)
			(layer "F.SilkS")
		)
		(fp_line
			(start 0.841 -11.06)
			(end 1.915 -11.06)
			(stroke
				(width 0.15)
				(type solid)
			)
			(layer "F.SilkS")
		)
		(fp_line
			(start -33.697 12.085)
			(end -33.697 6.355)
			(stroke
				(width 0.15)
				(type solid)
			)
			(layer "F.SilkS")
		)
		(fp_line
			(start -33.697 -2.901)
			(end -33.697 1.115)
			(stroke
				(width 0.15)
				(type solid)
			)
			(layer "F.SilkS")
		)
		(fp_line
			(start -36.197 12.085)
			(end -33.697 12.085)
			(stroke
				(width 0.15)
				(type solid)
			)
			(layer "F.SilkS")
		)
		(fp_line
			(start -36.197 -3.695)
			(end -36.197 12.085)
			(stroke
				(width 0.15)
				(type solid)
			)
			(layer "F.SilkS")
		)
		(fp_line
			(start -36.597 -3.695)
			(end -36.197 -3.695)
			(stroke
				(width 0.15)
				(type solid)
			)
			(layer "F.SilkS")
		)
		(fp_line
			(start -36.597 -11.865)
			(end -33.622 -11.865)
			(stroke
				(width 0.15)
				(type solid)
			)
			(layer "F.SilkS")
		)
		(fp_line
			(start -36.597 -11.865)
			(end -36.597 -3.695)
			(stroke
				(width 0.15)
				(type solid)
			)
			(layer "F.SilkS")
		)
		(fp_circle
			(center 33.38 -13.2)
			(end 33.43 -13.2)
			(stroke
				(width 0.15)
				(type solid)
			)
			(fill yes)
			(layer "F.SilkS")
		)
		(fp_line
			(start 39.38 12.33)
			(end 39.38 3.74)
			(stroke
				(width 0.05)
				(type solid)
			)
			(layer "F.CrtYd")
		)
		(fp_line
			(start 36.85 0.23)
			(end 39.38 3.74)
			(stroke
				(width 0.05)
				(type solid)
			)
			(layer "F.CrtYd")
		)
		(fp_line
			(start 36.85 -12.56)
			(end 36.85 0.23)
			(stroke
				(width 0.05)
				(type solid)
			)
			(layer "F.CrtYd")
		)
		(fp_line
			(start 36.85 -12.56)
			(end -36.85 -12.56)
			(stroke
				(width 0.05)
				(type solid)
			)
			(layer "F.CrtYd")
		)
		(fp_line
			(start -36.85 0.23)
			(end -39.38 3.74)
			(stroke
				(width 0.05)
				(type solid)
			)
			(layer "F.CrtYd")
		)
		(fp_line
			(start -36.85 -12.56)
			(end -36.85 0.23)
			(stroke
				(width 0.05)
				(type solid)
			)
			(layer "F.CrtYd")
		)
		(fp_line
			(start -39.38 12.33)
			(end 39.38 12.33)
			(stroke
				(width 0.05)
				(type solid)
			)
			(layer "F.CrtYd")
		)
		(fp_line
			(start -39.38 3.74)
			(end -39.38 12.33)
			(stroke
				(width 0.05)
				(type solid)
			)
			(layer "F.CrtYd")
		)
		(fp_line
			(start 36.603 -3.695)
			(end 36.203 -3.695)
			(stroke
				(width 0.15)
				(type solid)
			)
			(layer "F.Fab")
		)
		(fp_line
			(start 36.603 -11.375)
			(end 36.603 -3.695)
			(stroke
				(width 0.15)
				(type solid)
			)
			(layer "F.Fab")
		)
		(fp_line
			(start 36.203 12.085)
			(end 36.203 -3.695)
			(stroke
				(width 0.15)
				(type solid)
			)
			(layer "F.Fab")
		)
		(fp_line
			(start 36.203 12.085)
			(end 33.703 12.085)
			(stroke
				(width 0.15)
				(type solid)
			)
			(layer "F.Fab")
		)
		(fp_line
			(start 36.175 -11.865)
			(end 36.603 -11.375)
			(stroke
				(width 0.15)
				(type solid)
			)
			(layer "F.Fab")
		)
		(fp_line
			(start 33.878 -11.865)
			(end 36.175 -11.865)
			(stroke
				(width 0.15)
				(type solid)
			)
			(layer "F.Fab")
		)
		(fp_line
			(start 33.728 -11.06)
			(end 33.878 -11.865)
			(stroke
				(width 0.15)
				(type solid)
			)
			(layer "F.Fab")
		)
		(fp_line
			(start 33.703 12.085)
			(end 33.703 -4.295)
			(stroke
				(width 0.15)
				(type solid)
			)
			(layer "F.Fab")
		)
		(fp_line
			(start 33.703 -4.295)
			(end -33.697 -4.295)
			(stroke
				(width 0.15)
				(type solid)
			)
			(layer "F.Fab")
		)
		(fp_line
			(start -33.472 -11.06)
			(end 33.728 -11.06)
			(stroke
				(width 0.15)
				(type solid)
			)
			(layer "F.Fab")
		)
		(fp_line
			(start -33.622 -11.865)
			(end -33.472 -11.06)
			(stroke
				(width 0.15)
				(type solid)
			)
			(layer "F.Fab")
		)
		(fp_line
			(start -33.697 12.085)
			(end -33.697 -4.295)
			(stroke
				(width 0.15)
				(type solid)
			)
			(layer "F.Fab")
		)
		(fp_line
			(start -36.197 12.085)
			(end -33.697 12.085)
			(stroke
				(width 0.15)
				(type solid)
			)
			(layer "F.Fab")
		)
		(fp_line
			(start -36.197 -3.695)
			(end -36.197 12.085)
			(stroke
				(width 0.15)
				(type solid)
			)
			(layer "F.Fab")
		)
		(fp_line
			(start -36.597 -3.695)
			(end -36.197 -3.695)
			(stroke
				(width 0.15)
				(type solid)
			)
			(layer "F.Fab")
		)
		(fp_line
			(start -36.597 -11.865)
			(end -33.622 -11.865)
			(stroke
				(width 0.15)
				(type solid)
			)
			(layer "F.Fab")
		)
		(fp_line
			(start -36.597 -11.865)
			(end -36.597 -3.695)
			(stroke
				(width 0.15)
				(type solid)
			)
			(layer "F.Fab")
		)
		(pad "" np_thru_hole circle
			(at -34.395 -7.065 180)
			(size 1.25 1.25)
			(drill 1.25)
			(layers "*.Cu" "*.Mask")
		)
		(pad "" np_thru_hole circle
			(at 34.405 -7.065 180)
			(size 1.65 1.65)
			(drill 1.65)
			(layers "*.Cu" "*.Mask")
		)
		(pad "1" smd rect
			(at 33.38 -11.365 180)
			(size 0.3 1.5)
			(layers "F.Cu" "F.Mask" "F.Paste")
			(net 201 "+5V")
			(pinfunction "VIN_BULK")
			(pintype "passive")
		)
		(pad "2" smd rect
			(at 33.13 -3.965 180)
			(size 0.3 1.5)
			(layers "F.Cu" "F.Mask" "F.Paste")
			(net 49 "/DDR5 SODIMM/HSA")
			(pinfunction "HSA")
			(pintype "passive")
		)
		(pad "3" smd rect
			(at 32.88 -11.365 180)
			(size 0.3 1.5)
			(layers "F.Cu" "F.Mask" "F.Paste")
			(net 201 "+5V")
			(pinfunction "VIN_BULK")
			(pintype "passive")
		)
		(pad "4" smd rect
			(at 32.63 -3.965 180)
			(size 0.3 1.5)
			(layers "F.Cu" "F.Mask" "F.Paste")
			(net 50 "/DDR5 SODIMM/DDR.SCL")
			(pinfunction "HSCL")
			(pintype "passive")
		)
		(pad "5" smd rect
			(at 32.38 -11.365 180)
			(size 0.3 1.5)
			(layers "F.Cu" "F.Mask" "F.Paste")
			(net 137 "/DDR5 SODIMM/RFU1")
			(pinfunction "RFU")
			(pintype "passive")
		)
		(pad "6" smd rect
			(at 32.13 -3.965 180)
			(size 0.3 1.5)
			(layers "F.Cu" "F.Mask" "F.Paste")
			(net 54 "/DDR5 SODIMM/DDR.SDA")
			(pinfunction "HSDA")
			(pintype "passive")
		)
		(pad "7" smd rect
			(at 31.88 -11.365 180)
			(size 0.3 1.5)
			(layers "F.Cu" "F.Mask" "F.Paste")
			(net 313 "Net-(J2C-PWR_GOOD)")
			(pinfunction "PWR_GOOD")
			(pintype "passive")
		)
		(pad "8" smd rect
			(at 31.63 -3.965 180)
			(size 0.3 1.5)
			(layers "F.Cu" "F.Mask" "F.Paste")
			(net 314 "Net-(J2C-PWR_EN)")
			(pinfunction "PWR_EN")
			(pintype "passive")
		)
		(pad "9" smd rect
			(at 31.38 -11.365 180)
			(size 0.3 1.5)
			(layers "F.Cu" "F.Mask" "F.Paste")
			(net 1 "GND")
			(pinfunction "VSS")
			(pintype "passive")
		)
		(pad "10" smd rect
			(at 31.13 -3.965 180)
			(size 0.3 1.5)
			(layers "F.Cu" "F.Mask" "F.Paste")
			(net 1 "GND")
			(pinfunction "VSS")
			(pintype "passive")
		)
		(pad "11" smd rect
			(at 30.88 -11.365 180)
			(size 0.3 1.5)
			(layers "F.Cu" "F.Mask" "F.Paste")
			(net 55 "/DDR5 SODIMM/A.DQ0")
			(pinfunction "DQ0_A")
			(pintype "passive")
		)
		(pad "12" smd rect
			(at 30.63 -3.965 180)
			(size 0.3 1.5)
			(layers "F.Cu" "F.Mask" "F.Paste")
			(net 57 "/DDR5 SODIMM/A.DQ1")
			(pinfunction "DQ1_A")
			(pintype "passive")
		)
		(pad "13" smd rect
			(at 30.38 -11.365 180)
			(size 0.3 1.5)
			(layers "F.Cu" "F.Mask" "F.Paste")
			(net 1 "GND")
			(pinfunction "VSS")
			(pintype "passive")
		)
		(pad "14" smd rect
			(at 30.13 -3.965 180)
			(size 0.3 1.5)
			(layers "F.Cu" "F.Mask" "F.Paste")
			(net 1 "GND")
			(pinfunction "VSS")
			(pintype "passive")
		)
		(pad "15" smd rect
			(at 29.88 -11.365 180)
			(size 0.3 1.5)
			(layers "F.Cu" "F.Mask" "F.Paste")
			(net 59 "/DDR5 SODIMM/A.DQ2")
			(pinfunction "DQ2_A")
			(pintype "passive")
		)
		(pad "16" smd rect
			(at 29.63 -3.965 180)
			(size 0.3 1.5)
			(layers "F.Cu" "F.Mask" "F.Paste")
			(net 61 "/DDR5 SODIMM/A.DQ3")
			(pinfunction "DQ3_A")
			(pintype "passive")
		)
		(pad "17" smd rect
			(at 29.38 -11.365 180)
			(size 0.3 1.5)
			(layers "F.Cu" "F.Mask" "F.Paste")
			(net 1 "GND")
			(pinfunction "VSS")
			(pintype "passive")
		)
		(pad "18" smd rect
			(at 29.13 -3.965 180)
			(size 0.3 1.5)
			(layers "F.Cu" "F.Mask" "F.Paste")
			(net 1 "GND")
			(pinfunction "VSS")
			(pintype "passive")
		)
		(pad "19" smd rect
			(at 28.88 -11.365 180)
			(size 0.3 1.5)
			(layers "F.Cu" "F.Mask" "F.Paste")
			(net 65 "/DDR5 SODIMM/A.~{DM0}")
			(pinfunction "DM0_A_n")
			(pintype "passive")
		)
		(pad "20" smd rect
			(at 28.63 -3.965 180)
			(size 0.3 1.5)
			(layers "F.Cu" "F.Mask" "F.Paste")
			(net 68 "/DDR5 SODIMM/A.DQS0_N")
			(pinfunction "DQS0_A_C")
			(pintype "passive")
		)
		(pad "21" smd rect
			(at 28.38 -11.365 180)
			(size 0.3 1.5)
			(layers "F.Cu" "F.Mask" "F.Paste")
			(net 1 "GND")
			(pinfunction "VSS")
			(pintype "passive")
		)
		(pad "22" smd rect
			(at 28.13 -3.965 180)
			(size 0.3 1.5)
			(layers "F.Cu" "F.Mask" "F.Paste")
			(net 69 "/DDR5 SODIMM/A.DQS0_P")
			(pinfunction "DQS0_A_t")
			(pintype "passive")
		)
		(pad "23" smd rect
			(at 27.88 -11.365 180)
			(size 0.3 1.5)
			(layers "F.Cu" "F.Mask" "F.Paste")
			(net 70 "/DDR5 SODIMM/A.DQ4")
			(pinfunction "DQ4_A")
			(pintype "passive")
		)
		(pad "24" smd rect
			(at 27.63 -3.965 180)
			(size 0.3 1.5)
			(layers "F.Cu" "F.Mask" "F.Paste")
			(net 1 "GND")
			(pinfunction "VSS")
			(pintype "passive")
		)
		(pad "25" smd rect
			(at 27.38 -11.365 180)
			(size 0.3 1.5)
			(layers "F.Cu" "F.Mask" "F.Paste")
			(net 1 "GND")
			(pinfunction "VSS")
			(pintype "passive")
		)
		(pad "26" smd rect
			(at 27.13 -3.965 180)
			(size 0.3 1.5)
			(layers "F.Cu" "F.Mask" "F.Paste")
			(net 71 "/DDR5 SODIMM/A.DQ5")
			(pinfunction "DQ5_A")
			(pintype "passive")
		)
		(pad "27" smd rect
			(at 26.88 -11.365 180)
			(size 0.3 1.5)
			(layers "F.Cu" "F.Mask" "F.Paste")
			(net 72 "/DDR5 SODIMM/A.DQ6")
			(pinfunction "DQ6_A")
			(pintype "passive")
		)
		(pad "28" smd rect
			(at 26.63 -3.965 180)
			(size 0.3 1.5)
			(layers "F.Cu" "F.Mask" "F.Paste")
			(net 1 "GND")
			(pinfunction "VSS")
			(pintype "passive")
		)
		(pad "29" smd rect
			(at 26.38 -11.365 180)
			(size 0.3 1.5)
			(layers "F.Cu" "F.Mask" "F.Paste")
			(net 1 "GND")
			(pinfunction "VSS")
			(pintype "passive")
		)
		(pad "30" smd rect
			(at 26.13 -3.965 180)
			(size 0.3 1.5)
			(layers "F.Cu" "F.Mask" "F.Paste")
			(net 73 "/DDR5 SODIMM/A.DQ7")
			(pinfunction "DQ7_A")
			(pintype "passive")
		)
		(pad "31" smd rect
			(at 25.88 -11.365 180)
			(size 0.3 1.5)
			(layers "F.Cu" "F.Mask" "F.Paste")
			(net 74 "/DDR5 SODIMM/A.DQ8")
			(pinfunction "DQ8_A")
			(pintype "passive")
		)
		(pad "32" smd rect
			(at 25.63 -3.965 180)
			(size 0.3 1.5)
			(layers "F.Cu" "F.Mask" "F.Paste")
			(net 1 "GND")
			(pinfunction "VSS")
			(pintype "passive")
		)
		(pad "33" smd rect
			(at 25.38 -11.365 180)
			(size 0.3 1.5)
			(layers "F.Cu" "F.Mask" "F.Paste")
			(net 1 "GND")
			(pinfunction "VSS")
			(pintype "passive")
		)
		(pad "34" smd rect
			(at 25.13 -3.965 180)
			(size 0.3 1.5)
			(layers "F.Cu" "F.Mask" "F.Paste")
			(net 77 "/DDR5 SODIMM/A.DQ9")
			(pinfunction "DQ09_A")
			(pintype "passive")
		)
		(pad "35" smd rect
			(at 24.88 -11.365 180)
			(size 0.3 1.5)
			(layers "F.Cu" "F.Mask" "F.Paste")
			(net 79 "/DDR5 SODIMM/A.DQ10")
			(pinfunction "DQ10_A")
			(pintype "passive")
		)
		(pad "36" smd rect
			(at 24.63 -3.965 180)
			(size 0.3 1.5)
			(layers "F.Cu" "F.Mask" "F.Paste")
			(net 1 "GND")
			(pinfunction "VSS")
			(pintype "passive")
		)
		(pad "37" smd rect
			(at 24.38 -11.365 180)
			(size 0.3 1.5)
			(layers "F.Cu" "F.Mask" "F.Paste")
			(net 1 "GND")
			(pinfunction "VSS")
			(pintype "passive")
		)
		(pad "38" smd rect
			(at 24.13 -3.965 180)
			(size 0.3 1.5)
			(layers "F.Cu" "F.Mask" "F.Paste")
			(net 80 "/DDR5 SODIMM/A.DQ11")
			(pinfunction "DQ11_A")
			(pintype "passive")
		)
		(pad "39" smd rect
			(at 23.88 -11.365 180)
			(size 0.3 1.5)
			(layers "F.Cu" "F.Mask" "F.Paste")
			(net 81 "/DDR5 SODIMM/A.DQS1_N")
			(pinfunction "DQS1_A_C")
			(pintype "passive")
		)
		(pad "40" smd rect
			(at 23.63 -3.965 180)
			(size 0.3 1.5)
			(layers "F.Cu" "F.Mask" "F.Paste")
			(net 1 "GND")
			(pinfunction "VSS")
			(pintype "passive")
		)
		(pad "41" smd rect
			(at 23.38 -11.365 180)
			(size 0.3 1.5)
			(layers "F.Cu" "F.Mask" "F.Paste")
			(net 82 "/DDR5 SODIMM/A.DQS1_P")
			(pinfunction "DQS1_A_t")
			(pintype "passive")
		)
		(pad "42" smd rect
			(at 23.13 -3.965 180)
			(size 0.3 1.5)
			(layers "F.Cu" "F.Mask" "F.Paste")
			(net 83 "/DDR5 SODIMM/A.~{DM1}")
			(pinfunction "DM1_A_n")
			(pintype "passive")
		)
		(pad "43" smd rect
			(at 22.88 -11.365 180)
			(size 0.3 1.5)
			(layers "F.Cu" "F.Mask" "F.Paste")
			(net 1 "GND")
			(pinfunction "VSS")
			(pintype "passive")
		)
		(pad "44" smd rect
			(at 22.63 -3.965 180)
			(size 0.3 1.5)
			(layers "F.Cu" "F.Mask" "F.Paste")
			(net 1 "GND")
			(pinfunction "VSS")
			(pintype "passive")
		)
		(pad "45" smd rect
			(at 22.38 -11.365 180)
			(size 0.3 1.5)
			(layers "F.Cu" "F.Mask" "F.Paste")
			(net 84 "/DDR5 SODIMM/A.DQ12")
			(pinfunction "DQ12_A")
			(pintype "passive")
		)
		(pad "46" smd rect
			(at 22.13 -3.965 180)
			(size 0.3 1.5)
			(layers "F.Cu" "F.Mask" "F.Paste")
			(net 85 "/DDR5 SODIMM/A.DQ13")
			(pinfunction "DQ13_A")
			(pintype "passive")
		)
		(pad "47" smd rect
			(at 21.88 -11.365 180)
			(size 0.3 1.5)
			(layers "F.Cu" "F.Mask" "F.Paste")
			(net 1 "GND")
			(pinfunction "VSS")
			(pintype "passive")
		)
		(pad "48" smd rect
			(at 21.63 -3.965 180)
			(size 0.3 1.5)
			(layers "F.Cu" "F.Mask" "F.Paste")
			(net 1 "GND")
			(pinfunction "VSS")
			(pintype "passive")
		)
		(pad "49" smd rect
			(at 21.38 -11.365 180)
			(size 0.3 1.5)
			(layers "F.Cu" "F.Mask" "F.Paste")
			(net 87 "/DDR5 SODIMM/A.DQ14")
			(pinfunction "DQ14_A")
			(pintype "passive")
		)
		(pad "50" smd rect
			(at 21.13 -3.965 180)
			(size 0.3 1.5)
			(layers "F.Cu" "F.Mask" "F.Paste")
			(net 88 "/DDR5 SODIMM/A.DQ15")
			(pinfunction "DQ15_A")
			(pintype "passive")
		)
		(pad "51" smd rect
			(at 20.88 -11.365 180)
			(size 0.3 1.5)
			(layers "F.Cu" "F.Mask" "F.Paste")
			(net 1 "GND")
			(pinfunction "VSS")
			(pintype "passive")
		)
		(pad "52" smd rect
			(at 20.63 -3.965 180)
			(size 0.3 1.5)
			(layers "F.Cu" "F.Mask" "F.Paste")
			(net 1 "GND")
			(pinfunction "VSS")
			(pintype "passive")
		)
		(pad "53" smd rect
			(at 20.38 -11.365 180)
			(size 0.3 1.5)
			(layers "F.Cu" "F.Mask" "F.Paste")
			(net 89 "/DDR5 SODIMM/A.DQ16")
			(pinfunction "DQ16_A")
			(pintype "passive")
		)
		(pad "54" smd rect
			(at 20.13 -3.965 180)
			(size 0.3 1.5)
			(layers "F.Cu" "F.Mask" "F.Paste")
			(net 91 "/DDR5 SODIMM/A.DQ17")
			(pinfunction "DQ17_A")
			(pintype "passive")
		)
		(pad "55" smd rect
			(at 19.88 -11.365 180)
			(size 0.3 1.5)
			(layers "F.Cu" "F.Mask" "F.Paste")
			(net 1 "GND")
			(pinfunction "VSS")
			(pintype "passive")
		)
		(pad "56" smd rect
			(at 19.63 -3.965 180)
			(size 0.3 1.5)
			(layers "F.Cu" "F.Mask" "F.Paste")
			(net 1 "GND")
			(pinfunction "VSS")
			(pintype "passive")
		)
		(pad "57" smd rect
			(at 19.38 -11.365 180)
			(size 0.3 1.5)
			(layers "F.Cu" "F.Mask" "F.Paste")
			(net 92 "/DDR5 SODIMM/A.DQ18")
			(pinfunction "DQ18_A")
			(pintype "passive")
		)
		(pad "58" smd rect
			(at 19.13 -3.965 180)
			(size 0.3 1.5)
			(layers "F.Cu" "F.Mask" "F.Paste")
			(net 93 "/DDR5 SODIMM/A.DQ19")
			(pinfunction "DQ19_A")
			(pintype "passive")
		)
		(pad "59" smd rect
			(at 18.88 -11.365 180)
			(size 0.3 1.5)
			(layers "F.Cu" "F.Mask" "F.Paste")
			(net 1 "GND")
			(pinfunction "VSS")
			(pintype "passive")
		)
		(pad "60" smd rect
			(at 18.63 -3.965 180)
			(size 0.3 1.5)
			(layers "F.Cu" "F.Mask" "F.Paste")
			(net 1 "GND")
			(pinfunction "VSS")
			(pintype "passive")
		)
		(pad "61" smd rect
			(at 18.38 -11.365 180)
			(size 0.3 1.5)
			(layers "F.Cu" "F.Mask" "F.Paste")
			(net 94 "/DDR5 SODIMM/A.~{DM2}")
			(pinfunction "DM2_A_n")
			(pintype "passive")
		)
		(pad "62" smd rect
			(at 18.13 -3.965 180)
			(size 0.3 1.5)
			(layers "F.Cu" "F.Mask" "F.Paste")
			(net 95 "/DDR5 SODIMM/A.DQS2_N")
			(pinfunction "DQS2_A_C")
			(pintype "passive")
		)
		(pad "63" smd rect
			(at 17.88 -11.365 180)
			(size 0.3 1.5)
			(layers "F.Cu" "F.Mask" "F.Paste")
			(net 1 "GND")
			(pinfunction "VSS")
			(pintype "passive")
		)
		(pad "64" smd rect
			(at 17.63 -3.965 180)
			(size 0.3 1.5)
			(layers "F.Cu" "F.Mask" "F.Paste")
			(net 96 "/DDR5 SODIMM/A.DQS2_P")
			(pinfunction "DQS2_A_t")
			(pintype "passive")
		)
		(pad "65" smd rect
			(at 17.38 -11.365 180)
			(size 0.3 1.5)
			(layers "F.Cu" "F.Mask" "F.Paste")
			(net 97 "/DDR5 SODIMM/A.DQ20")
			(pinfunction "DQ20_A")
			(pintype "passive")
		)
		(pad "66" smd rect
			(at 17.13 -3.965 180)
			(size 0.3 1.5)
			(layers "F.Cu" "F.Mask" "F.Paste")
			(net 1 "GND")
			(pinfunction "VSS")
			(pintype "passive")
		)
		(pad "67" smd rect
			(at 16.88 -11.365 180)
			(size 0.3 1.5)
			(layers "F.Cu" "F.Mask" "F.Paste")
			(net 1 "GND")
			(pinfunction "VSS")
			(pintype "passive")
		)
		(pad "68" smd rect
			(at 16.63 -3.965 180)
			(size 0.3 1.5)
			(layers "F.Cu" "F.Mask" "F.Paste")
			(net 98 "/DDR5 SODIMM/A.DQ21")
			(pinfunction "DQ21_A")
			(pintype "passive")
		)
		(pad "69" smd rect
			(at 16.38 -11.365 180)
			(size 0.3 1.5)
			(layers "F.Cu" "F.Mask" "F.Paste")
			(net 99 "/DDR5 SODIMM/A.DQ22")
			(pinfunction "DQ22_A")
			(pintype "passive")
		)
		(pad "70" smd rect
			(at 16.13 -3.965 180)
			(size 0.3 1.5)
			(layers "F.Cu" "F.Mask" "F.Paste")
			(net 1 "GND")
			(pinfunction "VSS")
			(pintype "passive")
		)
		(pad "71" smd rect
			(at 15.88 -11.365 180)
			(size 0.3 1.5)
			(layers "F.Cu" "F.Mask" "F.Paste")
			(net 1 "GND")
			(pinfunction "VSS")
			(pintype "passive")
		)
		(pad "72" smd rect
			(at 15.63 -3.965 180)
			(size 0.3 1.5)
			(layers "F.Cu" "F.Mask" "F.Paste")
			(net 100 "/DDR5 SODIMM/A.DQ23")
			(pinfunction "DQ23_A")
			(pintype "passive")
		)
		(pad "73" smd rect
			(at 15.38 -11.365 180)
			(size 0.3 1.5)
			(layers "F.Cu" "F.Mask" "F.Paste")
			(net 102 "/DDR5 SODIMM/A.DQ24")
			(pinfunction "DQ24_A")
			(pintype "passive")
		)
		(pad "74" smd rect
			(at 15.13 -3.965 180)
			(size 0.3 1.5)
			(layers "F.Cu" "F.Mask" "F.Paste")
			(net 1 "GND")
			(pinfunction "VSS")
			(pintype "passive")
		)
		(pad "75" smd rect
			(at 14.88 -11.365 180)
			(size 0.3 1.5)
			(layers "F.Cu" "F.Mask" "F.Paste")
			(net 1 "GND")
			(pinfunction "VSS")
			(pintype "passive")
		)
		(pad "76" smd rect
			(at 14.63 -3.965 180)
			(size 0.3 1.5)
			(layers "F.Cu" "F.Mask" "F.Paste")
			(net 103 "/DDR5 SODIMM/A.DQ25")
			(pinfunction "DQ25_A")
			(pintype "passive")
		)
		(pad "77" smd rect
			(at 14.38 -11.365 180)
			(size 0.3 1.5)
			(layers "F.Cu" "F.Mask" "F.Paste")
			(net 104 "/DDR5 SODIMM/A.DQ26")
			(pinfunction "DQ26_A")
			(pintype "passive")
		)
		(pad "78" smd rect
			(at 14.13 -3.965 180)
			(size 0.3 1.5)
			(layers "F.Cu" "F.Mask" "F.Paste")
			(net 1 "GND")
			(pinfunction "VSS")
			(pintype "passive")
		)
		(pad "79" smd rect
			(at 13.88 -11.365 180)
			(size 0.3 1.5)
			(layers "F.Cu" "F.Mask" "F.Paste")
			(net 1 "GND")
			(pinfunction "VSS")
			(pintype "passive")
		)
		(pad "80" smd rect
			(at 13.63 -3.965 180)
			(size 0.3 1.5)
			(layers "F.Cu" "F.Mask" "F.Paste")
			(net 105 "/DDR5 SODIMM/A.DQ27")
			(pinfunction "DQ27_A")
			(pintype "passive")
		)
		(pad "81" smd rect
			(at 13.38 -11.365 180)
			(size 0.3 1.5)
			(layers "F.Cu" "F.Mask" "F.Paste")
			(net 107 "/DDR5 SODIMM/A.DQS3_N")
			(pinfunction "DQS3_A_C")
			(pintype "passive")
		)
		(pad "82" smd rect
			(at 13.13 -3.965 180)
			(size 0.3 1.5)
			(layers "F.Cu" "F.Mask" "F.Paste")
			(net 1 "GND")
			(pinfunction "VSS")
			(pintype "passive")
		)
		(pad "83" smd rect
			(at 12.88 -11.365 180)
			(size 0.3 1.5)
			(layers "F.Cu" "F.Mask" "F.Paste")
			(net 108 "/DDR5 SODIMM/A.DQS3_P")
			(pinfunction "DQS3_A_t")
			(pintype "passive")
		)
		(pad "84" smd rect
			(at 12.63 -3.965 180)
			(size 0.3 1.5)
			(layers "F.Cu" "F.Mask" "F.Paste")
			(net 109 "/DDR5 SODIMM/A.~{DM3}")
			(pinfunction "DM3_A_n")
			(pintype "passive")
		)
		(pad "85" smd rect
			(at 12.38 -11.365 180)
			(size 0.3 1.5)
			(layers "F.Cu" "F.Mask" "F.Paste")
			(net 1 "GND")
			(pinfunction "VSS")
			(pintype "passive")
		)
		(pad "86" smd rect
			(at 12.13 -3.965 180)
			(size 0.3 1.5)
			(layers "F.Cu" "F.Mask" "F.Paste")
			(net 1 "GND")
			(pinfunction "VSS")
			(pintype "passive")
		)
		(pad "87" smd rect
			(at 11.88 -11.365 180)
			(size 0.3 1.5)
			(layers "F.Cu" "F.Mask" "F.Paste")
			(net 110 "/DDR5 SODIMM/A.DQ28")
			(pinfunction "DQ28_A")
			(pintype "passive")
		)
		(pad "88" smd rect
			(at 11.63 -3.965 180)
			(size 0.3 1.5)
			(layers "F.Cu" "F.Mask" "F.Paste")
			(net 111 "/DDR5 SODIMM/A.DQ29")
			(pinfunction "DQ29_A")
			(pintype "passive")
		)
		(pad "89" smd rect
			(at 11.38 -11.365 180)
			(size 0.3 1.5)
			(layers "F.Cu" "F.Mask" "F.Paste")
			(net 1 "GND")
			(pinfunction "VSS")
			(pintype "passive")
		)
		(pad "90" smd rect
			(at 11.13 -3.965 180)
			(size 0.3 1.5)
			(layers "F.Cu" "F.Mask" "F.Paste")
			(net 1 "GND")
			(pinfunction "VSS")
			(pintype "passive")
		)
		(pad "91" smd rect
			(at 10.88 -11.365 180)
			(size 0.3 1.5)
			(layers "F.Cu" "F.Mask" "F.Paste")
			(net 112 "/DDR5 SODIMM/A.DQ30")
			(pinfunction "DQ30_A")
			(pintype "passive")
		)
		(pad "92" smd rect
			(at 10.63 -3.965 180)
			(size 0.3 1.5)
			(layers "F.Cu" "F.Mask" "F.Paste")
			(net 113 "/DDR5 SODIMM/A.DQ31")
			(pinfunction "DQ31_A")
			(pintype "passive")
		)
		(pad "93" smd rect
			(at 10.38 -11.365 180)
			(size 0.3 1.5)
			(layers "F.Cu" "F.Mask" "F.Paste")
			(net 1 "GND")
			(pinfunction "VSS")
			(pintype "passive")
		)
		(pad "94" smd rect
			(at 10.13 -3.965 180)
			(size 0.3 1.5)
			(layers "F.Cu" "F.Mask" "F.Paste")
			(net 1 "GND")
			(pinfunction "VSS")
			(pintype "passive")
		)
		(pad "95" smd rect
			(at 9.88 -11.365 180)
			(size 0.3 1.5)
			(layers "F.Cu" "F.Mask" "F.Paste")
			(net 114 "/DDR5 SODIMM/A.CB0")
			(pinfunction "CB0_A")
			(pintype "passive")
		)
		(pad "96" smd rect
			(at 9.63 -3.965 180)
			(size 0.3 1.5)
			(layers "F.Cu" "F.Mask" "F.Paste")
			(net 115 "/DDR5 SODIMM/A.CB1")
			(pinfunction "CB1_A")
			(pintype "passive")
		)
		(pad "97" smd rect
			(at 9.38 -11.365 180)
			(size 0.3 1.5)
			(layers "F.Cu" "F.Mask" "F.Paste")
			(net 1 "GND")
			(pinfunction "VSS")
			(pintype "passive")
		)
		(pad "98" smd rect
			(at 9.13 -3.965 180)
			(size 0.3 1.5)
			(layers "F.Cu" "F.Mask" "F.Paste")
			(net 1 "GND")
			(pinfunction "VSS")
			(pintype "passive")
		)
		(pad "99" smd rect
			(at 8.88 -11.365 180)
			(size 0.3 1.5)
			(layers "F.Cu" "F.Mask" "F.Paste")
			(net 116 "/DDR5 SODIMM/A.CB2")
			(pinfunction "CB2_A")
			(pintype "passive")
		)
		(pad "100" smd rect
			(at 8.63 -3.965 180)
			(size 0.3 1.5)
			(layers "F.Cu" "F.Mask" "F.Paste")
			(net 117 "/DDR5 SODIMM/A.DQS4_N")
			(pinfunction "DQS4_A_c")
			(pintype "passive")
		)
		(pad "101" smd rect
			(at 8.38 -11.365 180)
			(size 0.3 1.5)
			(layers "F.Cu" "F.Mask" "F.Paste")
			(net 1 "GND")
			(pinfunction "VSS")
			(pintype "passive")
		)
		(pad "102" smd rect
			(at 8.13 -3.965 180)
			(size 0.3 1.5)
			(layers "F.Cu" "F.Mask" "F.Paste")
			(net 118 "/DDR5 SODIMM/A.DQS4_P")
			(pinfunction "DQS4_A_t")
			(pintype "passive")
		)
		(pad "103" smd rect
			(at 7.88 -11.365 180)
			(size 0.3 1.5)
			(layers "F.Cu" "F.Mask" "F.Paste")
			(net 119 "/DDR5 SODIMM/A.CB3")
			(pinfunction "CB3_A")
			(pintype "passive")
		)
		(pad "104" smd rect
			(at 7.63 -3.965 180)
			(size 0.3 1.5)
			(layers "F.Cu" "F.Mask" "F.Paste")
			(net 1 "GND")
			(pinfunction "VSS")
			(pintype "passive")
		)
		(pad "105" smd rect
			(at 7.38 -11.365 180)
			(size 0.3 1.5)
			(layers "F.Cu" "F.Mask" "F.Paste")
			(net 1 "GND")
			(pinfunction "VSS")
			(pintype "passive")
		)
		(pad "106" smd rect
			(at 7.13 -3.965 180)
			(size 0.3 1.5)
			(layers "F.Cu" "F.Mask" "F.Paste")
			(net 120 "/DDR5 SODIMM/A.~{CS0}")
			(pinfunction "CS0_A_n")
			(pintype "passive")
		)
		(pad "107" smd rect
			(at 6.88 -11.365 180)
			(size 0.3 1.5)
			(layers "F.Cu" "F.Mask" "F.Paste")
			(net 121 "/DDR5 SODIMM/A.CA0")
			(pinfunction "CA0_A")
			(pintype "passive")
		)
		(pad "108" smd rect
			(at 6.63 -3.965 180)
			(size 0.3 1.5)
			(layers "F.Cu" "F.Mask" "F.Paste")
			(net 122 "/DDR5 SODIMM/Control.~{ALERT}")
			(pinfunction "ALERT_n")
			(pintype "passive")
		)
		(pad "109" smd rect
			(at 6.38 -11.365 180)
			(size 0.3 1.5)
			(layers "F.Cu" "F.Mask" "F.Paste")
			(net 136 "/DDR5 SODIMM/A.CA1")
			(pinfunction "CA1_A")
			(pintype "passive")
		)
		(pad "110" smd rect
			(at 6.13 -3.965 180)
			(size 0.3 1.5)
			(layers "F.Cu" "F.Mask" "F.Paste")
			(net 138 "/DDR5 SODIMM/A.~{CS1}")
			(pinfunction "CS1_A_n")
			(pintype "passive")
		)
		(pad "111" smd rect
			(at 5.88 -11.365 180)
			(size 0.3 1.5)
			(layers "F.Cu" "F.Mask" "F.Paste")
			(net 1 "GND")
			(pinfunction "VSS")
			(pintype "passive")
		)
		(pad "112" smd rect
			(at 5.63 -3.965 180)
			(size 0.3 1.5)
			(layers "F.Cu" "F.Mask" "F.Paste")
			(net 1 "GND")
			(pinfunction "VSS")
			(pintype "passive")
		)
		(pad "113" smd rect
			(at 5.38 -11.365 180)
			(size 0.3 1.5)
			(layers "F.Cu" "F.Mask" "F.Paste")
			(net 139 "/DDR5 SODIMM/A.CA2")
			(pinfunction "CA2_A")
			(pintype "passive")
		)
		(pad "114" smd rect
			(at 5.13 -3.965 180)
			(size 0.3 1.5)
			(layers "F.Cu" "F.Mask" "F.Paste")
			(net 147 "/DDR5 SODIMM/A.CA3")
			(pinfunction "CA3_A")
			(pintype "passive")
		)
		(pad "115" smd rect
			(at 4.88 -11.365 180)
			(size 0.3 1.5)
			(layers "F.Cu" "F.Mask" "F.Paste")
			(net 148 "/DDR5 SODIMM/A.CA4")
			(pinfunction "CA4_A")
			(pintype "passive")
		)
		(pad "116" smd rect
			(at 4.63 -3.965 180)
			(size 0.3 1.5)
			(layers "F.Cu" "F.Mask" "F.Paste")
			(net 149 "/DDR5 SODIMM/A.CA5")
			(pinfunction "CA5_A")
			(pintype "passive")
		)
		(pad "117" smd rect
			(at 4.38 -11.365 180)
			(size 0.3 1.5)
			(layers "F.Cu" "F.Mask" "F.Paste")
			(net 1 "GND")
			(pinfunction "VSS")
			(pintype "passive")
		)
		(pad "118" smd rect
			(at 4.13 -3.965 180)
			(size 0.3 1.5)
			(layers "F.Cu" "F.Mask" "F.Paste")
			(net 1 "GND")
			(pinfunction "VSS")
			(pintype "passive")
		)
		(pad "119" smd rect
			(at 3.88 -11.365 180)
			(size 0.3 1.5)
			(layers "F.Cu" "F.Mask" "F.Paste")
			(net 150 "/DDR5 SODIMM/A.CA6")
			(pinfunction "CA6_A")
			(pintype "passive")
		)
		(pad "120" smd rect
			(at 3.63 -3.965 180)
			(size 0.3 1.5)
			(layers "F.Cu" "F.Mask" "F.Paste")
			(net 151 "/DDR5 SODIMM/A.CA7")
			(pinfunction "CA7_A")
			(pintype "passive")
		)
		(pad "121" smd rect
			(at 3.38 -11.365 180)
			(size 0.3 1.5)
			(layers "F.Cu" "F.Mask" "F.Paste")
			(net 152 "/DDR5 SODIMM/A.CA8")
			(pinfunction "CA8_A")
			(pintype "passive")
		)
		(pad "122" smd rect
			(at 3.13 -3.965 180)
			(size 0.3 1.5)
			(layers "F.Cu" "F.Mask" "F.Paste")
			(net 153 "/DDR5 SODIMM/A.CA9")
			(pinfunction "CA9_A")
			(pintype "passive")
		)
		(pad "123" smd rect
			(at 2.88 -11.365 180)
			(size 0.3 1.5)
			(layers "F.Cu" "F.Mask" "F.Paste")
			(net 1 "GND")
			(pinfunction "VSS")
			(pintype "passive")
		)
		(pad "124" smd rect
			(at 2.63 -3.965 180)
			(size 0.3 1.5)
			(layers "F.Cu" "F.Mask" "F.Paste")
			(net 140 "/DDR5 SODIMM/VSS_DET1")
			(pinfunction "SDM_DETECT")
			(pintype "passive")
		)
		(pad "125" smd rect
			(at 2.38 -11.365 180)
			(size 0.3 1.5)
			(layers "F.Cu" "F.Mask" "F.Paste")
			(net 154 "/DDR5 SODIMM/A.CA10")
			(pinfunction "CA10_A")
			(pintype "passive")
		)
		(pad "126" smd rect
			(at 2.13 -3.965 180)
			(size 0.3 1.5)
			(layers "F.Cu" "F.Mask" "F.Paste")
			(net 155 "/DDR5 SODIMM/A.CA11")
			(pinfunction "CA11_A")
			(pintype "passive")
		)
		(pad "127" smd rect
			(at 0.38 -11.365 180)
			(size 0.3 1.5)
			(layers "F.Cu" "F.Mask" "F.Paste")
			(net 156 "/DDR5 SODIMM/A.CA12")
			(pinfunction "CA12_A")
			(pintype "passive")
		)
		(pad "128" smd rect
			(at 0.13 -3.965 180)
			(size 0.3 1.5)
			(layers "F.Cu" "F.Mask" "F.Paste")
			(net 171 "/DDR5 SODIMM/RFU2")
			(pinfunction "RFU")
			(pintype "passive")
		)
		(pad "129" smd rect
			(at -0.12 -11.365 180)
			(size 0.3 1.5)
			(layers "F.Cu" "F.Mask" "F.Paste")
			(net 1 "GND")
			(pinfunction "VSS")
			(pintype "passive")
		)
		(pad "130" smd rect
			(at -0.37 -3.965 180)
			(size 0.3 1.5)
			(layers "F.Cu" "F.Mask" "F.Paste")
			(net 172 "/DDR5 SODIMM/VSS_DET2")
			(pinfunction "TB_DETECT")
			(pintype "passive")
		)
		(pad "131" smd rect
			(at -0.62 -11.365 180)
			(size 0.3 1.5)
			(layers "F.Cu" "F.Mask" "F.Paste")
			(net 157 "/DDR5 SODIMM/A.CK0_P")
			(pinfunction "CK0_A_t")
			(pintype "passive")
		)
		(pad "132" smd rect
			(at -0.87 -3.965 180)
			(size 0.3 1.5)
			(layers "F.Cu" "F.Mask" "F.Paste")
			(net 158 "/DDR5 SODIMM/A.CK1_P")
			(pinfunction "CK1_A_t")
			(pintype "passive")
		)
		(pad "133" smd rect
			(at -1.12 -11.365 180)
			(size 0.3 1.5)
			(layers "F.Cu" "F.Mask" "F.Paste")
			(net 159 "/DDR5 SODIMM/A.CK0_N")
			(pinfunction "CK0_A_c")
			(pintype "passive")
		)
		(pad "134" smd rect
			(at -1.37 -3.965 180)
			(size 0.3 1.5)
			(layers "F.Cu" "F.Mask" "F.Paste")
			(net 160 "/DDR5 SODIMM/A.CK1_N")
			(pinfunction "CK1_A_c")
			(pintype "passive")
		)
		(pad "135" smd rect
			(at -1.62 -11.365 180)
			(size 0.3 1.5)
			(layers "F.Cu" "F.Mask" "F.Paste")
			(net 1 "GND")
			(pinfunction "VSS")
			(pintype "passive")
		)
		(pad "136" smd rect
			(at -1.87 -3.965 180)
			(size 0.3 1.5)
			(layers "F.Cu" "F.Mask" "F.Paste")
			(net 1 "GND")
			(pinfunction "VSS")
			(pintype "passive")
		)
		(pad "137" smd rect
			(at -2.12 -11.365 180)
			(size 0.3 1.5)
			(layers "F.Cu" "F.Mask" "F.Paste")
			(net 161 "/DDR5 SODIMM/B.CK0_P")
			(pinfunction "CK0_B_t")
			(pintype "passive")
		)
		(pad "138" smd rect
			(at -2.37 -3.965 180)
			(size 0.3 1.5)
			(layers "F.Cu" "F.Mask" "F.Paste")
			(net 162 "/DDR5 SODIMM/B.CK1_P")
			(pinfunction "CK1_B_t")
			(pintype "passive")
		)
		(pad "139" smd rect
			(at -2.62 -11.365 180)
			(size 0.3 1.5)
			(layers "F.Cu" "F.Mask" "F.Paste")
			(net 163 "/DDR5 SODIMM/B.CK0_N")
			(pinfunction "CK0_B_c")
			(pintype "passive")
		)
		(pad "140" smd rect
			(at -2.87 -3.965 180)
			(size 0.3 1.5)
			(layers "F.Cu" "F.Mask" "F.Paste")
			(net 164 "/DDR5 SODIMM/B.CK1_N")
			(pinfunction "CK1_B_C")
			(pintype "passive")
		)
		(pad "141" smd rect
			(at -3.12 -11.365 180)
			(size 0.3 1.5)
			(layers "F.Cu" "F.Mask" "F.Paste")
			(net 1 "GND")
			(pinfunction "VSS")
			(pintype "passive")
		)
		(pad "142" smd rect
			(at -3.37 -3.965 180)
			(size 0.3 1.5)
			(layers "F.Cu" "F.Mask" "F.Paste")
			(net 1 "GND")
			(pinfunction "VSS")
			(pintype "passive")
		)
		(pad "143" smd rect
			(at -3.62 -11.365 180)
			(size 0.3 1.5)
			(layers "F.Cu" "F.Mask" "F.Paste")
			(net 173 "/DDR5 SODIMM/RFU3")
			(pinfunction "RFU")
			(pintype "passive")
		)
		(pad "144" smd rect
			(at -3.87 -3.965 180)
			(size 0.3 1.5)
			(layers "F.Cu" "F.Mask" "F.Paste")
			(net 165 "/DDR5 SODIMM/B.CA12")
			(pinfunction "CA12_B")
			(pintype "passive")
		)
		(pad "145" smd rect
			(at -4.12 -11.365 180)
			(size 0.3 1.5)
			(layers "F.Cu" "F.Mask" "F.Paste")
			(net 166 "/DDR5 SODIMM/B.CA11")
			(pinfunction "CA11_B")
			(pintype "passive")
		)
		(pad "146" smd rect
			(at -4.37 -3.965 180)
			(size 0.3 1.5)
			(layers "F.Cu" "F.Mask" "F.Paste")
			(net 167 "/DDR5 SODIMM/B.CA10")
			(pinfunction "CA10_B")
			(pintype "passive")
		)
		(pad "147" smd rect
			(at -4.62 -11.365 180)
			(size 0.3 1.5)
			(layers "F.Cu" "F.Mask" "F.Paste")
			(net 1 "GND")
			(pinfunction "VSS")
			(pintype "passive")
		)
		(pad "148" smd rect
			(at -4.87 -3.965 180)
			(size 0.3 1.5)
			(layers "F.Cu" "F.Mask" "F.Paste")
			(net 1 "GND")
			(pinfunction "VSS")
			(pintype "passive")
		)
		(pad "149" smd rect
			(at -5.12 -11.365 180)
			(size 0.3 1.5)
			(layers "F.Cu" "F.Mask" "F.Paste")
			(net 168 "/DDR5 SODIMM/B.CA9")
			(pinfunction "CA9_B")
			(pintype "passive")
		)
		(pad "150" smd rect
			(at -5.37 -3.965 180)
			(size 0.3 1.5)
			(layers "F.Cu" "F.Mask" "F.Paste")
			(net 169 "/DDR5 SODIMM/B.CA8")
			(pinfunction "CA8_B")
			(pintype "passive")
		)
		(pad "151" smd rect
			(at -5.62 -11.365 180)
			(size 0.3 1.5)
			(layers "F.Cu" "F.Mask" "F.Paste")
			(net 170 "/DDR5 SODIMM/B.CA7")
			(pinfunction "CA7_B")
			(pintype "passive")
		)
		(pad "152" smd rect
			(at -5.87 -3.965 180)
			(size 0.3 1.5)
			(layers "F.Cu" "F.Mask" "F.Paste")
			(net 174 "/DDR5 SODIMM/B.CA6")
			(pinfunction "CA6_B")
			(pintype "passive")
		)
		(pad "153" smd rect
			(at -6.12 -11.365 180)
			(size 0.3 1.5)
			(layers "F.Cu" "F.Mask" "F.Paste")
			(net 1 "GND")
			(pinfunction "VSS")
			(pintype "passive")
		)
		(pad "154" smd rect
			(at -6.37 -3.965 180)
			(size 0.3 1.5)
			(layers "F.Cu" "F.Mask" "F.Paste")
			(net 1 "GND")
			(pinfunction "VSS")
			(pintype "passive")
		)
		(pad "155" smd rect
			(at -6.62 -11.365 180)
			(size 0.3 1.5)
			(layers "F.Cu" "F.Mask" "F.Paste")
			(net 176 "/DDR5 SODIMM/B.CA5")
			(pinfunction "CA5_B")
			(pintype "passive")
		)
		(pad "156" smd rect
			(at -6.87 -3.965 180)
			(size 0.3 1.5)
			(layers "F.Cu" "F.Mask" "F.Paste")
			(net 177 "/DDR5 SODIMM/B.CA4")
			(pinfunction "CA4_B")
			(pintype "passive")
		)
		(pad "157" smd rect
			(at -7.12 -11.365 180)
			(size 0.3 1.5)
			(layers "F.Cu" "F.Mask" "F.Paste")
			(net 178 "/DDR5 SODIMM/B.CA3")
			(pinfunction "CA3_B")
			(pintype "passive")
		)
		(pad "158" smd rect
			(at -7.37 -3.965 180)
			(size 0.3 1.5)
			(layers "F.Cu" "F.Mask" "F.Paste")
			(net 179 "/DDR5 SODIMM/B.CA2")
			(pinfunction "CA2_B")
			(pintype "passive")
		)
		(pad "159" smd rect
			(at -7.62 -11.365 180)
			(size 0.3 1.5)
			(layers "F.Cu" "F.Mask" "F.Paste")
			(net 1 "GND")
			(pinfunction "VSS")
			(pintype "passive")
		)
		(pad "160" smd rect
			(at -7.87 -3.965 180)
			(size 0.3 1.5)
			(layers "F.Cu" "F.Mask" "F.Paste")
			(net 1 "GND")
			(pinfunction "VSS")
			(pintype "passive")
		)
		(pad "161" smd rect
			(at -8.12 -11.365 180)
			(size 0.3 1.5)
			(layers "F.Cu" "F.Mask" "F.Paste")
			(net 180 "/DDR5 SODIMM/B.~{CS0}")
			(pinfunction "CS0_B_n")
			(pintype "passive")
		)
		(pad "162" smd rect
			(at -8.37 -3.965 180)
			(size 0.3 1.5)
			(layers "F.Cu" "F.Mask" "F.Paste")
			(net 181 "/DDR5 SODIMM/B.CA1")
			(pinfunction "CA1_B")
			(pintype "passive")
		)
		(pad "163" smd rect
			(at -8.62 -11.365 180)
			(size 0.3 1.5)
			(layers "F.Cu" "F.Mask" "F.Paste")
			(net 182 "/DDR5 SODIMM/Control.~{RESET}")
			(pinfunction "RESET_n")
			(pintype "passive")
		)
		(pad "164" smd rect
			(at -8.87 -3.965 180)
			(size 0.3 1.5)
			(layers "F.Cu" "F.Mask" "F.Paste")
			(net 183 "/DDR5 SODIMM/B.CA0")
			(pinfunction "CA0_B")
			(pintype "passive")
		)
		(pad "165" smd rect
			(at -9.12 -11.365 180)
			(size 0.3 1.5)
			(layers "F.Cu" "F.Mask" "F.Paste")
			(net 184 "/DDR5 SODIMM/B.~{CS1}")
			(pinfunction "CS1_B_N")
			(pintype "passive")
		)
		(pad "166" smd rect
			(at -9.37 -3.965 180)
			(size 0.3 1.5)
			(layers "F.Cu" "F.Mask" "F.Paste")
			(net 1 "GND")
			(pinfunction "VSS")
			(pintype "passive")
		)
		(pad "167" smd rect
			(at -9.62 -11.365 180)
			(size 0.3 1.5)
			(layers "F.Cu" "F.Mask" "F.Paste")
			(net 1 "GND")
			(pinfunction "VSS")
			(pintype "passive")
		)
		(pad "168" smd rect
			(at -9.87 -3.965 180)
			(size 0.3 1.5)
			(layers "F.Cu" "F.Mask" "F.Paste")
			(net 189 "/DDR5 SODIMM/B.CB0")
			(pinfunction "CB0_B")
			(pintype "passive")
		)
		(pad "169" smd rect
			(at -10.12 -11.365 180)
			(size 0.3 1.5)
			(layers "F.Cu" "F.Mask" "F.Paste")
			(net 190 "/DDR5 SODIMM/B.DQS4_N")
			(pinfunction "DQS4_B_c")
			(pintype "passive")
		)
		(pad "170" smd rect
			(at -10.37 -3.965 180)
			(size 0.3 1.5)
			(layers "F.Cu" "F.Mask" "F.Paste")
			(net 1 "GND")
			(pinfunction "VSS")
			(pintype "passive")
		)
		(pad "171" smd rect
			(at -10.62 -11.365 180)
			(size 0.3 1.5)
			(layers "F.Cu" "F.Mask" "F.Paste")
			(net 191 "/DDR5 SODIMM/B.DQS4_P")
			(pinfunction "DQS4_B_T")
			(pintype "passive")
		)
		(pad "172" smd rect
			(at -10.87 -3.965 180)
			(size 0.3 1.5)
			(layers "F.Cu" "F.Mask" "F.Paste")
			(net 192 "/DDR5 SODIMM/B.CB1")
			(pinfunction "CB1_B")
			(pintype "passive")
		)
		(pad "173" smd rect
			(at -11.12 -11.365 180)
			(size 0.3 1.5)
			(layers "F.Cu" "F.Mask" "F.Paste")
			(net 1 "GND")
			(pinfunction "VSS")
			(pintype "passive")
		)
		(pad "174" smd rect
			(at -11.37 -3.965 180)
			(size 0.3 1.5)
			(layers "F.Cu" "F.Mask" "F.Paste")
			(net 1 "GND")
			(pinfunction "VSS")
			(pintype "passive")
		)
		(pad "175" smd rect
			(at -11.62 -11.365 180)
			(size 0.3 1.5)
			(layers "F.Cu" "F.Mask" "F.Paste")
			(net 193 "/DDR5 SODIMM/B.CB3")
			(pinfunction "CB3_B")
			(pintype "passive")
		)
		(pad "176" smd rect
			(at -11.87 -3.965 180)
			(size 0.3 1.5)
			(layers "F.Cu" "F.Mask" "F.Paste")
			(net 194 "/DDR5 SODIMM/B.CB2")
			(pinfunction "CB2_B")
			(pintype "passive")
		)
		(pad "177" smd rect
			(at -12.12 -11.365 180)
			(size 0.3 1.5)
			(layers "F.Cu" "F.Mask" "F.Paste")
			(net 1 "GND")
			(pinfunction "VSS")
			(pintype "passive")
		)
		(pad "178" smd rect
			(at -12.37 -3.965 180)
			(size 0.3 1.5)
			(layers "F.Cu" "F.Mask" "F.Paste")
			(net 1 "GND")
			(pinfunction "VSS")
			(pintype "passive")
		)
		(pad "179" smd rect
			(at -12.62 -11.365 180)
			(size 0.3 1.5)
			(layers "F.Cu" "F.Mask" "F.Paste")
			(net 195 "/DDR5 SODIMM/B.DQ0")
			(pinfunction "DQ0_B")
			(pintype "passive")
		)
		(pad "180" smd rect
			(at -12.87 -3.965 180)
			(size 0.3 1.5)
			(layers "F.Cu" "F.Mask" "F.Paste")
			(net 196 "/DDR5 SODIMM/B.DQ1")
			(pinfunction "DQ1_B")
			(pintype "passive")
		)
		(pad "181" smd rect
			(at -13.12 -11.365 180)
			(size 0.3 1.5)
			(layers "F.Cu" "F.Mask" "F.Paste")
			(net 1 "GND")
			(pinfunction "VSS")
			(pintype "passive")
		)
		(pad "182" smd rect
			(at -13.37 -3.965 180)
			(size 0.3 1.5)
			(layers "F.Cu" "F.Mask" "F.Paste")
			(net 1 "GND")
			(pinfunction "VSS")
			(pintype "passive")
		)
		(pad "183" smd rect
			(at -13.62 -11.365 180)
			(size 0.3 1.5)
			(layers "F.Cu" "F.Mask" "F.Paste")
			(net 197 "/DDR5 SODIMM/B.DQ2")
			(pinfunction "DQ2_B")
			(pintype "passive")
		)
		(pad "184" smd rect
			(at -13.87 -3.965 180)
			(size 0.3 1.5)
			(layers "F.Cu" "F.Mask" "F.Paste")
			(net 198 "/DDR5 SODIMM/B.DQ3")
			(pinfunction "DQ3_B")
			(pintype "passive")
		)
		(pad "185" smd rect
			(at -14.12 -11.365 180)
			(size 0.3 1.5)
			(layers "F.Cu" "F.Mask" "F.Paste")
			(net 1 "GND")
			(pinfunction "VSS")
			(pintype "passive")
		)
		(pad "186" smd rect
			(at -14.37 -3.965 180)
			(size 0.3 1.5)
			(layers "F.Cu" "F.Mask" "F.Paste")
			(net 1 "GND")
			(pinfunction "VSS")
			(pintype "passive")
		)
		(pad "187" smd rect
			(at -14.62 -11.365 180)
			(size 0.3 1.5)
			(layers "F.Cu" "F.Mask" "F.Paste")
			(net 202 "/DDR5 SODIMM/B.~{DM0}")
			(pinfunction "DM0_B_n")
			(pintype "passive")
		)
		(pad "188" smd rect
			(at -14.87 -3.965 180)
			(size 0.3 1.5)
			(layers "F.Cu" "F.Mask" "F.Paste")
			(net 203 "/DDR5 SODIMM/B.DQS0_N")
			(pinfunction "DQS0_B_C")
			(pintype "passive")
		)
		(pad "189" smd rect
			(at -15.12 -11.365 180)
			(size 0.3 1.5)
			(layers "F.Cu" "F.Mask" "F.Paste")
			(net 1 "GND")
			(pinfunction "VSS")
			(pintype "passive")
		)
		(pad "190" smd rect
			(at -15.37 -3.965 180)
			(size 0.3 1.5)
			(layers "F.Cu" "F.Mask" "F.Paste")
			(net 204 "/DDR5 SODIMM/B.DQS0_P")
			(pinfunction "DQS0_B_t")
			(pintype "passive")
		)
		(pad "191" smd rect
			(at -15.62 -11.365 180)
			(size 0.3 1.5)
			(layers "F.Cu" "F.Mask" "F.Paste")
			(net 205 "/DDR5 SODIMM/B.DQ4")
			(pinfunction "DQ4_B")
			(pintype "passive")
		)
		(pad "192" smd rect
			(at -15.87 -3.965 180)
			(size 0.3 1.5)
			(layers "F.Cu" "F.Mask" "F.Paste")
			(net 1 "GND")
			(pinfunction "VSS")
			(pintype "passive")
		)
		(pad "193" smd rect
			(at -16.12 -11.365 180)
			(size 0.3 1.5)
			(layers "F.Cu" "F.Mask" "F.Paste")
			(net 1 "GND")
			(pinfunction "VSS")
			(pintype "passive")
		)
		(pad "194" smd rect
			(at -16.37 -3.965 180)
			(size 0.3 1.5)
			(layers "F.Cu" "F.Mask" "F.Paste")
			(net 212 "/DDR5 SODIMM/B.DQ5")
			(pinfunction "DQ5_B")
			(pintype "passive")
		)
		(pad "195" smd rect
			(at -16.62 -11.365 180)
			(size 0.3 1.5)
			(layers "F.Cu" "F.Mask" "F.Paste")
			(net 213 "/DDR5 SODIMM/B.DQ6")
			(pinfunction "DQ6_B")
			(pintype "passive")
		)
		(pad "196" smd rect
			(at -16.87 -3.965 180)
			(size 0.3 1.5)
			(layers "F.Cu" "F.Mask" "F.Paste")
			(net 1 "GND")
			(pinfunction "VSS")
			(pintype "passive")
		)
		(pad "197" smd rect
			(at -17.12 -11.365 180)
			(size 0.3 1.5)
			(layers "F.Cu" "F.Mask" "F.Paste")
			(net 1 "GND")
			(pinfunction "VSS")
			(pintype "passive")
		)
		(pad "198" smd rect
			(at -17.37 -3.965 180)
			(size 0.3 1.5)
			(layers "F.Cu" "F.Mask" "F.Paste")
			(net 219 "/DDR5 SODIMM/B.DQ7")
			(pinfunction "DQ7_B")
			(pintype "passive")
		)
		(pad "199" smd rect
			(at -17.62 -11.365 180)
			(size 0.3 1.5)
			(layers "F.Cu" "F.Mask" "F.Paste")
			(net 228 "/DDR5 SODIMM/B.DQ8")
			(pinfunction "DQ8_B")
			(pintype "passive")
		)
		(pad "200" smd rect
			(at -17.87 -3.965 180)
			(size 0.3 1.5)
			(layers "F.Cu" "F.Mask" "F.Paste")
			(net 1 "GND")
			(pinfunction "VSS")
			(pintype "passive")
		)
		(pad "201" smd rect
			(at -18.12 -11.365 180)
			(size 0.3 1.5)
			(layers "F.Cu" "F.Mask" "F.Paste")
			(net 1 "GND")
			(pinfunction "VSS")
			(pintype "passive")
		)
		(pad "202" smd rect
			(at -18.37 -3.965 180)
			(size 0.3 1.5)
			(layers "F.Cu" "F.Mask" "F.Paste")
			(net 233 "/DDR5 SODIMM/B.DQ9")
			(pinfunction "DQ9_B")
			(pintype "passive")
		)
		(pad "203" smd rect
			(at -18.62 -11.365 180)
			(size 0.3 1.5)
			(layers "F.Cu" "F.Mask" "F.Paste")
			(net 238 "/DDR5 SODIMM/B.DQ10")
			(pinfunction "DQ10_B")
			(pintype "passive")
		)
		(pad "204" smd rect
			(at -18.87 -3.965 180)
			(size 0.3 1.5)
			(layers "F.Cu" "F.Mask" "F.Paste")
			(net 1 "GND")
			(pinfunction "VSS")
			(pintype "passive")
		)
		(pad "205" smd rect
			(at -19.12 -11.365 180)
			(size 0.3 1.5)
			(layers "F.Cu" "F.Mask" "F.Paste")
			(net 1 "GND")
			(pinfunction "VSS")
			(pintype "passive")
		)
		(pad "206" smd rect
			(at -19.37 -3.965 180)
			(size 0.3 1.5)
			(layers "F.Cu" "F.Mask" "F.Paste")
			(net 247 "/DDR5 SODIMM/B.DQ11")
			(pinfunction "DQ11_B")
			(pintype "passive")
		)
		(pad "207" smd rect
			(at -19.62 -11.365 180)
			(size 0.3 1.5)
			(layers "F.Cu" "F.Mask" "F.Paste")
			(net 250 "/DDR5 SODIMM/B.DQS1_N")
			(pinfunction "DQS1_B_C")
			(pintype "passive")
		)
		(pad "208" smd rect
			(at -19.87 -3.965 180)
			(size 0.3 1.5)
			(layers "F.Cu" "F.Mask" "F.Paste")
			(net 1 "GND")
			(pinfunction "VSS")
			(pintype "passive")
		)
		(pad "209" smd rect
			(at -20.12 -11.365 180)
			(size 0.3 1.5)
			(layers "F.Cu" "F.Mask" "F.Paste")
			(net 253 "/DDR5 SODIMM/B.DQS1_P")
			(pinfunction "DQS1_B_t")
			(pintype "passive")
		)
		(pad "210" smd rect
			(at -20.37 -3.965 180)
			(size 0.3 1.5)
			(layers "F.Cu" "F.Mask" "F.Paste")
			(net 254 "/DDR5 SODIMM/B.~{DM1}")
			(pinfunction "DM1_B_n")
			(pintype "passive")
		)
		(pad "211" smd rect
			(at -20.62 -11.365 180)
			(size 0.3 1.5)
			(layers "F.Cu" "F.Mask" "F.Paste")
			(net 1 "GND")
			(pinfunction "VSS")
			(pintype "passive")
		)
		(pad "212" smd rect
			(at -20.87 -3.965 180)
			(size 0.3 1.5)
			(layers "F.Cu" "F.Mask" "F.Paste")
			(net 1 "GND")
			(pinfunction "VSS")
			(pintype "passive")
		)
		(pad "213" smd rect
			(at -21.12 -11.365 180)
			(size 0.3 1.5)
			(layers "F.Cu" "F.Mask" "F.Paste")
			(net 255 "/DDR5 SODIMM/B.DQ12")
			(pinfunction "DQ12_B")
			(pintype "passive")
		)
		(pad "214" smd rect
			(at -21.37 -3.965 180)
			(size 0.3 1.5)
			(layers "F.Cu" "F.Mask" "F.Paste")
			(net 256 "/DDR5 SODIMM/B.DQ13")
			(pinfunction "DQ13_B")
			(pintype "passive")
		)
		(pad "215" smd rect
			(at -21.62 -11.365 180)
			(size 0.3 1.5)
			(layers "F.Cu" "F.Mask" "F.Paste")
			(net 1 "GND")
			(pinfunction "VSS")
			(pintype "passive")
		)
		(pad "216" smd rect
			(at -21.87 -3.965 180)
			(size 0.3 1.5)
			(layers "F.Cu" "F.Mask" "F.Paste")
			(net 1 "GND")
			(pinfunction "VSS")
			(pintype "passive")
		)
		(pad "217" smd rect
			(at -22.12 -11.365 180)
			(size 0.3 1.5)
			(layers "F.Cu" "F.Mask" "F.Paste")
			(net 257 "/DDR5 SODIMM/B.DQ14")
			(pinfunction "DQ14_B")
			(pintype "passive")
		)
		(pad "218" smd rect
			(at -22.37 -3.965 180)
			(size 0.3 1.5)
			(layers "F.Cu" "F.Mask" "F.Paste")
			(net 258 "/DDR5 SODIMM/B.DQ15")
			(pinfunction "DQ15_B")
			(pintype "passive")
		)
		(pad "219" smd rect
			(at -22.62 -11.365 180)
			(size 0.3 1.5)
			(layers "F.Cu" "F.Mask" "F.Paste")
			(net 1 "GND")
			(pinfunction "VSS")
			(pintype "passive")
		)
		(pad "220" smd rect
			(at -22.87 -3.965 180)
			(size 0.3 1.5)
			(layers "F.Cu" "F.Mask" "F.Paste")
			(net 1 "GND")
			(pinfunction "VSS")
			(pintype "passive")
		)
		(pad "221" smd rect
			(at -23.12 -11.365 180)
			(size 0.3 1.5)
			(layers "F.Cu" "F.Mask" "F.Paste")
			(net 259 "/DDR5 SODIMM/B.DQ16")
			(pinfunction "DQ16_B")
			(pintype "passive")
		)
		(pad "222" smd rect
			(at -23.37 -3.965 180)
			(size 0.3 1.5)
			(layers "F.Cu" "F.Mask" "F.Paste")
			(net 260 "/DDR5 SODIMM/B.DQ17")
			(pinfunction "DQ17_B")
			(pintype "passive")
		)
		(pad "223" smd rect
			(at -23.62 -11.365 180)
			(size 0.3 1.5)
			(layers "F.Cu" "F.Mask" "F.Paste")
			(net 1 "GND")
			(pinfunction "VSS")
			(pintype "passive")
		)
		(pad "224" smd rect
			(at -23.87 -3.965 180)
			(size 0.3 1.5)
			(layers "F.Cu" "F.Mask" "F.Paste")
			(net 1 "GND")
			(pinfunction "VSS")
			(pintype "passive")
		)
		(pad "225" smd rect
			(at -24.12 -11.365 180)
			(size 0.3 1.5)
			(layers "F.Cu" "F.Mask" "F.Paste")
			(net 261 "/DDR5 SODIMM/B.DQ18")
			(pinfunction "DQ18_B")
			(pintype "passive")
		)
		(pad "226" smd rect
			(at -24.37 -3.965 180)
			(size 0.3 1.5)
			(layers "F.Cu" "F.Mask" "F.Paste")
			(net 262 "/DDR5 SODIMM/B.DQ19")
			(pinfunction "DQ19_B")
			(pintype "passive")
		)
		(pad "227" smd rect
			(at -24.62 -11.365 180)
			(size 0.3 1.5)
			(layers "F.Cu" "F.Mask" "F.Paste")
			(net 1 "GND")
			(pinfunction "VSS")
			(pintype "passive")
		)
		(pad "228" smd rect
			(at -24.87 -3.965 180)
			(size 0.3 1.5)
			(layers "F.Cu" "F.Mask" "F.Paste")
			(net 1 "GND")
			(pinfunction "VSS")
			(pintype "passive")
		)
		(pad "229" smd rect
			(at -25.12 -11.365 180)
			(size 0.3 1.5)
			(layers "F.Cu" "F.Mask" "F.Paste")
			(net 264 "/DDR5 SODIMM/B.~{DM2}")
			(pinfunction "DM2_B_n")
			(pintype "passive")
		)
		(pad "230" smd rect
			(at -25.37 -3.965 180)
			(size 0.3 1.5)
			(layers "F.Cu" "F.Mask" "F.Paste")
			(net 265 "/DDR5 SODIMM/B.DQS2_N")
			(pinfunction "DQS2_B_C")
			(pintype "passive")
		)
		(pad "231" smd rect
			(at -25.62 -11.365 180)
			(size 0.3 1.5)
			(layers "F.Cu" "F.Mask" "F.Paste")
			(net 1 "GND")
			(pinfunction "VSS")
			(pintype "passive")
		)
		(pad "232" smd rect
			(at -25.87 -3.965 180)
			(size 0.3 1.5)
			(layers "F.Cu" "F.Mask" "F.Paste")
			(net 266 "/DDR5 SODIMM/B.DQS2_P")
			(pinfunction "DQS2_B_t")
			(pintype "passive")
		)
		(pad "233" smd rect
			(at -26.12 -11.365 180)
			(size 0.3 1.5)
			(layers "F.Cu" "F.Mask" "F.Paste")
			(net 268 "/DDR5 SODIMM/B.DQ20")
			(pinfunction "DQ20_B")
			(pintype "passive")
		)
		(pad "234" smd rect
			(at -26.37 -3.965 180)
			(size 0.3 1.5)
			(layers "F.Cu" "F.Mask" "F.Paste")
			(net 1 "GND")
			(pinfunction "VSS")
			(pintype "passive")
		)
		(pad "235" smd rect
			(at -26.62 -11.365 180)
			(size 0.3 1.5)
			(layers "F.Cu" "F.Mask" "F.Paste")
			(net 1 "GND")
			(pinfunction "VSS")
			(pintype "passive")
		)
		(pad "236" smd rect
			(at -26.87 -3.965 180)
			(size 0.3 1.5)
			(layers "F.Cu" "F.Mask" "F.Paste")
			(net 269 "/DDR5 SODIMM/B.DQ21")
			(pinfunction "DQ21_B")
			(pintype "passive")
		)
		(pad "237" smd rect
			(at -27.12 -11.365 180)
			(size 0.3 1.5)
			(layers "F.Cu" "F.Mask" "F.Paste")
			(net 270 "/DDR5 SODIMM/B.DQ22")
			(pinfunction "DQ22_B")
			(pintype "passive")
		)
		(pad "238" smd rect
			(at -27.37 -3.965 180)
			(size 0.3 1.5)
			(layers "F.Cu" "F.Mask" "F.Paste")
			(net 1 "GND")
			(pinfunction "VSS")
			(pintype "passive")
		)
		(pad "239" smd rect
			(at -27.62 -11.365 180)
			(size 0.3 1.5)
			(layers "F.Cu" "F.Mask" "F.Paste")
			(net 1 "GND")
			(pinfunction "VSS")
			(pintype "passive")
		)
		(pad "240" smd rect
			(at -27.87 -3.965 180)
			(size 0.3 1.5)
			(layers "F.Cu" "F.Mask" "F.Paste")
			(net 271 "/DDR5 SODIMM/B.DQ23")
			(pinfunction "DQ23_B")
			(pintype "passive")
		)
		(pad "241" smd rect
			(at -28.12 -11.365 180)
			(size 0.3 1.5)
			(layers "F.Cu" "F.Mask" "F.Paste")
			(net 275 "/DDR5 SODIMM/B.DQ24")
			(pinfunction "DQ24_B")
			(pintype "passive")
		)
		(pad "242" smd rect
			(at -28.37 -3.965 180)
			(size 0.3 1.5)
			(layers "F.Cu" "F.Mask" "F.Paste")
			(net 1 "GND")
			(pinfunction "VSS")
			(pintype "passive")
		)
		(pad "243" smd rect
			(at -28.62 -11.365 180)
			(size 0.3 1.5)
			(layers "F.Cu" "F.Mask" "F.Paste")
			(net 1 "GND")
			(pinfunction "VSS")
			(pintype "passive")
		)
		(pad "244" smd rect
			(at -28.87 -3.965 180)
			(size 0.3 1.5)
			(layers "F.Cu" "F.Mask" "F.Paste")
			(net 276 "/DDR5 SODIMM/B.DQ25")
			(pinfunction "DQ25_B")
			(pintype "passive")
		)
		(pad "245" smd rect
			(at -29.12 -11.365 180)
			(size 0.3 1.5)
			(layers "F.Cu" "F.Mask" "F.Paste")
			(net 277 "/DDR5 SODIMM/B.DQ26")
			(pinfunction "DQ26_B")
			(pintype "passive")
		)
		(pad "246" smd rect
			(at -29.37 -3.965 180)
			(size 0.3 1.5)
			(layers "F.Cu" "F.Mask" "F.Paste")
			(net 1 "GND")
			(pinfunction "VSS")
			(pintype "passive")
		)
		(pad "247" smd rect
			(at -29.62 -11.365 180)
			(size 0.3 1.5)
			(layers "F.Cu" "F.Mask" "F.Paste")
			(net 1 "GND")
			(pinfunction "VSS")
			(pintype "passive")
		)
		(pad "248" smd rect
			(at -29.87 -3.965 180)
			(size 0.3 1.5)
			(layers "F.Cu" "F.Mask" "F.Paste")
			(net 278 "/DDR5 SODIMM/B.DQ27")
			(pinfunction "DQ27_B")
			(pintype "passive")
		)
		(pad "249" smd rect
			(at -30.12 -11.365 180)
			(size 0.3 1.5)
			(layers "F.Cu" "F.Mask" "F.Paste")
			(net 279 "/DDR5 SODIMM/B.DQS3_N")
			(pinfunction "DQS3_B_c")
			(pintype "passive")
		)
		(pad "250" smd rect
			(at -30.37 -3.965 180)
			(size 0.3 1.5)
			(layers "F.Cu" "F.Mask" "F.Paste")
			(net 1 "GND")
			(pinfunction "VSS")
			(pintype "passive")
		)
		(pad "251" smd rect
			(at -30.62 -11.365 180)
			(size 0.3 1.5)
			(layers "F.Cu" "F.Mask" "F.Paste")
			(net 283 "/DDR5 SODIMM/B.DQS3_P")
			(pinfunction "DQS3_B_t")
			(pintype "passive")
		)
		(pad "252" smd rect
			(at -30.87 -3.965 180)
			(size 0.3 1.5)
			(layers "F.Cu" "F.Mask" "F.Paste")
			(net 284 "/DDR5 SODIMM/B.~{DM3}")
			(pinfunction "DM3_B_n")
			(pintype "passive")
		)
		(pad "253" smd rect
			(at -31.12 -11.365 180)
			(size 0.3 1.5)
			(layers "F.Cu" "F.Mask" "F.Paste")
			(net 1 "GND")
			(pinfunction "VSS")
			(pintype "passive")
		)
		(pad "254" smd rect
			(at -31.37 -3.965 180)
			(size 0.3 1.5)
			(layers "F.Cu" "F.Mask" "F.Paste")
			(net 1 "GND")
			(pinfunction "VSS")
			(pintype "passive")
		)
		(pad "255" smd rect
			(at -31.62 -11.365 180)
			(size 0.3 1.5)
			(layers "F.Cu" "F.Mask" "F.Paste")
			(net 286 "/DDR5 SODIMM/B.DQ28")
			(pinfunction "DQ28_B")
			(pintype "passive")
		)
		(pad "256" smd rect
			(at -31.87 -3.965 180)
			(size 0.3 1.5)
			(layers "F.Cu" "F.Mask" "F.Paste")
			(net 287 "/DDR5 SODIMM/B.DQ29")
			(pinfunction "DQ29_B")
			(pintype "passive")
		)
		(pad "257" smd rect
			(at -32.12 -11.365 180)
			(size 0.3 1.5)
			(layers "F.Cu" "F.Mask" "F.Paste")
			(net 1 "GND")
			(pinfunction "VSS")
			(pintype "passive")
		)
		(pad "258" smd rect
			(at -32.37 -3.965 180)
			(size 0.3 1.5)
			(layers "F.Cu" "F.Mask" "F.Paste")
			(net 1 "GND")
			(pinfunction "VSS")
			(pintype "passive")
		)
		(pad "259" smd rect
			(at -32.62 -11.365 180)
			(size 0.3 1.5)
			(layers "F.Cu" "F.Mask" "F.Paste")
			(net 288 "/DDR5 SODIMM/B.DQ30")
			(pinfunction "DQ30_B")
			(pintype "passive")
		)
		(pad "260" smd rect
			(at -32.87 -3.965 180)
			(size 0.3 1.5)
			(layers "F.Cu" "F.Mask" "F.Paste")
			(net 289 "/DDR5 SODIMM/B.DQ31")
			(pinfunction "DQ31_B")
			(pintype "passive")
		)
		(pad "261" smd rect
			(at -33.12 -11.365 180)
			(size 0.3 1.5)
			(layers "F.Cu" "F.Mask" "F.Paste")
			(net 1 "GND")
			(pinfunction "VSS")
			(pintype "passive")
		)
		(pad "262" smd rect
			(at -33.37 -3.965 180)
			(size 0.3 1.5)
			(layers "F.Cu" "F.Mask" "F.Paste")
			(net 1 "GND")
			(pinfunction "VSS")
			(pintype "passive")
		)
		(pad "SH" smd rect
			(at -33.795 3.735 180)
			(size 3.5 4.6)
			(layers "F.Cu" "F.Mask" "F.Paste")
			(net 1 "GND")
			(pintype "passive")
			(zone_connect 2)
		)
		(pad "SH" smd rect
			(at 33.805 3.735 180)
			(size 3.5 4.6)
			(layers "F.Cu" "F.Mask" "F.Paste")
			(net 1 "GND")
			(pintype "passive")
			(zone_connect 2)
		)
	)
	(footprint "antmicro-footprints:SC70-3"
		(layer "F.Cu")
		(at 86.350501 122.926 90)
		(property "Reference" "Q6"
			(at 0 -1.6 90)
			(layer "F.SilkS")
			(hide yes)
			(effects
				(font
					(size 0.7 0.7)
					(thickness 0.15)
				)
				(justify left bottom)
			)
		)
		(property "Value" "BSS138PW,115"
			(at 0 2.3 90)
			(layer "F.Fab")
			(effects
				(font
					(size 0.7 0.7)
					(thickness 0.15)
				)
				(justify left bottom)
			)
		)
		(property "Datasheet" "https://assets.nexperia.com/documents/data-sheet/BSS138PW.pdf"
			(at 0 0 90)
			(layer "F.Fab")
			(hide yes)
			(effects
				(font
					(size 1.27 1.27)
					(thickness 0.15)
				)
			)
		)
		(property "Description" "Power MOSFET, N Channel, 60 V, 320 mA, 0.9 ohm, SOT-323, Surface Mount"
			(at 0 0 90)
			(layer "F.Fab")
			(hide yes)
			(effects
				(font
					(size 1.27 1.27)
					(thickness 0.15)
				)
			)
		)
		(property "Author" "Antmicro"
			(at 209.276501 36.575499 0)
			(layer "F.Fab")
			(hide yes)
			(effects
				(font
					(size 1 1)
					(thickness 0.15)
				)
			)
		)
		(property "License" "Apache-2.0"
			(at 209.276501 36.575499 0)
			(layer "F.Fab")
			(hide yes)
			(effects
				(font
					(size 1 1)
					(thickness 0.15)
				)
			)
		)
		(property "MPN" "BSS138PW,115"
			(at 209.276501 36.575499 0)
			(layer "F.Fab")
			(hide yes)
			(effects
				(font
					(size 1 1)
					(thickness 0.15)
				)
			)
		)
		(property "Manufacturer" "Nexperia"
			(at 209.276501 36.575499 0)
			(layer "F.Fab")
			(hide yes)
			(effects
				(font
					(size 1 1)
					(thickness 0.15)
				)
			)
		)
		(sheetname "/FPGA bank 14/")
		(sheetfile "fpga-bank-14.kicad_sch")
		(attr smd)
		(fp_line
			(start -0.3 -1)
			(end 0.627 -0.999)
			(stroke
				(width 0.15)
				(type solid)
			)
			(layer "F.SilkS")
		)
		(fp_line
			(start 0.627 -0.6)
			(end 0.627 -0.999)
			(stroke
				(width 0.15)
				(type solid)
			)
			(layer "F.SilkS")
		)
		(fp_line
			(start 0.627 0.6)
			(end 0.627 1.001)
			(stroke
				(width 0.15)
				(type solid)
			)
			(layer "F.SilkS")
		)
		(fp_line
			(start -0.3 1)
			(end 0.627 1.001)
			(stroke
				(width 0.15)
				(type solid)
			)
			(layer "F.SilkS")
		)
		(fp_line
			(start 0.9 -1.3)
			(end 0.9 -0.4)
			(stroke
				(width 0.05)
				(type solid)
			)
			(layer "F.CrtYd")
		)
		(fp_line
			(start -0.9 -1.3)
			(end 0.9 -1.3)
			(stroke
				(width 0.05)
				(type solid)
			)
			(layer "F.CrtYd")
		)
		(fp_line
			(start -0.9 -1.3)
			(end -0.9 -1)
			(stroke
				(width 0.05)
				(type solid)
			)
			(layer "F.CrtYd")
		)
		(fp_line
			(start -0.9 -1)
			(end -1.4 -1)
			(stroke
				(width 0.05)
				(type solid)
			)
			(layer "F.CrtYd")
		)
		(fp_line
			(start 1.4 -0.4)
			(end 1.4 0.4)
			(stroke
				(width 0.05)
				(type solid)
			)
			(layer "F.CrtYd")
		)
		(fp_line
			(start 0.9 -0.4)
			(end 1.4 -0.4)
			(stroke
				(width 0.05)
				(type solid)
			)
			(layer "F.CrtYd")
		)
		(fp_line
			(start 1.4 0.4)
			(end 0.9 0.4)
			(stroke
				(width 0.05)
				(type solid)
			)
			(layer "F.CrtYd")
		)
		(fp_line
			(start 0.9 0.4)
			(end 0.9 1.3)
			(stroke
				(width 0.05)
				(type solid)
			)
			(layer "F.CrtYd")
		)
		(fp_line
			(start -0.9 1)
			(end -1.4 1)
			(stroke
				(width 0.05)
				(type solid)
			)
			(layer "F.CrtYd")
		)
		(fp_line
			(start -1.4 1)
			(end -1.4 -1)
			(stroke
				(width 0.05)
				(type solid)
			)
			(layer "F.CrtYd")
		)
		(fp_line
			(start 0.9 1.3)
			(end -0.9 1.3)
			(stroke
				(width 0.05)
				(type solid)
			)
			(layer "F.CrtYd")
		)
		(fp_line
			(start -0.9 1.3)
			(end -0.9 1)
			(stroke
				(width 0.05)
				(type solid)
			)
			(layer "F.CrtYd")
		)
		(fp_rect
			(start -0.623 -0.999)
			(end 0.627 1.001)
			(stroke
				(width 0.15)
				(type solid)
			)
			(fill no)
			(layer "F.Fab")
		)
		(pad "1" smd rect
			(at -1.051 -0.65 180)
			(size 0.6 0.6)
			(layers "F.Cu" "F.Mask" "F.Paste")
			(net 619 "/FPGA bank 14/USR_LED2")
			(pinfunction "G")
			(pintype "input")
		)
		(pad "2" smd rect
			(at -1.051 0.65 180)
			(size 0.6 0.6)
			(layers "F.Cu" "F.Mask" "F.Paste")
			(net 1 "GND")
			(pinfunction "S")
			(pintype "passive")
		)
		(pad "3" smd rect
			(at 1.05 0 180)
			(size 0.6 0.6)
			(layers "F.Cu" "F.Mask" "F.Paste")
			(net 355 "Net-(Q6-D)")
			(pinfunction "D")
			(pintype "passive")
		)
	)
	(footprint "antmicro-footprints:C_0603_1608Metric"
		(layer "F.Cu")
		(at 191.245501 182.923 90)
		(descr "Capacitor SMD 0603")
		(tags "capacitor 0603")
		(property "Reference" "C187"
			(at -1.42757 -1.000252 90)
			(layer "F.SilkS")
			(hide yes)
			(effects
				(font
					(size 0.7 0.7)
					(thickness 0.15)
				)
				(justify left bottom)
			)
		)
		(property "Value" "C_22u_0603"
			(at -1.42757 1.770288 90)
			(layer "F.Fab")
			(effects
				(font
					(size 0.7 0.7)
					(thickness 0.15)
				)
				(justify left bottom)
			)
		)
		(property "Datasheet" "https://www.murata.com/products/productdetail?partno=GRM188R60J226MEA0%23"
			(at 0 0 90)
			(layer "F.Fab")
			(hide yes)
			(effects
				(font
					(size 1.27 1.27)
					(thickness 0.15)
				)
			)
		)
		(property "Author" "Antmicro"
			(at 374.168501 -8.322501 0)
			(layer "F.Fab")
			(hide yes)
			(effects
				(font
					(size 1 1)
					(thickness 0.15)
				)
			)
		)
		(property "Dielectric" ""
			(at 374.168501 -8.322501 0)
			(layer "F.Fab")
			(hide yes)
			(effects
				(font
					(size 1 1)
					(thickness 0.15)
				)
			)
		)
		(property "License" "Apache-2.0"
			(at 374.168501 -8.322501 0)
			(layer "F.Fab")
			(hide yes)
			(effects
				(font
					(size 1 1)
					(thickness 0.15)
				)
			)
		)
		(property "MPN" "GRM188R60J226MEA0D"
			(at 374.168501 -8.322501 0)
			(layer "F.Fab")
			(hide yes)
			(effects
				(font
					(size 1 1)
					(thickness 0.15)
				)
			)
		)
		(property "Manufacturer" "Murata"
			(at 374.168501 -8.322501 0)
			(layer "F.Fab")
			(hide yes)
			(effects
				(font
					(size 1 1)
					(thickness 0.15)
				)
			)
		)
		(property "Val" "22u"
			(at 374.168501 -8.322501 0)
			(layer "F.Fab")
			(hide yes)
			(effects
				(font
					(size 1 1)
					(thickness 0.15)
				)
			)
		)
		(property "Voltage" ""
			(at 374.168501 -8.322501 0)
			(layer "F.Fab")
			(hide yes)
			(effects
				(font
					(size 1 1)
					(thickness 0.15)
				)
			)
		)
		(sheetname "/Supply/")
		(sheetfile "supply.kicad_sch")
		(attr smd)
		(fp_line
			(start -0.3 -0.3)
			(end 0.3 -0.3)
			(stroke
				(width 0.15)
				(type solid)
			)
			(layer "F.SilkS")
		)
		(fp_line
			(start -0.3 0.3)
			(end 0.3 0.3)
			(stroke
				(width 0.15)
				(type solid)
			)
			(layer "F.SilkS")
		)
		(fp_rect
			(start -1.24 -0.7)
			(end 1.24 0.7)
			(stroke
				(width 0.05)
				(type solid)
			)
			(fill no)
			(layer "F.CrtYd")
		)
		(fp_rect
			(start -0.8 -0.4)
			(end 0.8 0.4)
			(stroke
				(width 0.15)
				(type solid)
			)
			(fill no)
			(layer "F.Fab")
		)
		(pad "1" smd roundrect
			(at -0.7 0 90)
			(size 0.6 0.8)
			(layers "F.Cu" "F.Mask" "F.Paste")
			(roundrect_rratio 0.2)
			(net 1 "GND")
			(pintype "passive")
		)
		(pad "2" smd roundrect
			(at 0.7 0 90)
			(size 0.6 0.8)
			(layers "F.Cu" "F.Mask" "F.Paste")
			(roundrect_rratio 0.2)
			(net 51 "/Supply/1V8_local")
			(pintype "passive")
		)
	)
	(footprint "antmicro-footprints:R_0402_1005Metric"
		(layer "F.Cu")
		(at 122.85 186.6 -90)
		(descr "Resistor SMD 0402")
		(tags "resistor SMD 0402")
		(property "Reference" "R8"
			(at -1.122484 -0.772697 270)
			(layer "F.SilkS")
			(hide yes)
			(effects
				(font
					(size 0.7 0.7)
					(thickness 0.15)
				)
				(justify left bottom)
			)
		)
		(property "Value" "R_22R_0402"
			(at -1.011843 1.772047 270)
			(layer "F.Fab")
			(effects
				(font
					(size 0.7 0.7)
					(thickness 0.15)
				)
				(justify left bottom)
			)
		)
		(property "Datasheet" "https://www.bourns.com/docs/product-datasheets/cr.pdf"
			(at 0 0 270)
			(layer "F.Fab")
			(hide yes)
			(effects
				(font
					(size 1.27 1.27)
					(thickness 0.15)
				)
			)
		)
		(property "Author" "Antmicro"
			(at -63.75 309.45 0)
			(layer "F.Fab")
			(hide yes)
			(effects
				(font
					(size 1 1)
					(thickness 0.15)
				)
			)
		)
		(property "License" "Apache-2.0"
			(at -63.75 309.45 0)
			(layer "F.Fab")
			(hide yes)
			(effects
				(font
					(size 1 1)
					(thickness 0.15)
				)
			)
		)
		(property "MPN" "CR0402-FX-22R0GLF"
			(at -63.75 309.45 0)
			(layer "F.Fab")
			(hide yes)
			(effects
				(font
					(size 1 1)
					(thickness 0.15)
				)
			)
		)
		(property "Manufacturer" "Bourns"
			(at -63.75 309.45 0)
			(layer "F.Fab")
			(hide yes)
			(effects
				(font
					(size 1 1)
					(thickness 0.15)
				)
			)
		)
		(property "Tolerance" "1%"
			(at -63.75 309.45 0)
			(layer "F.Fab")
			(hide yes)
			(effects
				(font
					(size 1 1)
					(thickness 0.15)
				)
			)
		)
		(property "Val" "22R"
			(at -63.75 309.45 0)
			(layer "F.Fab")
			(hide yes)
			(effects
				(font
					(size 1 1)
					(thickness 0.15)
				)
			)
		)
		(sheetname "/HyperRAM + QSPI Flash/")
		(sheetfile "hyperram-flash.kicad_sch")
		(attr smd)
		(fp_rect
			(start -0.93 -0.47)
			(end 0.93 0.47)
			(stroke
				(width 0.05)
				(type solid)
			)
			(fill no)
			(layer "F.CrtYd")
		)
		(fp_rect
			(start -0.5 -0.25)
			(end 0.5 0.25)
			(stroke
				(width 0.15)
				(type solid)
			)
			(fill no)
			(layer "F.Fab")
		)
		(pad "1" smd roundrect
			(at -0.485 0 270)
			(size 0.59 0.64)
			(layers "F.Cu" "F.Mask" "F.Paste")
			(roundrect_rratio 0.25)
			(net 361 "/HyperRAM + QSPI Flash/IO2")
			(pintype "passive")
		)
		(pad "2" smd roundrect
			(at 0.485 0 270)
			(size 0.59 0.64)
			(layers "F.Cu" "F.Mask" "F.Paste")
			(roundrect_rratio 0.25)
			(net 628 "/FPGA Config/FLASH.IO2")
			(pintype "passive")
		)
	)
	(footprint "antmicro-footprints:TP_SMD_1mm"
		(layer "F.Cu")
		(at 199.2 141.2)
		(property "Reference" "TP19"
			(at 0 -0.731898 0)
			(layer "F.SilkS")
			(hide yes)
			(effects
				(font
					(size 0.7 0.7)
					(thickness 0.15)
				)
				(justify left bottom)
			)
		)
		(property "Value" "TP_1mm_SMD"
			(at 0 1.4 0)
			(layer "F.Fab")
			(effects
				(font
					(size 0.7 0.7)
					(thickness 0.15)
				)
				(justify left bottom)
			)
		)
		(property "Author" "Antmicro"
			(at 0 0 0)
			(layer "F.Fab")
			(hide yes)
			(effects
				(font
					(size 1 1)
					(thickness 0.15)
				)
			)
		)
		(property "License" "Apache-2.0"
			(at 0 0 0)
			(layer "F.Fab")
			(hide yes)
			(effects
				(font
					(size 1 1)
					(thickness 0.15)
				)
			)
		)
		(property "MPN" ""
			(at 0 0 0)
			(layer "F.Fab")
			(hide yes)
			(effects
				(font
					(size 1 1)
					(thickness 0.15)
				)
			)
		)
		(property "Manufacturer" ""
			(at 0 0 0)
			(layer "F.Fab")
			(hide yes)
			(effects
				(font
					(size 1 1)
					(thickness 0.15)
				)
			)
		)
		(sheetname "/Supply/")
		(sheetfile "supply.kicad_sch")
		(attr exclude_from_pos_files)
		(pad "1" smd circle
			(at 0 0)
			(size 1 1)
			(layers "F.Cu" "F.Mask")
			(net 41 "+3V3_AON")
			(pinfunction "1")
			(pintype "passive")
		)
	)
	(footprint "antmicro-footprints:LGA-33_7x7mm_P0.65mm"
		(layer "F.Cu")
		(at 197.993501 166.8595 -90)
		(property "Reference" "U20"
			(at 4.6405 -1.706499 0)
			(layer "F.SilkS")
			(effects
				(font
					(size 0.7 0.7)
					(thickness 0.15)
				)
				(justify left bottom)
			)
		)
		(property "Value" "MPM54304GMN"
			(at 0 5 270)
			(layer "F.Fab")
			(effects
				(font
					(size 0.7 0.7)
					(thickness 0.15)
				)
				(justify left bottom)
			)
		)
		(property "Datasheet" "https://www.monolithicpower.com/en/documentview/productdocument/index/version/2/document_type/Datasheet/lang/en/sku/MPM54304/document_id/4982/"
			(at 0 0 270)
			(layer "F.Fab")
			(hide yes)
			(effects
				(font
					(size 1.27 1.27)
					(thickness 0.15)
				)
			)
		)
		(property "Author" "Antmicro"
			(at 31.134001 364.853001 0)
			(layer "F.Fab")
			(hide yes)
			(effects
				(font
					(size 1 1)
					(thickness 0.15)
				)
			)
		)
		(property "License" "Apache-2.0"
			(at 31.134001 364.853001 0)
			(layer "F.Fab")
			(hide yes)
			(effects
				(font
					(size 1 1)
					(thickness 0.15)
				)
			)
		)
		(property "MPN" "MPM54304GMN-0000"
			(at 31.134001 364.853001 0)
			(layer "F.Fab")
			(hide yes)
			(effects
				(font
					(size 1 1)
					(thickness 0.15)
				)
			)
		)
		(property "Manufacturer" "Monolithic Power Systems"
			(at 31.134001 364.853001 0)
			(layer "F.Fab")
			(hide yes)
			(effects
				(font
					(size 1 1)
					(thickness 0.15)
				)
			)
		)
		(property ki_fp_filters "CP_48_13_ADI CP_48_13_ADI-M CP_48_13_ADI-L")
		(sheetname "/Supply/")
		(sheetfile "supply.kicad_sch")
		(solder_paste_margin_ratio -0.1)
		(attr smd)
		(fp_line
			(start -3.65 3.648)
			(end -3.65 2.922)
			(stroke
				(width 0.15)
				(type solid)
			)
			(layer "F.SilkS")
		)
		(fp_line
			(start -2.926 3.648)
			(end -3.65 3.648)
			(stroke
				(width 0.15)
				(type solid)
			)
			(layer "F.SilkS")
		)
		(fp_line
			(start 2.922 3.648)
			(end 3.648 3.648)
			(stroke
				(width 0.15)
				(type solid)
			)
			(layer "F.SilkS")
		)
		(fp_line
			(start 3.648 3.648)
			(end 3.648 2.922)
			(stroke
				(width 0.15)
				(type solid)
			)
			(layer "F.SilkS")
		)
		(fp_line
			(start -3.665 -2.928)
			(end -3.665 -3.653)
			(stroke
				(width 0.15)
				(type solid)
			)
			(layer "F.SilkS")
		)
		(fp_line
			(start 2.922 -3.65)
			(end 3.648 -3.65)
			(stroke
				(width 0.15)
				(type solid)
			)
			(layer "F.SilkS")
		)
		(fp_line
			(start 3.648 -3.65)
			(end 3.648 -2.926)
			(stroke
				(width 0.15)
				(type solid)
			)
			(layer "F.SilkS")
		)
		(fp_line
			(start -3.665 -3.653)
			(end -2.94 -3.653)
			(stroke
				(width 0.15)
				(type solid)
			)
			(layer "F.SilkS")
		)
		(fp_circle
			(center -3.8 -1.925)
			(end -3.75 -1.925)
			(stroke
				(width 0.15)
				(type solid)
			)
			(fill yes)
			(layer "F.SilkS")
		)
		(fp_rect
			(start -4 -4)
			(end 3.999 3.999)
			(stroke
				(width 0.05)
				(type solid)
			)
			(fill no)
			(layer "F.CrtYd")
		)
		(fp_line
			(start -3.5 3.499)
			(end 3.499 3.499)
			(stroke
				(width 0.15)
				(type solid)
			)
			(layer "F.Fab")
		)
		(fp_line
			(start 3.499 3.499)
			(end 3.499 -3.5)
			(stroke
				(width 0.15)
				(type solid)
			)
			(layer "F.Fab")
		)
		(fp_line
			(start -3.5 -3.5)
			(end -3.5 3.499)
			(stroke
				(width 0.15)
				(type solid)
			)
			(layer "F.Fab")
		)
		(fp_line
			(start -3.101 -3.5)
			(end -3.5 -3.101)
			(stroke
				(width 0.15)
				(type solid)
			)
			(layer "F.Fab")
		)
		(fp_line
			(start 3.499 -3.5)
			(end -3.5 -3.5)
			(stroke
				(width 0.15)
				(type solid)
			)
			(layer "F.Fab")
		)
		(pad "1" smd rect
			(at -3.138 -1.625)
			(size 0.3 1.125)
			(layers "F.Cu" "F.Mask" "F.Paste")
			(net 53 "/Supply/1V1_local")
			(pinfunction "VOUT3")
			(pintype "power_out")
		)
		(pad "2" smd rect
			(at -3.138 -0.975)
			(size 0.3 1.125)
			(layers "F.Cu" "F.Mask" "F.Paste")
			(net 1 "GND")
			(pinfunction "GND")
			(pintype "passive")
		)
		(pad "3" smd rect
			(at -3.138 -0.328)
			(size 0.3 1.125)
			(layers "F.Cu" "F.Mask" "F.Paste")
			(net 690 "/I^{2}C/PWR.SDA")
			(pinfunction "SDA")
			(pintype "bidirectional")
		)
		(pad "4" smd rect
			(at -3.138 0.325)
			(size 0.3 1.125)
			(layers "F.Cu" "F.Mask" "F.Paste")
			(net 285 "/Supply/QDCDC2_SCL")
			(pinfunction "SCL")
			(pintype "input")
		)
		(pad "5" smd rect
			(at -3.138 0.972)
			(size 0.3 1.125)
			(layers "F.Cu" "F.Mask" "F.Paste")
			(net 1 "GND")
			(pinfunction "GND")
			(pintype "passive")
		)
		(pad "6" smd rect
			(at -3.138 1.624)
			(size 0.3 1.125)
			(layers "F.Cu" "F.Mask" "F.Paste")
			(net 208 "/Supply/FB6")
			(pinfunction "FB2")
			(pintype "input")
		)
		(pad "7" smd rect
			(at -2.926 3.136 90)
			(size 0.3 1.125)
			(layers "F.Cu" "F.Mask" "F.Paste")
			(net 1 "GND")
			(pinfunction "GND")
			(pintype "passive")
		)
		(pad "8" smd rect
			(at -2.275 3.136 90)
			(size 0.3 1.125)
			(layers "F.Cu" "F.Mask" "F.Paste")
			(net 60 "/Supply/5V_local")
			(pinfunction "VOUT2")
			(pintype "power_out")
		)
		(pad "9" smd rect
			(at -1.625 3.136 270)
			(size 0.3 1.125)
			(layers "F.Cu" "F.Mask" "F.Paste")
			(net 60 "/Supply/5V_local")
			(pinfunction "VOUT2")
			(pintype "passive")
		)
		(pad "10" smd rect
			(at -0.975 3.136 270)
			(size 0.3 1.125)
			(layers "F.Cu" "F.Mask" "F.Paste")
			(net 1 "GND")
			(pinfunction "GND")
			(pintype "passive")
		)
		(pad "11" smd rect
			(at -0.328 3.136 270)
			(size 0.3 1.125)
			(layers "F.Cu" "F.Mask" "F.Paste")
			(net 728 "unconnected-(U20-SW2-Pad11)")
			(pinfunction "SW2")
			(pintype "power_out+no_connect")
		)
		(pad "12" smd rect
			(at 0.325 3.136 270)
			(size 0.3 1.125)
			(layers "F.Cu" "F.Mask" "F.Paste")
			(net 729 "unconnected-(U20-SW1-Pad12)")
			(pinfunction "SW1")
			(pintype "power_out+no_connect")
		)
		(pad "13" smd rect
			(at 0.972 3.136 270)
			(size 0.3 1.125)
			(layers "F.Cu" "F.Mask" "F.Paste")
			(net 1 "GND")
			(pinfunction "GND")
			(pintype "passive")
		)
		(pad "14" smd rect
			(at 1.624 3.136 270)
			(size 0.3 1.125)
			(layers "F.Cu" "F.Mask" "F.Paste")
			(net 52 "/Supply/3V3_local")
			(pinfunction "VOUT1")
			(pintype "power_out")
		)
		(pad "15" smd rect
			(at 2.273 3.136 270)
			(size 0.3 1.125)
			(layers "F.Cu" "F.Mask" "F.Paste")
			(net 52 "/Supply/3V3_local")
			(pinfunction "VOUT1")
			(pintype "passive")
		)
		(pad "16" smd rect
			(at 2.922 3.136 270)
			(size 0.3 1.125)
			(layers "F.Cu" "F.Mask" "F.Paste")
			(net 1 "GND")
			(pinfunction "GND")
			(pintype "passive")
		)
		(pad "17" smd rect
			(at 3.136 1.624)
			(size 0.3 1.125)
			(layers "F.Cu" "F.Mask" "F.Paste")
			(net 1 "GND")
			(pinfunction "SGND1")
			(pintype "power_out")
		)
		(pad "18" smd rect
			(at 3.136 0.972)
			(size 0.3 1.125)
			(layers "F.Cu" "F.Mask" "F.Paste")
			(net 209 "/Supply/FB5")
			(pinfunction "FB1")
			(pintype "input")
		)
		(pad "19" smd rect
			(at 3.136 0.325)
			(size 0.3 1.125)
			(layers "F.Cu" "F.Mask" "F.Paste")
			(net 223 "/Supply/EN3")
			(pinfunction "EN/SYNCI")
			(pintype "input")
		)
		(pad "20" smd rect
			(at 3.136 -0.328)
			(size 0.3 1.125)
			(layers "F.Cu" "F.Mask" "F.Paste")
			(net 1 "GND")
			(pinfunction "GND")
			(pintype "passive")
		)
		(pad "21" smd rect
			(at 3.136 -0.975)
			(size 0.3 1.125)
			(layers "F.Cu" "F.Mask" "F.Paste")
			(net 1 "GND")
			(pinfunction "GND")
			(pintype "passive")
		)
		(pad "22" smd rect
			(at 3.136 -1.625)
			(size 0.3 1.125)
			(layers "F.Cu" "F.Mask" "F.Paste")
			(net 56 "/Supply/1V2_local")
			(pinfunction "VOUT4")
			(pintype "power_out")
		)
		(pad "23" smd rect
			(at 2.922 -3.138 90)
			(size 0.3 1.125)
			(layers "F.Cu" "F.Mask" "F.Paste")
			(net 56 "/Supply/1V2_local")
			(pinfunction "VOUT4")
			(pintype "passive")
		)
		(pad "24" smd rect
			(at 2.273 -3.138 90)
			(size 0.3 1.125)
			(layers "F.Cu" "F.Mask" "F.Paste")
			(net 218 "/Supply/FB8")
			(pinfunction "FB4")
			(pintype "input")
		)
		(pad "25" smd rect
			(at 1.624 -3.138 270)
			(size 0.3 1.125)
			(layers "F.Cu" "F.Mask" "F.Paste")
			(net 40 "/Supply/QDCDC2_VCC")
			(pinfunction "VCC")
			(pintype "input")
		)
		(pad "26" smd rect
			(at 0.972 -3.138 270)
			(size 0.3 1.125)
			(layers "F.Cu" "F.Mask" "F.Paste")
			(net 282 "/Supply/PG3")
			(pinfunction "GPIO")
			(pintype "input")
		)
		(pad "27" smd rect
			(at 0.325 -3.138 270)
			(size 0.3 1.125)
			(layers "F.Cu" "F.Mask" "F.Paste")
			(net 1 "GND")
			(pinfunction "GND")
			(pintype "passive")
		)
		(pad "28" smd rect
			(at -0.328 -3.138 270)
			(size 0.3 1.125)
			(layers "F.Cu" "F.Mask" "F.Paste")
			(net 38 "VDC")
			(pinfunction "VIN")
			(pintype "input")
		)
		(pad "29" smd rect
			(at -0.975 -3.138 270)
			(size 0.3 1.125)
			(layers "F.Cu" "F.Mask" "F.Paste")
			(net 38 "VDC")
			(pinfunction "VIN")
			(pintype "passive")
		)
		(pad "30" smd rect
			(at -1.625 -3.138 270)
			(size 0.3 1.125)
			(layers "F.Cu" "F.Mask" "F.Paste")
			(net 1 "GND")
			(pinfunction "SGND2")
			(pintype "power_out")
		)
		(pad "31" smd rect
			(at -2.275 -3.138 270)
			(size 0.3 1.125)
			(layers "F.Cu" "F.Mask" "F.Paste")
			(net 217 "/Supply/FB7")
			(pinfunction "FB3")
			(pintype "input")
		)
		(pad "32" smd rect
			(at -2.926 -3.138 270)
			(size 0.3 1.125)
			(layers "F.Cu" "F.Mask" "F.Paste")
			(net 53 "/Supply/1V1_local")
			(pinfunction "VOUT3")
			(pintype "passive")
		)
		(pad "33" smd rect
			(at -0.863 -0.863 270)
			(size 1.725 1.725)
			(layers "F.Cu" "F.Mask" "F.Paste")
			(net 1 "GND")
			(pinfunction "GND")
			(pintype "passive")
			(solder_paste_margin -0.1)
		)
		(pad "33" smd rect
			(at -0.863 0.86 270)
			(size 1.725 1.725)
			(layers "F.Cu" "F.Mask" "F.Paste")
			(net 1 "GND")
			(pinfunction "GND")
			(pintype "passive")
			(solder_paste_margin -0.1)
		)
		(pad "33" smd rect
			(at 0.86 -0.863 270)
			(size 1.725 1.725)
			(layers "F.Cu" "F.Mask" "F.Paste")
			(net 1 "GND")
			(pinfunction "GND")
			(pintype "passive")
			(solder_paste_margin -0.1)
		)
		(pad "33" smd rect
			(at 0.86 0.86 270)
			(size 1.725 1.725)
			(layers "F.Cu" "F.Mask" "F.Paste")
			(net 1 "GND")
			(pinfunction "GND")
			(pintype "passive")
			(solder_paste_margin -0.1)
		)
	)
	(footprint "antmicro-footprints:LGA-33_7x7mm_P0.65mm"
		(layer "F.Cu")
		(at 198.020501 184.3105 -90)
		(property "Reference" "U19"
			(at 4.5895 -1.779499 0)
			(layer "F.SilkS")
			(effects
				(font
					(size 0.7 0.7)
					(thickness 0.15)
				)
				(justify left bottom)
			)
		)
		(property "Value" "MPM54304GMN"
			(at 0 5 270)
			(layer "F.Fab")
			(effects
				(font
					(size 0.7 0.7)
					(thickness 0.15)
				)
				(justify left bottom)
			)
		)
		(property "Datasheet" "https://www.monolithicpower.com/en/documentview/productdocument/index/version/2/document_type/Datasheet/lang/en/sku/MPM54304/document_id/4982/"
			(at 0 0 270)
			(layer "F.Fab")
			(hide yes)
			(effects
				(font
					(size 1.27 1.27)
					(thickness 0.15)
				)
			)
		)
		(property "Author" "Antmicro"
			(at 13.710001 382.331001 0)
			(layer "F.Fab")
			(hide yes)
			(effects
				(font
					(size 1 1)
					(thickness 0.15)
				)
			)
		)
		(property "License" "Apache-2.0"
			(at 13.710001 382.331001 0)
			(layer "F.Fab")
			(hide yes)
			(effects
				(font
					(size 1 1)
					(thickness 0.15)
				)
			)
		)
		(property "MPN" "MPM54304GMN-0000"
			(at 13.710001 382.331001 0)
			(layer "F.Fab")
			(hide yes)
			(effects
				(font
					(size 1 1)
					(thickness 0.15)
				)
			)
		)
		(property "Manufacturer" "Monolithic Power Systems"
			(at 13.710001 382.331001 0)
			(layer "F.Fab")
			(hide yes)
			(effects
				(font
					(size 1 1)
					(thickness 0.15)
				)
			)
		)
		(property ki_fp_filters "CP_48_13_ADI CP_48_13_ADI-M CP_48_13_ADI-L")
		(sheetname "/Supply/")
		(sheetfile "supply.kicad_sch")
		(solder_paste_margin_ratio -0.1)
		(attr smd)
		(fp_line
			(start -3.65 3.648)
			(end -3.65 2.922)
			(stroke
				(width 0.15)
				(type solid)
			)
			(layer "F.SilkS")
		)
		(fp_line
			(start -2.926 3.648)
			(end -3.65 3.648)
			(stroke
				(width 0.15)
				(type solid)
			)
			(layer "F.SilkS")
		)
		(fp_line
			(start 2.922 3.648)
			(end 3.648 3.648)
			(stroke
				(width 0.15)
				(type solid)
			)
			(layer "F.SilkS")
		)
		(fp_line
			(start 3.648 3.648)
			(end 3.648 2.922)
			(stroke
				(width 0.15)
				(type solid)
			)
			(layer "F.SilkS")
		)
		(fp_line
			(start -3.665 -2.928)
			(end -3.665 -3.653)
			(stroke
				(width 0.15)
				(type solid)
			)
			(layer "F.SilkS")
		)
		(fp_line
			(start 2.922 -3.65)
			(end 3.648 -3.65)
			(stroke
				(width 0.15)
				(type solid)
			)
			(layer "F.SilkS")
		)
		(fp_line
			(start 3.648 -3.65)
			(end 3.648 -2.926)
			(stroke
				(width 0.15)
				(type solid)
			)
			(layer "F.SilkS")
		)
		(fp_line
			(start -3.665 -3.653)
			(end -2.94 -3.653)
			(stroke
				(width 0.15)
				(type solid)
			)
			(layer "F.SilkS")
		)
		(fp_circle
			(center -3.8 -1.925)
			(end -3.75 -1.925)
			(stroke
				(width 0.15)
				(type solid)
			)
			(fill yes)
			(layer "F.SilkS")
		)
		(fp_rect
			(start -4 -4)
			(end 3.999 3.999)
			(stroke
				(width 0.05)
				(type solid)
			)
			(fill no)
			(layer "F.CrtYd")
		)
		(fp_line
			(start -3.5 3.499)
			(end 3.499 3.499)
			(stroke
				(width 0.15)
				(type solid)
			)
			(layer "F.Fab")
		)
		(fp_line
			(start 3.499 3.499)
			(end 3.499 -3.5)
			(stroke
				(width 0.15)
				(type solid)
			)
			(layer "F.Fab")
		)
		(fp_line
			(start -3.5 -3.5)
			(end -3.5 3.499)
			(stroke
				(width 0.15)
				(type solid)
			)
			(layer "F.Fab")
		)
		(fp_line
			(start -3.101 -3.5)
			(end -3.5 -3.101)
			(stroke
				(width 0.15)
				(type solid)
			)
			(layer "F.Fab")
		)
		(fp_line
			(start 3.499 -3.5)
			(end -3.5 -3.5)
			(stroke
				(width 0.15)
				(type solid)
			)
			(layer "F.Fab")
		)
		(pad "1" smd rect
			(at -3.138 -1.625)
			(size 0.3 1.125)
			(layers "F.Cu" "F.Mask" "F.Paste")
			(net 35 "/Supply/spare_local")
			(pinfunction "VOUT3")
			(pintype "power_out")
		)
		(pad "2" smd rect
			(at -3.138 -0.975)
			(size 0.3 1.125)
			(layers "F.Cu" "F.Mask" "F.Paste")
			(net 1 "GND")
			(pinfunction "GND")
			(pintype "passive")
		)
		(pad "3" smd rect
			(at -3.138 -0.328)
			(size 0.3 1.125)
			(layers "F.Cu" "F.Mask" "F.Paste")
			(net 690 "/I^{2}C/PWR.SDA")
			(pinfunction "SDA")
			(pintype "bidirectional")
		)
		(pad "4" smd rect
			(at -3.138 0.325)
			(size 0.3 1.125)
			(layers "F.Cu" "F.Mask" "F.Paste")
			(net 691 "/I^{2}C/PWR.SCL")
			(pinfunction "SCL")
			(pintype "input")
		)
		(pad "5" smd rect
			(at -3.138 0.972)
			(size 0.3 1.125)
			(layers "F.Cu" "F.Mask" "F.Paste")
			(net 1 "GND")
			(pinfunction "GND")
			(pintype "passive")
		)
		(pad "6" smd rect
			(at -3.138 1.624)
			(size 0.3 1.125)
			(layers "F.Cu" "F.Mask" "F.Paste")
			(net 211 "/Supply/FB2")
			(pinfunction "FB2")
			(pintype "input")
		)
		(pad "7" smd rect
			(at -2.926 3.136 90)
			(size 0.3 1.125)
			(layers "F.Cu" "F.Mask" "F.Paste")
			(net 1 "GND")
			(pinfunction "GND")
			(pintype "passive")
		)
		(pad "8" smd rect
			(at -2.275 3.136 90)
			(size 0.3 1.125)
			(layers "F.Cu" "F.Mask" "F.Paste")
			(net 51 "/Supply/1V8_local")
			(pinfunction "VOUT2")
			(pintype "power_out")
		)
		(pad "9" smd rect
			(at -1.625 3.136 270)
			(size 0.3 1.125)
			(layers "F.Cu" "F.Mask" "F.Paste")
			(net 51 "/Supply/1V8_local")
			(pinfunction "VOUT2")
			(pintype "passive")
		)
		(pad "10" smd rect
			(at -0.975 3.136 270)
			(size 0.3 1.125)
			(layers "F.Cu" "F.Mask" "F.Paste")
			(net 1 "GND")
			(pinfunction "GND")
			(pintype "passive")
		)
		(pad "11" smd rect
			(at -0.328 3.136 270)
			(size 0.3 1.125)
			(layers "F.Cu" "F.Mask" "F.Paste")
			(net 726 "unconnected-(U19-SW2-Pad11)")
			(pinfunction "SW2")
			(pintype "power_out+no_connect")
		)
		(pad "12" smd rect
			(at 0.325 3.136 270)
			(size 0.3 1.125)
			(layers "F.Cu" "F.Mask" "F.Paste")
			(net 727 "unconnected-(U19-SW1-Pad12)")
			(pinfunction "SW1")
			(pintype "power_out+no_connect")
		)
		(pad "13" smd rect
			(at 0.972 3.136 270)
			(size 0.3 1.125)
			(layers "F.Cu" "F.Mask" "F.Paste")
			(net 1 "GND")
			(pinfunction "GND")
			(pintype "passive")
		)
		(pad "14" smd rect
			(at 1.624 3.136 270)
			(size 0.3 1.125)
			(layers "F.Cu" "F.Mask" "F.Paste")
			(net 42 "/Supply/MGTAVCC_local")
			(pinfunction "VOUT1")
			(pintype "power_out")
		)
		(pad "15" smd rect
			(at 2.273 3.136 270)
			(size 0.3 1.125)
			(layers "F.Cu" "F.Mask" "F.Paste")
			(net 42 "/Supply/MGTAVCC_local")
			(pinfunction "VOUT1")
			(pintype "passive")
		)
		(pad "16" smd rect
			(at 2.922 3.136 270)
			(size 0.3 1.125)
			(layers "F.Cu" "F.Mask" "F.Paste")
			(net 1 "GND")
			(pinfunction "GND")
			(pintype "passive")
		)
		(pad "17" smd rect
			(at 3.136 1.624)
			(size 0.3 1.125)
			(layers "F.Cu" "F.Mask" "F.Paste")
			(net 1 "GND")
			(pinfunction "SGND1")
			(pintype "power_out")
		)
		(pad "18" smd rect
			(at 3.136 0.972)
			(size 0.3 1.125)
			(layers "F.Cu" "F.Mask" "F.Paste")
			(net 210 "/Supply/FB1")
			(pinfunction "FB1")
			(pintype "input")
		)
		(pad "19" smd rect
			(at 3.136 0.325)
			(size 0.3 1.125)
			(layers "F.Cu" "F.Mask" "F.Paste")
			(net 222 "/Supply/EN2")
			(pinfunction "EN/SYNCI")
			(pintype "input")
		)
		(pad "20" smd rect
			(at 3.136 -0.328)
			(size 0.3 1.125)
			(layers "F.Cu" "F.Mask" "F.Paste")
			(net 1 "GND")
			(pinfunction "GND")
			(pintype "passive")
		)
		(pad "21" smd rect
			(at 3.136 -0.975)
			(size 0.3 1.125)
			(layers "F.Cu" "F.Mask" "F.Paste")
			(net 1 "GND")
			(pinfunction "GND")
			(pintype "passive")
		)
		(pad "22" smd rect
			(at 3.136 -1.625)
			(size 0.3 1.125)
			(layers "F.Cu" "F.Mask" "F.Paste")
			(net 58 "/Supply/1V7_local")
			(pinfunction "VOUT4")
			(pintype "power_out")
		)
		(pad "23" smd rect
			(at 2.922 -3.138 90)
			(size 0.3 1.125)
			(layers "F.Cu" "F.Mask" "F.Paste")
			(net 58 "/Supply/1V7_local")
			(pinfunction "VOUT4")
			(pintype "passive")
		)
		(pad "24" smd rect
			(at 2.273 -3.138 90)
			(size 0.3 1.125)
			(layers "F.Cu" "F.Mask" "F.Paste")
			(net 220 "/Supply/FB4")
			(pinfunction "FB4")
			(pintype "input")
		)
		(pad "25" smd rect
			(at 1.624 -3.138 270)
			(size 0.3 1.125)
			(layers "F.Cu" "F.Mask" "F.Paste")
			(net 39 "/Supply/QDCDC1_VCC")
			(pinfunction "VCC")
			(pintype "input")
		)
		(pad "26" smd rect
			(at 0.972 -3.138 270)
			(size 0.3 1.125)
			(layers "F.Cu" "F.Mask" "F.Paste")
			(net 281 "/Supply/PG2")
			(pinfunction "GPIO")
			(pintype "input")
		)
		(pad "27" smd rect
			(at 0.325 -3.138 270)
			(size 0.3 1.125)
			(layers "F.Cu" "F.Mask" "F.Paste")
			(net 1 "GND")
			(pinfunction "GND")
			(pintype "passive")
		)
		(pad "28" smd rect
			(at -0.328 -3.138 270)
			(size 0.3 1.125)
			(layers "F.Cu" "F.Mask" "F.Paste")
			(net 38 "VDC")
			(pinfunction "VIN")
			(pintype "input")
		)
		(pad "29" smd rect
			(at -0.975 -3.138 270)
			(size 0.3 1.125)
			(layers "F.Cu" "F.Mask" "F.Paste")
			(net 38 "VDC")
			(pinfunction "VIN")
			(pintype "passive")
		)
		(pad "30" smd rect
			(at -1.625 -3.138 270)
			(size 0.3 1.125)
			(layers "F.Cu" "F.Mask" "F.Paste")
			(net 1 "GND")
			(pinfunction "SGND2")
			(pintype "power_out")
		)
		(pad "31" smd rect
			(at -2.275 -3.138 270)
			(size 0.3 1.125)
			(layers "F.Cu" "F.Mask" "F.Paste")
			(net 216 "/Supply/FB3")
			(pinfunction "FB3")
			(pintype "input")
		)
		(pad "32" smd rect
			(at -2.926 -3.138 270)
			(size 0.3 1.125)
			(layers "F.Cu" "F.Mask" "F.Paste")
			(net 35 "/Supply/spare_local")
			(pinfunction "VOUT3")
			(pintype "passive")
		)
		(pad "33" smd rect
			(at -0.863 -0.863 270)
			(size 1.725 1.725)
			(layers "F.Cu" "F.Mask" "F.Paste")
			(net 1 "GND")
			(pinfunction "GND")
			(pintype "passive")
			(solder_paste_margin -0.1)
		)
		(pad "33" smd rect
			(at -0.863 0.86 270)
			(size 1.725 1.725)
			(layers "F.Cu" "F.Mask" "F.Paste")
			(net 1 "GND")
			(pinfunction "GND")
			(pintype "passive")
			(solder_paste_margin -0.1)
		)
		(pad "33" smd rect
			(at 0.86 -0.863 270)
			(size 1.725 1.725)
			(layers "F.Cu" "F.Mask" "F.Paste")
			(net 1 "GND")
			(pinfunction "GND")
			(pintype "passive")
			(solder_paste_margin -0.1)
		)
		(pad "33" smd rect
			(at 0.86 0.86 270)
			(size 1.725 1.725)
			(layers "F.Cu" "F.Mask" "F.Paste")
			(net 1 "GND")
			(pinfunction "GND")
			(pintype "passive")
			(solder_paste_margin -0.1)
		)
	)
	(footprint "antmicro-footprints:R_0402_1005Metric"
		(layer "F.Cu")
		(at 93.738501 126.721921 -90)
		(descr "Resistor SMD 0402")
		(tags "resistor SMD 0402")
		(property "Reference" "R19"
			(at -1.122484 -0.772697 270)
			(layer "F.SilkS")
			(hide yes)
			(effects
				(font
					(size 0.7 0.7)
					(thickness 0.15)
				)
				(justify left bottom)
			)
		)
		(property "Value" "R_330R_0402"
			(at -1.011843 1.772047 270)
			(layer "F.Fab")
			(effects
				(font
					(size 0.7 0.7)
					(thickness 0.15)
				)
				(justify left bottom)
			)
		)
		(property "Datasheet" "https://www.bourns.com/docs/product-datasheets/cr.pdf"
			(at 0 0 270)
			(layer "F.Fab")
			(hide yes)
			(effects
				(font
					(size 1.27 1.27)
					(thickness 0.15)
				)
			)
		)
		(property "Author" "Antmicro"
			(at -32.98342 220.460422 0)
			(layer "F.Fab")
			(hide yes)
			(effects
				(font
					(size 1 1)
					(thickness 0.15)
				)
			)
		)
		(property "License" "Apache-2.0"
			(at -32.98342 220.460422 0)
			(layer "F.Fab")
			(hide yes)
			(effects
				(font
					(size 1 1)
					(thickness 0.15)
				)
			)
		)
		(property "MPN" "CR0402-FX-3300GLF"
			(at -32.98342 220.460422 0)
			(layer "F.Fab")
			(hide yes)
			(effects
				(font
					(size 1 1)
					(thickness 0.15)
				)
			)
		)
		(property "Manufacturer" "Bourns"
			(at -32.98342 220.460422 0)
			(layer "F.Fab")
			(hide yes)
			(effects
				(font
					(size 1 1)
					(thickness 0.15)
				)
			)
		)
		(property "Tolerance" "1%"
			(at -32.98342 220.460422 0)
			(layer "F.Fab")
			(hide yes)
			(effects
				(font
					(size 1 1)
					(thickness 0.15)
				)
			)
		)
		(property "Val" "330R"
			(at -32.98342 220.460422 0)
			(layer "F.Fab")
			(hide yes)
			(effects
				(font
					(size 1 1)
					(thickness 0.15)
				)
			)
		)
		(sheetname "/FPGA Config/")
		(sheetfile "fpga-config.kicad_sch")
		(attr smd)
		(fp_rect
			(start -0.93 -0.47)
			(end 0.93 0.47)
			(stroke
				(width 0.05)
				(type solid)
			)
			(fill no)
			(layer "F.CrtYd")
		)
		(fp_rect
			(start -0.5 -0.25)
			(end 0.5 0.25)
			(stroke
				(width 0.15)
				(type solid)
			)
			(fill no)
			(layer "F.Fab")
		)
		(pad "1" smd roundrect
			(at -0.485 0 270)
			(size 0.59 0.64)
			(layers "F.Cu" "F.Mask" "F.Paste")
			(roundrect_rratio 0.25)
			(net 200 "+3V3")
			(pintype "passive")
		)
		(pad "2" smd roundrect
			(at 0.485 0 270)
			(size 0.59 0.64)
			(layers "F.Cu" "F.Mask" "F.Paste")
			(roundrect_rratio 0.25)
			(net 613 "/FPGA Config/DONE")
			(pintype "passive")
		)
	)
	(footprint "antmicro-footprints:R_0402_1005Metric"
		(layer "F.Cu")
		(at 99.850501 117.691 -90)
		(descr "Resistor SMD 0402")
		(tags "resistor SMD 0402")
		(property "Reference" "R63"
			(at -1.122484 -0.772697 270)
			(layer "F.SilkS")
			(hide yes)
			(effects
				(font
					(size 0.7 0.7)
					(thickness 0.15)
				)
				(justify left bottom)
			)
		)
		(property "Value" "R_330R_0402"
			(at -1.011843 1.772047 270)
			(layer "F.Fab")
			(effects
				(font
					(size 0.7 0.7)
					(thickness 0.15)
				)
				(justify left bottom)
			)
		)
		(property "Datasheet" "https://www.bourns.com/docs/product-datasheets/cr.pdf"
			(at 0 0 270)
			(layer "F.Fab")
			(hide yes)
			(effects
				(font
					(size 1.27 1.27)
					(thickness 0.15)
				)
			)
		)
		(property "Author" "Antmicro"
			(at -17.840499 217.541501 0)
			(layer "F.Fab")
			(hide yes)
			(effects
				(font
					(size 1 1)
					(thickness 0.15)
				)
			)
		)
		(property "License" "Apache-2.0"
			(at -17.840499 217.541501 0)
			(layer "F.Fab")
			(hide yes)
			(effects
				(font
					(size 1 1)
					(thickness 0.15)
				)
			)
		)
		(property "MPN" "CR0402-FX-3300GLF"
			(at -17.840499 217.541501 0)
			(layer "F.Fab")
			(hide yes)
			(effects
				(font
					(size 1 1)
					(thickness 0.15)
				)
			)
		)
		(property "Manufacturer" "Bourns"
			(at -17.840499 217.541501 0)
			(layer "F.Fab")
			(hide yes)
			(effects
				(font
					(size 1 1)
					(thickness 0.15)
				)
			)
		)
		(property "Tolerance" "1%"
			(at -17.840499 217.541501 0)
			(layer "F.Fab")
			(hide yes)
			(effects
				(font
					(size 1 1)
					(thickness 0.15)
				)
			)
		)
		(property "Val" "330R"
			(at -17.840499 217.541501 0)
			(layer "F.Fab")
			(hide yes)
			(effects
				(font
					(size 1 1)
					(thickness 0.15)
				)
			)
		)
		(sheetname "/DDR5 SODIMM/")
		(sheetfile "ddr5-sodimm.kicad_sch")
		(attr smd)
		(fp_rect
			(start -0.93 -0.47)
			(end 0.93 0.47)
			(stroke
				(width 0.05)
				(type solid)
			)
			(fill no)
			(layer "F.CrtYd")
		)
		(fp_rect
			(start -0.5 -0.25)
			(end 0.5 0.25)
			(stroke
				(width 0.15)
				(type solid)
			)
			(fill no)
			(layer "F.Fab")
		)
		(pad "1" smd roundrect
			(at -0.485 0 270)
			(size 0.59 0.64)
			(layers "F.Cu" "F.Mask" "F.Paste")
			(roundrect_rratio 0.25)
			(net 301 "Net-(D9-C_{R})")
			(pintype "passive")
		)
		(pad "2" smd roundrect
			(at 0.485 0 270)
			(size 0.59 0.64)
			(layers "F.Cu" "F.Mask" "F.Paste")
			(roundrect_rratio 0.25)
			(net 364 "Net-(Q11-D)")
			(pintype "passive")
		)
	)
	(footprint "antmicro-footprints:R_0402_1005Metric"
		(layer "F.Cu")
		(at 99.41 133.995 180)
		(descr "Resistor SMD 0402")
		(tags "resistor SMD 0402")
		(property "Reference" "R127"
			(at 4.16 -0.405 180)
			(layer "F.SilkS")
			(effects
				(font
					(size 0.7 0.7)
					(thickness 0.15)
				)
				(justify left bottom)
			)
		)
		(property "Value" "R_0R_0402"
			(at -1.011843 1.772047 180)
			(layer "F.Fab")
			(effects
				(font
					(size 0.7 0.7)
					(thickness 0.15)
				)
				(justify left bottom)
			)
		)
		(property "Datasheet" "https://industrial.panasonic.com/cdbs/www-data/pdf/RDA0000/AOA0000C301.pdf"
			(at 0 0 180)
			(layer "F.Fab")
			(hide yes)
			(effects
				(font
					(size 1.27 1.27)
					(thickness 0.15)
				)
			)
		)
		(property "Author" "Antmicro"
			(at 198.82 267.99 0)
			(layer "F.Fab")
			(hide yes)
			(effects
				(font
					(size 1 1)
					(thickness 0.15)
				)
			)
		)
		(property "Current" "1A"
			(at 198.82 267.99 0)
			(layer "F.Fab")
			(hide yes)
			(effects
				(font
					(size 1 1)
					(thickness 0.15)
				)
			)
		)
		(property "License" "Apache-2.0"
			(at 198.82 267.99 0)
			(layer "F.Fab")
			(hide yes)
			(effects
				(font
					(size 1 1)
					(thickness 0.15)
				)
			)
		)
		(property "MPN" "ERJ2GE0R00X"
			(at 198.82 267.99 0)
			(layer "F.Fab")
			(hide yes)
			(effects
				(font
					(size 1 1)
					(thickness 0.15)
				)
			)
		)
		(property "Manufacturer" "Panasonic"
			(at 198.82 267.99 0)
			(layer "F.Fab")
			(hide yes)
			(effects
				(font
					(size 1 1)
					(thickness 0.15)
				)
			)
		)
		(property "Tolerance" ""
			(at 198.82 267.99 0)
			(layer "F.Fab")
			(hide yes)
			(effects
				(font
					(size 1 1)
					(thickness 0.15)
				)
			)
		)
		(property "Val" "0R"
			(at 198.82 267.99 0)
			(layer "F.Fab")
			(hide yes)
			(effects
				(font
					(size 1 1)
					(thickness 0.15)
				)
			)
		)
		(sheetname "/I^{2}C/")
		(sheetfile "i2c.kicad_sch")
		(attr smd)
		(fp_rect
			(start -0.93 -0.47)
			(end 0.93 0.47)
			(stroke
				(width 0.05)
				(type solid)
			)
			(fill no)
			(layer "F.CrtYd")
		)
		(fp_rect
			(start -0.5 -0.25)
			(end 0.5 0.25)
			(stroke
				(width 0.15)
				(type solid)
			)
			(fill no)
			(layer "F.Fab")
		)
		(pad "1" smd roundrect
			(at -0.485 0 180)
			(size 0.59 0.64)
			(layers "F.Cu" "F.Mask" "F.Paste")
			(roundrect_rratio 0.25)
			(net 267 "VDDSPD")
			(pintype "passive")
		)
		(pad "2" smd roundrect
			(at 0.485 0 180)
			(size 0.59 0.64)
			(layers "F.Cu" "F.Mask" "F.Paste")
			(roundrect_rratio 0.25)
			(net 188 "+1V8")
			(pintype "passive")
		)
	)
	(footprint "antmicro-footprints:TP_SMD_1mm"
		(layer "F.Cu")
		(at 186.4 190.85)
		(property "Reference" "TP18"
			(at 0 -0.731898 0)
			(layer "F.SilkS")
			(hide yes)
			(effects
				(font
					(size 0.7 0.7)
					(thickness 0.15)
				)
				(justify left bottom)
			)
		)
		(property "Value" "TP_1mm_SMD"
			(at 0 1.4 0)
			(layer "F.Fab")
			(effects
				(font
					(size 0.7 0.7)
					(thickness 0.15)
				)
				(justify left bottom)
			)
		)
		(property "Author" "Antmicro"
			(at 0 0 0)
			(layer "F.Fab")
			(hide yes)
			(effects
				(font
					(size 1 1)
					(thickness 0.15)
				)
			)
		)
		(property "License" "Apache-2.0"
			(at 0 0 0)
			(layer "F.Fab")
			(hide yes)
			(effects
				(font
					(size 1 1)
					(thickness 0.15)
				)
			)
		)
		(property "MPN" ""
			(at 0 0 0)
			(layer "F.Fab")
			(hide yes)
			(effects
				(font
					(size 1 1)
					(thickness 0.15)
				)
			)
		)
		(property "Manufacturer" ""
			(at 0 0 0)
			(layer "F.Fab")
			(hide yes)
			(effects
				(font
					(size 1 1)
					(thickness 0.15)
				)
			)
		)
		(sheetname "/Supply/")
		(sheetfile "supply.kicad_sch")
		(attr exclude_from_pos_files)
		(pad "1" smd circle
			(at 0 0)
			(size 1 1)
			(layers "F.Cu" "F.Mask")
			(net 64 "/Supply/1V7")
			(pinfunction "1")
			(pintype "passive")
		)
	)
	(footprint "antmicro-footprints:DFN-6-1EP_2x2mm_P0.65mm_EP1x1.6mm"
		(layer "F.Cu")
		(at 182.541 151.875 90)
		(descr "6-Lead Plastic Dual Flat, No Lead Package - 2x2x0.9 mm Body")
		(tags "DFN")
		(property "Reference" "U29"
			(at -1.025 2.159 90)
			(layer "F.SilkS")
			(effects
				(font
					(size 0.7 0.7)
					(thickness 0.15)
				)
				(justify left bottom)
			)
		)
		(property "Value" "MCP4726A0T_DFN"
			(at 0 2.1 90)
			(layer "F.Fab")
			(effects
				(font
					(size 0.7 0.7)
					(thickness 0.15)
				)
				(justify left bottom)
			)
		)
		(property "Datasheet" "https://ww1.microchip.com/downloads/en/DeviceDoc/22272C.pdf"
			(at 0 0 90)
			(layer "F.Fab")
			(hide yes)
			(effects
				(font
					(size 1.27 1.27)
					(thickness 0.15)
				)
			)
		)
		(property "Author" "Antmicro"
			(at 334.416 -30.666 0)
			(layer "F.Fab")
			(hide yes)
			(effects
				(font
					(size 1 1)
					(thickness 0.15)
				)
			)
		)
		(property "License" "Apache-2.0"
			(at 334.416 -30.666 0)
			(layer "F.Fab")
			(hide yes)
			(effects
				(font
					(size 1 1)
					(thickness 0.15)
				)
			)
		)
		(property "MPN" "MCP4726A0T-E/MAY"
			(at 334.416 -30.666 0)
			(layer "F.Fab")
			(hide yes)
			(effects
				(font
					(size 1 1)
					(thickness 0.15)
				)
			)
		)
		(property "Manufacturer" "Microchip Technology"
			(at 334.416 -30.666 0)
			(layer "F.Fab")
			(hide yes)
			(effects
				(font
					(size 1 1)
					(thickness 0.15)
				)
			)
		)
		(property ki_fp_filters "DFN6_2x2MC_MCH DFN6_2x2MC_MCH-M DFN6_2x2MC_MCH-L")
		(sheetname "/Supply/")
		(sheetfile "supply.kicad_sch")
		(attr smd)
		(fp_line
			(start 1.075 -1.1)
			(end 1.075 -0.925)
			(stroke
				(width 0.15)
				(type solid)
			)
			(layer "F.SilkS")
		)
		(fp_line
			(start -1.075 -1.1)
			(end 1.075 -1.1)
			(stroke
				(width 0.15)
				(type solid)
			)
			(layer "F.SilkS")
		)
		(fp_line
			(start -1.075 -1.1)
			(end -1.075 -0.925)
			(stroke
				(width 0.15)
				(type solid)
			)
			(layer "F.SilkS")
		)
		(fp_line
			(start 1.075 0.9375)
			(end 1.075 1.1125)
			(stroke
				(width 0.15)
				(type solid)
			)
			(layer "F.SilkS")
		)
		(fp_line
			(start -1.075 0.9375)
			(end -1.075 1.1125)
			(stroke
				(width 0.15)
				(type solid)
			)
			(layer "F.SilkS")
		)
		(fp_line
			(start -1.075 1.1125)
			(end 1.075 1.1125)
			(stroke
				(width 0.15)
				(type solid)
			)
			(layer "F.SilkS")
		)
		(fp_circle
			(center -1.325 -1.04571)
			(end -1.275 -1.04571)
			(stroke
				(width 0.15)
				(type solid)
			)
			(fill yes)
			(layer "F.SilkS")
		)
		(fp_rect
			(start -1.405 -1.25)
			(end 1.405 1.225)
			(stroke
				(width 0.05)
				(type solid)
			)
			(fill no)
			(layer "F.CrtYd")
		)
		(fp_line
			(start -1 -0.5)
			(end -0.5 -1)
			(stroke
				(width 0.15)
				(type solid)
			)
			(layer "F.Fab")
		)
		(fp_rect
			(start 1 1)
			(end -1 -1)
			(stroke
				(width 0.15)
				(type solid)
			)
			(fill no)
			(layer "F.Fab")
		)
		(pad "" smd rect
			(at 0 -0.402 90)
			(size 0.82 0.63)
			(layers "F.Paste")
		)
		(pad "" smd rect
			(at 0 0.4 90)
			(size 0.82 0.63)
			(layers "F.Paste")
		)
		(pad "1" smd rect
			(at -1.051 -0.652 90)
			(size 0.65 0.35)
			(layers "F.Cu" "F.Mask" "F.Paste")
			(net 206 "+1V1")
			(pinfunction "VREF")
			(pintype "power_in")
		)
		(pad "2" smd rect
			(at -1.051 0 90)
			(size 0.65 0.35)
			(layers "F.Cu" "F.Mask" "F.Paste")
			(net 297 "/Supply/PWR_SCL_2")
			(pinfunction "SCL")
			(pintype "input")
		)
		(pad "3" smd rect
			(at -1.051 0.65 90)
			(size 0.65 0.35)
			(layers "F.Cu" "F.Mask" "F.Paste")
			(net 298 "/Supply/PWR_SDA_2")
			(pinfunction "SDA")
			(pintype "bidirectional")
		)
		(pad "4" smd rect
			(at 1.05 0.65 90)
			(size 0.65 0.35)
			(layers "F.Cu" "F.Mask" "F.Paste")
			(net 200 "+3V3")
			(pinfunction "VDD")
			(pintype "power_in")
		)
		(pad "5" smd rect
			(at 1.05 0 90)
			(size 0.65 0.35)
			(layers "F.Cu" "F.Mask" "F.Paste")
			(net 1 "GND")
			(pinfunction "GND")
			(pintype "power_in")
		)
		(pad "6" smd rect
			(at 1.05 -0.652 90)
			(size 0.65 0.35)
			(layers "F.Cu" "F.Mask" "F.Paste")
			(net 36 "DAC_VREF")
			(pinfunction "VOUT")
			(pintype "output")
		)
		(pad "7" smd rect
			(at 0 0 90)
			(size 1 1.6)
			(layers "F.Cu" "F.Mask")
			(net 1 "GND")
			(pinfunction "SH")
			(pintype "power_in")
		)
	)
	(footprint "antmicro-footprints:MP_Pad6mm_Drill3mm"
		(layer "F.Cu")
		(at 76.375501 119.551)
		(property "Reference" "MP1"
			(at 0 -3.2 0)
			(layer "F.SilkS")
			(hide yes)
			(effects
				(font
					(size 0.7 0.7)
					(thickness 0.15)
				)
				(justify left bottom)
			)
		)
		(property "Value" "MP_Pad6mm_Drill3mm"
			(at 0 3.9 0)
			(layer "F.Fab")
			(effects
				(font
					(size 0.7 0.7)
					(thickness 0.15)
				)
				(justify left bottom)
			)
		)
		(attr board_only exclude_from_pos_files exclude_from_bom)
		(pad "1" thru_hole circle
			(at 0 0)
			(size 6 6)
			(drill 3)
			(layers "*.Cu" "*.Mask")
			(remove_unused_layers no)
			(net 1 "GND")
		)
	)
	(footprint "antmicro-footprints:NetTie-2_SMD_Pad0.127mm"
		(layer "F.Cu")
		(at 198.175 191.326 180)
		(descr "Net tie, 2 pin, 0.127mm  SMD pads")
		(tags "net tie")
		(property "Reference" "NT12"
			(at -0.128 -1.345 180)
			(layer "F.SilkS")
			(hide yes)
			(effects
				(font
					(size 0.7 0.7)
					(thickness 0.15)
				)
				(justify left bottom)
			)
		)
		(property "Value" "Net-Tie_P0.127mm"
			(at 0 1.199 180)
			(layer "F.Fab")
			(effects
				(font
					(size 0.7 0.7)
					(thickness 0.15)
				)
				(justify left bottom)
			)
		)
		(property "Author" "Antmicro"
			(at 396.35 382.652 0)
			(layer "F.Fab")
			(hide yes)
			(effects
				(font
					(size 1 1)
					(thickness 0.15)
				)
			)
		)
		(property "License" "Apache-2.0"
			(at 396.35 382.652 0)
			(layer "F.Fab")
			(hide yes)
			(effects
				(font
					(size 1 1)
					(thickness 0.15)
				)
			)
		)
		(property "MPN" ""
			(at 396.35 382.652 0)
			(layer "F.Fab")
			(hide yes)
			(effects
				(font
					(size 1 1)
					(thickness 0.15)
				)
			)
		)
		(property "Manufacturer" ""
			(at 396.35 382.652 0)
			(layer "F.Fab")
			(hide yes)
			(effects
				(font
					(size 1 1)
					(thickness 0.15)
				)
			)
		)
		(property ki_fp_filters "Net*Tie*")
		(sheetname "/Supply/")
		(sheetfile "supply.kicad_sch")
		(attr smd exclude_from_pos_files exclude_from_bom)
		(net_tie_pad_groups "1, 2")
		(fp_poly
			(pts
				(xy -0.0635 -0.0635) (xy 0.0625 -0.0635) (xy 0.0625 0.0635) (xy -0.0635 0.0635)
			)
			(stroke
				(width 0)
				(type solid)
			)
			(fill yes)
			(layer "F.Cu")
		)
		(pad "1" smd roundrect
			(at -0.127 0)
			(size 0.127 0.127)
			(layers "F.Cu")
			(roundrect_rratio 0.5)
			(chamfer_ratio 0)
			(chamfer top_left bottom_left)
			(net 145 "/Supply/1V7_SEN_-")
			(pinfunction "1")
			(pintype "passive")
		)
		(pad "2" smd roundrect
			(at 0.126 0 180)
			(size 0.127 0.127)
			(layers "F.Cu")
			(roundrect_rratio 0.5)
			(chamfer_ratio 0)
			(chamfer top_left bottom_left)
			(net 64 "/Supply/1V7")
			(pinfunction "2")
			(pintype "passive")
		)
	)
	(footprint "antmicro-footprints:R_0402_1005Metric"
		(layer "F.Cu")
		(at 196.395501 189.1605 180)
		(descr "Resistor SMD 0402")
		(tags "resistor SMD 0402")
		(property "Reference" "R151"
			(at 3.895501 -0.3395 180)
			(layer "F.SilkS")
			(effects
				(font
					(size 0.7 0.7)
					(thickness 0.15)
				)
				(justify left bottom)
			)
		)
		(property "Value" "R_0R_0402"
			(at -1.011843 1.772047 180)
			(layer "F.Fab")
			(effects
				(font
					(size 0.7 0.7)
					(thickness 0.15)
				)
				(justify left bottom)
			)
		)
		(property "Datasheet" "https://industrial.panasonic.com/cdbs/www-data/pdf/RDA0000/AOA0000C301.pdf"
			(at 0 0 180)
			(layer "F.Fab")
			(hide yes)
			(effects
				(font
					(size 1.27 1.27)
					(thickness 0.15)
				)
			)
		)
		(property "Author" "Antmicro"
			(at 392.791002 378.321 0)
			(layer "F.Fab")
			(hide yes)
			(effects
				(font
					(size 1 1)
					(thickness 0.15)
				)
			)
		)
		(property "Current" "1A"
			(at 392.791002 378.321 0)
			(layer "F.Fab")
			(hide yes)
			(effects
				(font
					(size 1 1)
					(thickness 0.15)
				)
			)
		)
		(property "License" "Apache-2.0"
			(at 392.791002 378.321 0)
			(layer "F.Fab")
			(hide yes)
			(effects
				(font
					(size 1 1)
					(thickness 0.15)
				)
			)
		)
		(property "MPN" "ERJ2GE0R00X"
			(at 392.791002 378.321 0)
			(layer "F.Fab")
			(hide yes)
			(effects
				(font
					(size 1 1)
					(thickness 0.15)
				)
			)
		)
		(property "Manufacturer" "Panasonic"
			(at 392.791002 378.321 0)
			(layer "F.Fab")
			(hide yes)
			(effects
				(font
					(size 1 1)
					(thickness 0.15)
				)
			)
		)
		(property "Tolerance" ""
			(at 392.791002 378.321 0)
			(layer "F.Fab")
			(hide yes)
			(effects
				(font
					(size 1 1)
					(thickness 0.15)
				)
			)
		)
		(property "Val" "0R"
			(at 392.791002 378.321 0)
			(layer "F.Fab")
			(hide yes)
			(effects
				(font
					(size 1 1)
					(thickness 0.15)
				)
			)
		)
		(sheetname "/Supply/")
		(sheetfile "supply.kicad_sch")
		(attr smd)
		(fp_rect
			(start -0.93 -0.47)
			(end 0.93 0.47)
			(stroke
				(width 0.05)
				(type solid)
			)
			(fill no)
			(layer "F.CrtYd")
		)
		(fp_rect
			(start -0.5 -0.25)
			(end 0.5 0.25)
			(stroke
				(width 0.15)
				(type solid)
			)
			(fill no)
			(layer "F.Fab")
		)
		(pad "1" smd roundrect
			(at -0.485 0 180)
			(size 0.59 0.64)
			(layers "F.Cu" "F.Mask" "F.Paste")
			(roundrect_rratio 0.25)
			(net 210 "/Supply/FB1")
			(pintype "passive")
		)
		(pad "2" smd roundrect
			(at 0.485 0 180)
			(size 0.59 0.64)
			(layers "F.Cu" "F.Mask" "F.Paste")
			(roundrect_rratio 0.25)
			(net 42 "/Supply/MGTAVCC_local")
			(pintype "passive")
		)
	)
	(footprint "antmicro-footprints:R_0603_1608Metric"
		(layer "F.Cu")
		(at 190.725 193.3 180)
		(descr "Resistor SMD 0603")
		(tags "resistor SMD 0603")
		(property "Reference" "R183"
			(at 1.375 0.8 180)
			(layer "F.SilkS")
			(effects
				(font
					(size 0.7 0.7)
					(thickness 0.15)
				)
				(justify left bottom)
			)
		)
		(property "Value" "R_0R_22.4A_0603"
			(at 0 1.6 180)
			(layer "F.Fab")
			(effects
				(font
					(size 0.7 0.7)
					(thickness 0.15)
				)
				(justify left bottom)
			)
		)
		(property "Datasheet" "https://fscdn.rohm.com/en/products/databook/datasheet/passive/resistor/chip_resistor/pmr-jpw-e.pdf"
			(at 0 0 180)
			(layer "F.Fab")
			(hide yes)
			(effects
				(font
					(size 1.27 1.27)
					(thickness 0.15)
				)
			)
		)
		(property "Author" "Antmicro"
			(at 381.45 386.6 0)
			(layer "F.Fab")
			(hide yes)
			(effects
				(font
					(size 1 1)
					(thickness 0.15)
				)
			)
		)
		(property "License" "Apache-2.0"
			(at 381.45 386.6 0)
			(layer "F.Fab")
			(hide yes)
			(effects
				(font
					(size 1 1)
					(thickness 0.15)
				)
			)
		)
		(property "MPN" "PMR03EZPJ000"
			(at 381.45 386.6 0)
			(layer "F.Fab")
			(hide yes)
			(effects
				(font
					(size 1 1)
					(thickness 0.15)
				)
			)
		)
		(property "Manufacturer" "ROHM Semiconductor"
			(at 381.45 386.6 0)
			(layer "F.Fab")
			(hide yes)
			(effects
				(font
					(size 1 1)
					(thickness 0.15)
				)
			)
		)
		(property "Max. Curr." "22.4A"
			(at 381.45 386.6 0)
			(layer "F.Fab")
			(hide yes)
			(effects
				(font
					(size 1 1)
					(thickness 0.15)
				)
			)
		)
		(property "Val" "0R"
			(at 381.45 386.6 0)
			(layer "F.Fab")
			(hide yes)
			(effects
				(font
					(size 1 1)
					(thickness 0.15)
				)
			)
		)
		(sheetname "/Supply/")
		(sheetfile "supply.kicad_sch")
		(attr smd)
		(fp_line
			(start -0.3 0.3)
			(end 0.3 0.3)
			(stroke
				(width 0.15)
				(type solid)
			)
			(layer "F.SilkS")
		)
		(fp_line
			(start -0.3 -0.3)
			(end 0.3 -0.3)
			(stroke
				(width 0.15)
				(type solid)
			)
			(layer "F.SilkS")
		)
		(fp_rect
			(start -1.25 -0.7)
			(end 1.25 0.7)
			(stroke
				(width 0.05)
				(type solid)
			)
			(fill no)
			(layer "F.CrtYd")
		)
		(fp_rect
			(start -0.8 -0.4)
			(end 0.8 0.4)
			(stroke
				(width 0.15)
				(type solid)
			)
			(fill no)
			(layer "F.Fab")
		)
		(pad "1" smd roundrect
			(at -0.7 0 180)
			(size 0.6 0.8)
			(layers "F.Cu" "F.Mask" "F.Paste")
			(roundrect_rratio 0.2)
			(net 76 "/Supply/MGTAVTT_OUT")
			(pintype "passive")
		)
		(pad "2" smd roundrect
			(at 0.7 0 180)
			(size 0.6 0.8)
			(layers "F.Cu" "F.Mask" "F.Paste")
			(roundrect_rratio 0.2)
			(net 226 "+1V2_MGTAVTT")
			(pintype "passive")
		)
	)
	(footprint "antmicro-footprints:Oscillator_SMD_Abracon_ASFL1-4Pin_5.0x3.2mm"
		(layer "F.Cu")
		(at 135 191.9)
		(property "Reference" "Y3"
			(at 3 -1.1 0)
			(layer "F.SilkS")
			(effects
				(font
					(size 0.7 0.7)
					(thickness 0.15)
				)
				(justify left bottom)
			)
		)
		(property "Value" "Oscillator_100MHz_ASFL1"
			(at -11.7 3.3 0)
			(layer "F.Fab")
			(effects
				(font
					(size 0.7 0.7)
					(thickness 0.15)
				)
				(justify left bottom)
			)
		)
		(property "Datasheet" "https://abracon.com/Oscillators/ASFL1.pdf"
			(at 0 0 0)
			(layer "F.Fab")
			(hide yes)
			(effects
				(font
					(size 1.27 1.27)
					(thickness 0.15)
				)
			)
		)
		(property "Author" "Antmicro"
			(at 0 0 0)
			(layer "F.Fab")
			(hide yes)
			(effects
				(font
					(size 1 1)
					(thickness 0.15)
				)
			)
		)
		(property "License" "Apache-2.0"
			(at 0 0 0)
			(layer "F.Fab")
			(hide yes)
			(effects
				(font
					(size 1 1)
					(thickness 0.15)
				)
			)
		)
		(property "MPN" "ASFL1-100.000MHZ-L-T"
			(at 0 0 0)
			(layer "F.Fab")
			(hide yes)
			(effects
				(font
					(size 1 1)
					(thickness 0.15)
				)
			)
		)
		(property "Manufacturer" "Abracon"
			(at 0 0 0)
			(layer "F.Fab")
			(hide yes)
			(effects
				(font
					(size 1 1)
					(thickness 0.15)
				)
			)
		)
		(property "Val" "100 MHz"
			(at 0 0 0)
			(layer "F.Fab")
			(hide yes)
			(effects
				(font
					(size 1 1)
					(thickness 0.15)
				)
			)
		)
		(sheetname "/FPGA bank 16/")
		(sheetfile "fpga-bank-16.kicad_sch")
		(attr smd)
		(fp_line
			(start -2.702 -1.801)
			(end -2.301 -1.801)
			(stroke
				(width 0.15)
				(type solid)
			)
			(layer "F.SilkS")
		)
		(fp_line
			(start -2.702 -1.401)
			(end -2.702 -1.801)
			(stroke
				(width 0.15)
				(type solid)
			)
			(layer "F.SilkS")
		)
		(fp_line
			(start -2.702 1.8)
			(end -2.702 1.398)
			(stroke
				(width 0.15)
				(type solid)
			)
			(layer "F.SilkS")
		)
		(fp_line
			(start 2.298 -1.801)
			(end 2.7 -1.801)
			(stroke
				(width 0.15)
				(type solid)
			)
			(layer "F.SilkS")
		)
		(fp_line
			(start 2.7 -1.801)
			(end 2.7 -1.401)
			(stroke
				(width 0.15)
				(type solid)
			)
			(layer "F.SilkS")
		)
		(fp_line
			(start 2.7 1.398)
			(end 2.7 1.8)
			(stroke
				(width 0.15)
				(type solid)
			)
			(layer "F.SilkS")
		)
		(fp_line
			(start 2.7 1.8)
			(end 2.298 1.8)
			(stroke
				(width 0.15)
				(type solid)
			)
			(layer "F.SilkS")
		)
		(fp_circle
			(center -2.4 2.1)
			(end -2.35 2.1)
			(stroke
				(width 0.15)
				(type solid)
			)
			(fill no)
			(layer "F.SilkS")
		)
		(fp_rect
			(start -3 -2.101)
			(end 2.999 2.1)
			(stroke
				(width 0.05)
				(type solid)
			)
			(fill no)
			(layer "F.CrtYd")
		)
		(fp_line
			(start -2.3 1.6)
			(end -2.5 1.4)
			(stroke
				(width 0.15)
				(type solid)
			)
			(layer "F.Fab")
		)
		(fp_line
			(start -2.2 1.6)
			(end -2.5 1.3)
			(stroke
				(width 0.15)
				(type solid)
			)
			(layer "F.Fab")
		)
		(fp_line
			(start -2.1 1.6)
			(end -2.5 1.2)
			(stroke
				(width 0.15)
				(type solid)
			)
			(layer "F.Fab")
		)
		(fp_line
			(start -2 1.6)
			(end -2.5 1.1)
			(stroke
				(width 0.15)
				(type solid)
			)
			(layer "F.Fab")
		)
		(fp_rect
			(start -2.5 -1.601)
			(end 2.499 1.6)
			(stroke
				(width 0.15)
				(type solid)
			)
			(fill no)
			(layer "F.Fab")
		)
		(pad "1" smd rect
			(at -1.27 1.1 180)
			(size 1.7 1.5)
			(layers "F.Cu" "F.Mask" "F.Paste")
			(net 200 "+3V3")
			(pinfunction "EN")
			(pintype "input")
		)
		(pad "2" smd rect
			(at 1.269 1.1)
			(size 1.7 1.5)
			(layers "F.Cu" "F.Mask" "F.Paste")
			(net 1 "GND")
			(pinfunction "GND")
			(pintype "power_in")
		)
		(pad "3" smd rect
			(at 1.269 -1.101)
			(size 1.7 1.5)
			(layers "F.Cu" "F.Mask" "F.Paste")
			(net 706 "/FPGA bank 16/GCLK100")
			(pinfunction "OUT")
			(pintype "output")
		)
		(pad "4" smd rect
			(at -1.27 -1.101)
			(size 1.7 1.5)
			(layers "F.Cu" "F.Mask" "F.Paste")
			(net 200 "+3V3")
			(pinfunction "VDD")
			(pintype "power_in")
		)
	)
	(footprint "antmicro-footprints:R_0402_1005Metric"
		(layer "F.Cu")
		(at 107.3 184.8 -90)
		(descr "Resistor SMD 0402")
		(tags "resistor SMD 0402")
		(property "Reference" "R94"
			(at -1.122484 -0.772697 270)
			(layer "F.SilkS")
			(hide yes)
			(effects
				(font
					(size 0.7 0.7)
					(thickness 0.15)
				)
				(justify left bottom)
			)
		)
		(property "Value" "R_4k7_0402"
			(at -1.011843 1.772047 270)
			(layer "F.Fab")
			(effects
				(font
					(size 0.7 0.7)
					(thickness 0.15)
				)
				(justify left bottom)
			)
		)
		(property "Datasheet" "https://www.bourns.com/docs/product-datasheets/cr.pdf"
			(at 0 0 270)
			(layer "F.Fab")
			(hide yes)
			(effects
				(font
					(size 1.27 1.27)
					(thickness 0.15)
				)
			)
		)
		(property "Author" "Antmicro"
			(at -77.5 292.1 0)
			(layer "F.Fab")
			(hide yes)
			(effects
				(font
					(size 1 1)
					(thickness 0.15)
				)
			)
		)
		(property "License" "Apache-2.0"
			(at -77.5 292.1 0)
			(layer "F.Fab")
			(hide yes)
			(effects
				(font
					(size 1 1)
					(thickness 0.15)
				)
			)
		)
		(property "MPN" "CR0402-FX-4701GLF"
			(at -77.5 292.1 0)
			(layer "F.Fab")
			(hide yes)
			(effects
				(font
					(size 1 1)
					(thickness 0.15)
				)
			)
		)
		(property "Manufacturer" "Bourns"
			(at -77.5 292.1 0)
			(layer "F.Fab")
			(hide yes)
			(effects
				(font
					(size 1 1)
					(thickness 0.15)
				)
			)
		)
		(property "Tolerance" "1%"
			(at -77.5 292.1 0)
			(layer "F.Fab")
			(hide yes)
			(effects
				(font
					(size 1 1)
					(thickness 0.15)
				)
			)
		)
		(property "Val" "4k7"
			(at -77.5 292.1 0)
			(layer "F.Fab")
			(hide yes)
			(effects
				(font
					(size 1 1)
					(thickness 0.15)
				)
			)
		)
		(sheetname "/Debug FTDI/")
		(sheetfile "debug-ftdi.kicad_sch")
		(attr smd)
		(fp_rect
			(start -0.93 -0.47)
			(end 0.93 0.47)
			(stroke
				(width 0.05)
				(type solid)
			)
			(fill no)
			(layer "F.CrtYd")
		)
		(fp_rect
			(start -0.5 -0.25)
			(end 0.5 0.25)
			(stroke
				(width 0.15)
				(type solid)
			)
			(fill no)
			(layer "F.Fab")
		)
		(pad "1" smd roundrect
			(at -0.485 0 270)
			(size 0.59 0.64)
			(layers "F.Cu" "F.Mask" "F.Paste")
			(roundrect_rratio 0.25)
			(net 41 "+3V3_AON")
			(pintype "passive")
		)
		(pad "2" smd roundrect
			(at 0.485 0 270)
			(size 0.59 0.64)
			(layers "F.Cu" "F.Mask" "F.Paste")
			(roundrect_rratio 0.25)
			(net 671 "/Debug FTDI/FTDI.SCL")
			(pintype "passive")
		)
	)
	(footprint "antmicro-footprints:R_0402_1005Metric"
		(layer "F.Cu")
		(at 91.748501 126.719 -90)
		(descr "Resistor SMD 0402")
		(tags "resistor SMD 0402")
		(property "Reference" "R13"
			(at -1.122484 -0.772697 270)
			(layer "F.SilkS")
			(hide yes)
			(effects
				(font
					(size 0.7 0.7)
					(thickness 0.15)
				)
				(justify left bottom)
			)
		)
		(property "Value" "R_330R_0402"
			(at -1.011843 1.772047 270)
			(layer "F.Fab")
			(effects
				(font
					(size 0.7 0.7)
					(thickness 0.15)
				)
				(justify left bottom)
			)
		)
		(property "Datasheet" "https://www.bourns.com/docs/product-datasheets/cr.pdf"
			(at 0 0 270)
			(layer "F.Fab")
			(hide yes)
			(effects
				(font
					(size 1.27 1.27)
					(thickness 0.15)
				)
			)
		)
		(property "Author" "Antmicro"
			(at -34.970499 218.467501 0)
			(layer "F.Fab")
			(hide yes)
			(effects
				(font
					(size 1 1)
					(thickness 0.15)
				)
			)
		)
		(property "License" "Apache-2.0"
			(at -34.970499 218.467501 0)
			(layer "F.Fab")
			(hide yes)
			(effects
				(font
					(size 1 1)
					(thickness 0.15)
				)
			)
		)
		(property "MPN" "CR0402-FX-3300GLF"
			(at -34.970499 218.467501 0)
			(layer "F.Fab")
			(hide yes)
			(effects
				(font
					(size 1 1)
					(thickness 0.15)
				)
			)
		)
		(property "Manufacturer" "Bourns"
			(at -34.970499 218.467501 0)
			(layer "F.Fab")
			(hide yes)
			(effects
				(font
					(size 1 1)
					(thickness 0.15)
				)
			)
		)
		(property "Tolerance" "1%"
			(at -34.970499 218.467501 0)
			(layer "F.Fab")
			(hide yes)
			(effects
				(font
					(size 1 1)
					(thickness 0.15)
				)
			)
		)
		(property "Val" "330R"
			(at -34.970499 218.467501 0)
			(layer "F.Fab")
			(hide yes)
			(effects
				(font
					(size 1 1)
					(thickness 0.15)
				)
			)
		)
		(sheetname "/FPGA Config/")
		(sheetfile "fpga-config.kicad_sch")
		(attr smd)
		(fp_rect
			(start -0.93 -0.47)
			(end 0.93 0.47)
			(stroke
				(width 0.05)
				(type solid)
			)
			(fill no)
			(layer "F.CrtYd")
		)
		(fp_rect
			(start -0.5 -0.25)
			(end 0.5 0.25)
			(stroke
				(width 0.15)
				(type solid)
			)
			(fill no)
			(layer "F.Fab")
		)
		(pad "1" smd roundrect
			(at -0.485 0 270)
			(size 0.59 0.64)
			(layers "F.Cu" "F.Mask" "F.Paste")
			(roundrect_rratio 0.25)
			(net 306 "Net-(D3-Pad2)")
			(pintype "passive")
		)
		(pad "2" smd roundrect
			(at 0.485 0 270)
			(size 0.59 0.64)
			(layers "F.Cu" "F.Mask" "F.Paste")
			(roundrect_rratio 0.25)
			(net 352 "Net-(Q3-D)")
			(pintype "passive")
		)
	)
	(footprint "antmicro-footprints:C_0402_1005Metric"
		(layer "F.Cu")
		(at 82.9995 182.9 90)
		(descr "Capacitor SMD 0402")
		(tags "capacitor SMD 0402")
		(property "Reference" "C132"
			(at 0 -0.699 90)
			(layer "F.SilkS")
			(hide yes)
			(effects
				(font
					(size 0.7 0.7)
					(thickness 0.15)
				)
				(justify left bottom)
			)
		)
		(property "Value" "C_100n_0402"
			(at -1.022927 2.155213 90)
			(layer "F.Fab")
			(effects
				(font
					(size 0.7 0.7)
					(thickness 0.15)
				)
				(justify left bottom)
			)
		)
		(property "Datasheet" "https://www.murata.com/products/productdetail?partno=GRM155R61H104KE14%23"
			(at 0 0 90)
			(layer "F.Fab")
			(hide yes)
			(effects
				(font
					(size 1.27 1.27)
					(thickness 0.15)
				)
			)
		)
		(property "Author" "Antmicro"
			(at 265.8995 99.9005 0)
			(layer "F.Fab")
			(hide yes)
			(effects
				(font
					(size 1 1)
					(thickness 0.15)
				)
			)
		)
		(property "Dielectric" "X5R"
			(at 265.8995 99.9005 0)
			(layer "F.Fab")
			(hide yes)
			(effects
				(font
					(size 1 1)
					(thickness 0.15)
				)
			)
		)
		(property "License" "Apache-2.0"
			(at 265.8995 99.9005 0)
			(layer "F.Fab")
			(hide yes)
			(effects
				(font
					(size 1 1)
					(thickness 0.15)
				)
			)
		)
		(property "MPN" "GRM155R61H104KE14D"
			(at 265.8995 99.9005 0)
			(layer "F.Fab")
			(hide yes)
			(effects
				(font
					(size 1 1)
					(thickness 0.15)
				)
			)
		)
		(property "Manufacturer" "Murata"
			(at 265.8995 99.9005 0)
			(layer "F.Fab")
			(hide yes)
			(effects
				(font
					(size 1 1)
					(thickness 0.15)
				)
			)
		)
		(property "Val" "100n"
			(at 265.8995 99.9005 0)
			(layer "F.Fab")
			(hide yes)
			(effects
				(font
					(size 1 1)
					(thickness 0.15)
				)
			)
		)
		(property "Voltage" "50V"
			(at 265.8995 99.9005 0)
			(layer "F.Fab")
			(hide yes)
			(effects
				(font
					(size 1 1)
					(thickness 0.15)
				)
			)
		)
		(sheetname "/HDMI + SD Card/")
		(sheetfile "hdmi-sd-card.kicad_sch")
		(attr smd)
		(fp_rect
			(start -0.9659 -0.481258)
			(end 0.9649 0.458742)
			(stroke
				(width 0.05)
				(type solid)
			)
			(fill no)
			(layer "F.CrtYd")
		)
		(fp_line
			(start 0.499 -0.25)
			(end 0.499 0.248)
			(stroke
				(width 0.15)
				(type solid)
			)
			(layer "F.Fab")
		)
		(fp_line
			(start -0.499 -0.25)
			(end 0.499 -0.25)
			(stroke
				(width 0.15)
				(type solid)
			)
			(layer "F.Fab")
		)
		(fp_line
			(start 0.499 0.248)
			(end -0.499 0.248)
			(stroke
				(width 0.15)
				(type solid)
			)
			(layer "F.Fab")
		)
		(fp_line
			(start -0.499 0.248)
			(end -0.499 -0.25)
			(stroke
				(width 0.15)
				(type solid)
			)
			(layer "F.Fab")
		)
		(pad "1" smd roundrect
			(at -0.484 0 90)
			(size 0.59 0.64)
			(layers "F.Cu" "F.Mask" "F.Paste")
			(roundrect_rratio 0.25)
			(net 251 "Net-(C132-Pad1)")
			(pintype "passive")
		)
		(pad "2" smd roundrect
			(at 0.484 0 90)
			(size 0.59 0.64)
			(layers "F.Cu" "F.Mask" "F.Paste")
			(roundrect_rratio 0.25)
			(net 1 "GND")
			(pintype "passive")
		)
	)
	(footprint "antmicro-footprints:C_0603_1608Metric"
		(layer "F.Cu")
		(at 193.713499 134.94 -90)
		(descr "Capacitor SMD 0603")
		(tags "capacitor 0603")
		(property "Reference" "C181"
			(at -1.42757 -1.000252 270)
			(layer "F.SilkS")
			(hide yes)
			(effects
				(font
					(size 0.7 0.7)
					(thickness 0.15)
				)
				(justify left bottom)
			)
		)
		(property "Value" "C_1u_25V_0603"
			(at -1.42757 1.770288 270)
			(layer "F.Fab")
			(effects
				(font
					(size 0.7 0.7)
					(thickness 0.15)
				)
				(justify left bottom)
			)
		)
		(property "Datasheet" "https://product.samsungsem.com/mlcc/CL10A105KA8NNN.do"
			(at 0 0 270)
			(layer "F.Fab")
			(hide yes)
			(effects
				(font
					(size 1.27 1.27)
					(thickness 0.15)
				)
			)
		)
		(property "Author" "Antmicro"
			(at 58.773499 328.653499 0)
			(layer "F.Fab")
			(hide yes)
			(effects
				(font
					(size 1 1)
					(thickness 0.15)
				)
			)
		)
		(property "Dielectric" ""
			(at 58.773499 328.653499 0)
			(layer "F.Fab")
			(hide yes)
			(effects
				(font
					(size 1 1)
					(thickness 0.15)
				)
			)
		)
		(property "License" "Apache-2.0"
			(at 58.773499 328.653499 0)
			(layer "F.Fab")
			(hide yes)
			(effects
				(font
					(size 1 1)
					(thickness 0.15)
				)
			)
		)
		(property "MPN" "CL10A105KA8NNNC"
			(at 58.773499 328.653499 0)
			(layer "F.Fab")
			(hide yes)
			(effects
				(font
					(size 1 1)
					(thickness 0.15)
				)
			)
		)
		(property "Manufacturer" "Samsung Electro-Mechanics"
			(at 58.773499 328.653499 0)
			(layer "F.Fab")
			(hide yes)
			(effects
				(font
					(size 1 1)
					(thickness 0.15)
				)
			)
		)
		(property "Val" "1u/25V"
			(at 58.773499 328.653499 0)
			(layer "F.Fab")
			(hide yes)
			(effects
				(font
					(size 1 1)
					(thickness 0.15)
				)
			)
		)
		(property "Voltage" ""
			(at 58.773499 328.653499 0)
			(layer "F.Fab")
			(hide yes)
			(effects
				(font
					(size 1 1)
					(thickness 0.15)
				)
			)
		)
		(sheetname "/Supply/")
		(sheetfile "supply.kicad_sch")
		(attr smd)
		(fp_line
			(start -0.3 0.3)
			(end 0.3 0.3)
			(stroke
				(width 0.15)
				(type solid)
			)
			(layer "F.SilkS")
		)
		(fp_line
			(start -0.3 -0.3)
			(end 0.3 -0.3)
			(stroke
				(width 0.15)
				(type solid)
			)
			(layer "F.SilkS")
		)
		(fp_rect
			(start -1.24 -0.7)
			(end 1.24 0.7)
			(stroke
				(width 0.05)
				(type solid)
			)
			(fill no)
			(layer "F.CrtYd")
		)
		(fp_rect
			(start -0.8 -0.4)
			(end 0.8 0.4)
			(stroke
				(width 0.15)
				(type solid)
			)
			(fill no)
			(layer "F.Fab")
		)
		(pad "1" smd roundrect
			(at -0.7 0 270)
			(size 0.6 0.8)
			(layers "F.Cu" "F.Mask" "F.Paste")
			(roundrect_rratio 0.2)
			(net 38 "VDC")
			(pintype "passive")
		)
		(pad "2" smd roundrect
			(at 0.7 0 270)
			(size 0.6 0.8)
			(layers "F.Cu" "F.Mask" "F.Paste")
			(roundrect_rratio 0.2)
			(net 1 "GND")
			(pintype "passive")
		)
	)
	(footprint "antmicro-footprints:USON-10_2.5x1mm_P0.5mm"
		(layer "F.Cu")
		(at 84.8 168.5)
		(descr "USON-10 2.5x1mm_ Pitch 0.5mm")
		(tags "USON-10 2.5x1mm Pitch 0.5mm")
		(property "Reference" "U14"
			(at 0.018 -1.7 0)
			(layer "F.SilkS")
			(hide yes)
			(effects
				(font
					(size 0.7 0.7)
					(thickness 0.15)
				)
				(justify left bottom)
			)
		)
		(property "Value" "TPD4E05U06QDQARQ1"
			(at 0.018 2.499 0)
			(layer "F.Fab")
			(effects
				(font
					(size 0.7 0.7)
					(thickness 0.15)
				)
				(justify left bottom)
			)
		)
		(property "Datasheet" "https://www.ti.com/lit/ds/symlink/tpd4e05u06-q1.pdf?HQS=dis-mous-null-mousermode-dsf-pf-null-wwe&ts=1663591265741&ref_url=https%253A%252F%252Fwww.mouser.com%252F"
			(at 0 0 0)
			(layer "F.Fab")
			(hide yes)
			(effects
				(font
					(size 1.27 1.27)
					(thickness 0.15)
				)
			)
		)
		(property "Author" "Antmicro"
			(at 0 0 0)
			(layer "F.Fab")
			(hide yes)
			(effects
				(font
					(size 1 1)
					(thickness 0.15)
				)
			)
		)
		(property "License" "Apache-2.0"
			(at 0 0 0)
			(layer "F.Fab")
			(hide yes)
			(effects
				(font
					(size 1 1)
					(thickness 0.15)
				)
			)
		)
		(property "MPN" "TPD4E05U06QDQARQ1"
			(at 0 0 0)
			(layer "F.Fab")
			(hide yes)
			(effects
				(font
					(size 1 1)
					(thickness 0.15)
				)
			)
		)
		(property "Manufacturer" "Texas Instruments"
			(at 0 0 0)
			(layer "F.Fab")
			(hide yes)
			(effects
				(font
					(size 1 1)
					(thickness 0.15)
				)
			)
		)
		(sheetname "/HDMI + SD Card/")
		(sheetfile "hdmi-sd-card.kicad_sch")
		(attr smd)
		(fp_line
			(start 0.498 -1.401)
			(end -0.5 -1.401)
			(stroke
				(width 0.15)
				(type solid)
			)
			(layer "F.SilkS")
		)
		(fp_line
			(start 0.498 1.398)
			(end -0.5 1.398)
			(stroke
				(width 0.15)
				(type solid)
			)
			(layer "F.SilkS")
		)
		(fp_circle
			(center -0.68 -1.27)
			(end -0.63 -1.27)
			(stroke
				(width 0.15)
				(type solid)
			)
			(fill yes)
			(layer "F.SilkS")
		)
		(fp_rect
			(start -0.8 -1.5)
			(end 0.8 1.499)
			(stroke
				(width 0.05)
				(type solid)
			)
			(fill no)
			(layer "F.CrtYd")
		)
		(fp_line
			(start -0.5 -1)
			(end -0.5 1.249)
			(stroke
				(width 0.15)
				(type solid)
			)
			(layer "F.Fab")
		)
		(fp_line
			(start -0.5 1.249)
			(end 0.498 1.249)
			(stroke
				(width 0.15)
				(type solid)
			)
			(layer "F.Fab")
		)
		(fp_line
			(start -0.25 -1.25)
			(end -0.5 -1)
			(stroke
				(width 0.15)
				(type solid)
			)
			(layer "F.Fab")
		)
		(fp_line
			(start 0.498 -1.25)
			(end -0.25 -1.25)
			(stroke
				(width 0.15)
				(type solid)
			)
			(layer "F.Fab")
		)
		(fp_line
			(start 0.498 -1.25)
			(end 0.498 1.249)
			(stroke
				(width 0.15)
				(type solid)
			)
			(layer "F.Fab")
		)
		(pad "1" smd roundrect
			(at -0.387 -1 270)
			(size 0.25 0.55)
			(layers "F.Cu" "F.Mask" "F.Paste")
			(roundrect_rratio 0.25)
			(net 669 "/FPGA bank 16/SD.CD")
			(pintype "passive")
		)
		(pad "2" smd roundrect
			(at -0.387 -0.5 270)
			(size 0.25 0.55)
			(layers "F.Cu" "F.Mask" "F.Paste")
			(roundrect_rratio 0.25)
			(net 594 "/FPGA bank 16/SD.DAT1")
			(pintype "passive")
		)
		(pad "3" smd roundrect
			(at -0.387 0 270)
			(size 0.4 0.55)
			(layers "F.Cu" "F.Mask" "F.Paste")
			(roundrect_rratio 0.25)
			(net 1 "GND")
			(pintype "power_in")
		)
		(pad "4" smd roundrect
			(at -0.387 0.498 270)
			(size 0.25 0.55)
			(layers "F.Cu" "F.Mask" "F.Paste")
			(roundrect_rratio 0.25)
			(net 374 "/FPGA bank 16/SD.DAT0")
			(pintype "passive")
		)
		(pad "5" smd roundrect
			(at -0.387 0.998 270)
			(size 0.25 0.55)
			(layers "F.Cu" "F.Mask" "F.Paste")
			(roundrect_rratio 0.25)
			(net 756 "unconnected-(U14-Pad5)_1")
			(pintype "passive+no_connect")
		)
		(pad "6" smd roundrect
			(at 0.385 0.998 270)
			(size 0.25 0.55)
			(layers "F.Cu" "F.Mask" "F.Paste")
			(roundrect_rratio 0.25)
			(net 582 "unconnected-(U14-Pad5)")
			(pintype "passive+no_connect")
		)
		(pad "7" smd roundrect
			(at 0.385 0.498 270)
			(size 0.25 0.55)
			(layers "F.Cu" "F.Mask" "F.Paste")
			(roundrect_rratio 0.25)
			(net 374 "/FPGA bank 16/SD.DAT0")
			(pintype "passive")
		)
		(pad "8" smd roundrect
			(at 0.385 0 270)
			(size 0.4 0.55)
			(layers "F.Cu" "F.Mask" "F.Paste")
			(roundrect_rratio 0.25)
			(net 1 "GND")
			(pintype "passive")
		)
		(pad "9" smd roundrect
			(at 0.385 -0.5 270)
			(size 0.25 0.55)
			(layers "F.Cu" "F.Mask" "F.Paste")
			(roundrect_rratio 0.25)
			(net 594 "/FPGA bank 16/SD.DAT1")
			(pintype "passive")
		)
		(pad "10" smd roundrect
			(at 0.385 -1 270)
			(size 0.25 0.55)
			(layers "F.Cu" "F.Mask" "F.Paste")
			(roundrect_rratio 0.25)
			(net 669 "/FPGA bank 16/SD.CD")
			(pintype "passive")
		)
	)
	(footprint "antmicro-footprints:F_1206_3216Metric"
		(layer "F.Cu")
		(at 115.5 203.8 90)
		(property "Reference" "F2"
			(at 2.15 1.1 90)
			(layer "F.SilkS")
			(effects
				(font
					(size 0.7 0.7)
					(thickness 0.15)
				)
				(justify left bottom)
			)
		)
		(property "Value" "F_4A_1206"
			(at 0 2 90)
			(layer "F.Fab")
			(effects
				(font
					(size 0.7 0.7)
					(thickness 0.15)
				)
				(justify left bottom)
			)
		)
		(property "Datasheet" "https://www.littelfuse.com/media?resourcetype=datasheets&itemid=dbe9bcd7-6072-4adf-bf5b-d33e52a6b90f&filename=littelfuse-fuse-466-datasheet"
			(at 0 0 90)
			(layer "F.Fab")
			(hide yes)
			(effects
				(font
					(size 1.27 1.27)
					(thickness 0.15)
				)
			)
		)
		(property "Author" "Antmicro"
			(at 319.3 88.3 0)
			(layer "F.Fab")
			(hide yes)
			(effects
				(font
					(size 1 1)
					(thickness 0.15)
				)
			)
		)
		(property "License" "Apache-2.0"
			(at 319.3 88.3 0)
			(layer "F.Fab")
			(hide yes)
			(effects
				(font
					(size 1 1)
					(thickness 0.15)
				)
			)
		)
		(property "MPN" "0466004.NR "
			(at 319.3 88.3 0)
			(layer "F.Fab")
			(hide yes)
			(effects
				(font
					(size 1 1)
					(thickness 0.15)
				)
			)
		)
		(property "Manufacturer" "Littelfuse"
			(at 319.3 88.3 0)
			(layer "F.Fab")
			(hide yes)
			(effects
				(font
					(size 1 1)
					(thickness 0.15)
				)
			)
		)
		(sheetname "/Supply/")
		(sheetfile "supply.kicad_sch")
		(attr smd)
		(fp_line
			(start -0.413 -0.861)
			(end 0.36 -0.861)
			(stroke
				(width 0.15)
				(type solid)
			)
			(layer "F.SilkS")
		)
		(fp_line
			(start -0.413 0.792)
			(end 0.36 0.792)
			(stroke
				(width 0.15)
				(type solid)
			)
			(layer "F.SilkS")
		)
		(fp_rect
			(start -1.95 -1)
			(end 1.95 1)
			(stroke
				(width 0.05)
				(type solid)
			)
			(fill no)
			(layer "F.CrtYd")
		)
		(fp_line
			(start 1.624 -0.861)
			(end 1.624 0.792)
			(stroke
				(width 0.15)
				(type solid)
			)
			(layer "F.Fab")
		)
		(fp_line
			(start -1.677 -0.861)
			(end 1.624 -0.861)
			(stroke
				(width 0.15)
				(type solid)
			)
			(layer "F.Fab")
		)
		(fp_line
			(start 1.624 0.792)
			(end -1.677 0.792)
			(stroke
				(width 0.15)
				(type solid)
			)
			(layer "F.Fab")
		)
		(fp_line
			(start -1.677 0.792)
			(end -1.677 -0.861)
			(stroke
				(width 0.15)
				(type solid)
			)
			(layer "F.Fab")
		)
		(pad "1" smd rect
			(at -1.35 0 90)
			(size 1.143 2.032)
			(layers "F.Cu" "F.Mask" "F.Paste")
			(net 11 "+12V")
			(pintype "passive")
		)
		(pad "2" smd rect
			(at 1.35 0 90)
			(size 1.143 2.032)
			(layers "F.Cu" "F.Mask" "F.Paste")
			(net 596 "/Supply/12V_PCIE_fused")
			(pintype "passive")
		)
	)
	(footprint "antmicro-footprints:X2SON8_1.4x1x0.32mm_P0.35mm"
		(layer "F.Cu")
		(at 104.81 171.835)
		(property "Reference" "U33"
			(at -0.62 2.899 90)
			(layer "F.SilkS")
			(effects
				(font
					(size 0.7 0.7)
					(thickness 0.15)
				)
				(justify left bottom)
			)
		)
		(property "Value" "TXS0102DQER"
			(at 0 1.929 0)
			(layer "F.Fab")
			(effects
				(font
					(size 0.7 0.7)
					(thickness 0.15)
				)
				(justify left bottom)
			)
		)
		(property "Datasheet" "https://www.ti.com/lit/ds/symlink/txs0102.pdf?ts=1637914596981&ref_url=https%253A%252F%252Fwww.ti.com%252Fstore%252Fti%252Fen%252Fp%252Fproduct%252F%253Fp%253DTXS0102DCTR%2526keyMatch%253DTXS0102DCTR%2526tisearch%253Dsearch-everything%2526usecase%253DOPN"
			(at 0 0 0)
			(layer "F.Fab")
			(hide yes)
			(effects
				(font
					(size 1.27 1.27)
					(thickness 0.15)
				)
			)
		)
		(property "Author" "Antmicro"
			(at 0 0 0)
			(layer "F.Fab")
			(hide yes)
			(effects
				(font
					(size 1 1)
					(thickness 0.15)
				)
			)
		)
		(property "License" "Apache-2.0"
			(at 0 0 0)
			(layer "F.Fab")
			(hide yes)
			(effects
				(font
					(size 1 1)
					(thickness 0.15)
				)
			)
		)
		(property "MPN" "TXS0102DQER"
			(at 0 0 0)
			(layer "F.Fab")
			(hide yes)
			(effects
				(font
					(size 1 1)
					(thickness 0.15)
				)
			)
		)
		(property "Manufacturer" "Texas Instruments"
			(at 0 0 0)
			(layer "F.Fab")
			(hide yes)
			(effects
				(font
					(size 1 1)
					(thickness 0.15)
				)
			)
		)
		(sheetname "/Debug FTDI/")
		(sheetfile "debug-ftdi.kicad_sch")
		(attr smd)
		(fp_line
			(start -0.6 -0.801)
			(end -0.6 -0.7)
			(stroke
				(width 0.15)
				(type solid)
			)
			(layer "F.SilkS")
		)
		(fp_line
			(start -0.6 0.7)
			(end -0.6 0.801)
			(stroke
				(width 0.15)
				(type solid)
			)
			(layer "F.SilkS")
		)
		(fp_line
			(start -0.6 0.801)
			(end -0.5 0.801)
			(stroke
				(width 0.15)
				(type solid)
			)
			(layer "F.SilkS")
		)
		(fp_line
			(start -0.402 -0.801)
			(end -0.6 -0.801)
			(stroke
				(width 0.15)
				(type solid)
			)
			(layer "F.SilkS")
		)
		(fp_line
			(start 0.598 -0.801)
			(end 0.498 -0.801)
			(stroke
				(width 0.15)
				(type solid)
			)
			(layer "F.SilkS")
		)
		(fp_line
			(start 0.598 -0.7)
			(end 0.598 -0.801)
			(stroke
				(width 0.15)
				(type solid)
			)
			(layer "F.SilkS")
		)
		(fp_line
			(start 0.598 0.7)
			(end 0.598 0.801)
			(stroke
				(width 0.15)
				(type solid)
			)
			(layer "F.SilkS")
		)
		(fp_line
			(start 0.598 0.801)
			(end 0.498 0.801)
			(stroke
				(width 0.15)
				(type solid)
			)
			(layer "F.SilkS")
		)
		(fp_circle
			(center -0.81 -0.77)
			(end -0.81 -0.72)
			(stroke
				(width 0.15)
				(type solid)
			)
			(fill yes)
			(layer "F.SilkS")
		)
		(fp_rect
			(start 0.75 -0.925)
			(end -0.75 0.925)
			(stroke
				(width 0.05)
				(type solid)
			)
			(fill no)
			(layer "F.CrtYd")
		)
		(fp_line
			(start -0.5 -0.729)
			(end -0.5 0.719)
			(stroke
				(width 0.15)
				(type solid)
			)
			(layer "F.Fab")
		)
		(fp_line
			(start -0.5 -0.724)
			(end 0.498 -0.724)
			(stroke
				(width 0.15)
				(type solid)
			)
			(layer "F.Fab")
		)
		(fp_line
			(start -0.5 0.724)
			(end 0.498 0.724)
			(stroke
				(width 0.15)
				(type solid)
			)
			(layer "F.Fab")
		)
		(fp_line
			(start 0.498 -0.719)
			(end 0.498 0.719)
			(stroke
				(width 0.15)
				(type solid)
			)
			(layer "F.Fab")
		)
		(pad "1" smd rect
			(at -0.43 -0.526 270)
			(size 0.17 0.5)
			(layers "F.Cu" "F.Mask" "F.Paste")
			(net 6 "/Debug FTDI/FTDI_3V3")
			(pinfunction "VCCA")
			(pintype "power_in")
		)
		(pad "2" smd rect
			(at -0.43 -0.175 270)
			(size 0.17 0.5)
			(layers "F.Cu" "F.Mask" "F.Paste")
			(net 644 "/Debug FTDI/FTDI_UART1_RX")
			(pinfunction "A1")
			(pintype "bidirectional")
		)
		(pad "3" smd rect
			(at -0.43 0.175 270)
			(size 0.17 0.5)
			(layers "F.Cu" "F.Mask" "F.Paste")
			(net 642 "/Debug FTDI/FTDI_UART1_TX")
			(pinfunction "A2")
			(pintype "bidirectional")
		)
		(pad "4" smd rect
			(at -0.43 0.526 270)
			(size 0.17 0.5)
			(layers "F.Cu" "F.Mask" "F.Paste")
			(net 1 "GND")
			(pinfunction "GND")
			(pintype "power_in")
		)
		(pad "5" smd rect
			(at 0.43 0.526 270)
			(size 0.17 0.5)
			(layers "F.Cu" "F.Mask" "F.Paste")
			(net 6 "/Debug FTDI/FTDI_3V3")
			(pinfunction "OE")
			(pintype "tri_state")
		)
		(pad "6" smd rect
			(at 0.43 0.175 270)
			(size 0.17 0.5)
			(layers "F.Cu" "F.Mask" "F.Paste")
			(net 749 "Net-(U33-B2)")
			(pinfunction "B2")
			(pintype "bidirectional")
		)
		(pad "7" smd rect
			(at 0.43 -0.175 270)
			(size 0.17 0.5)
			(layers "F.Cu" "F.Mask" "F.Paste")
			(net 748 "Net-(U33-B1)")
			(pinfunction "B1")
			(pintype "bidirectional")
		)
		(pad "8" smd rect
			(at 0.43 -0.526 270)
			(size 0.17 0.5)
			(layers "F.Cu" "F.Mask" "F.Paste")
			(net 200 "+3V3")
			(pinfunction "VCCB")
			(pintype "power_in")
		)
	)
	(footprint "antmicro-footprints:TP_SMD_1mm"
		(layer "F.Cu")
		(at 98.100501 145.376 90)
		(property "Reference" "TP7"
			(at 0 -0.731898 90)
			(layer "F.SilkS")
			(effects
				(font
					(size 0.7 0.7)
					(thickness 0.15)
				)
				(justify left bottom)
			)
		)
		(property "Value" "TP_1mm_SMD"
			(at 0 1.4 90)
			(layer "F.Fab")
			(effects
				(font
					(size 0.7 0.7)
					(thickness 0.15)
				)
				(justify left bottom)
			)
		)
		(property "Author" "Antmicro"
			(at 243.476501 47.275499 0)
			(layer "F.Fab")
			(hide yes)
			(effects
				(font
					(size 1 1)
					(thickness 0.15)
				)
			)
		)
		(property "License" "Apache-2.0"
			(at 243.476501 47.275499 0)
			(layer "F.Fab")
			(hide yes)
			(effects
				(font
					(size 1 1)
					(thickness 0.15)
				)
			)
		)
		(property "MPN" ""
			(at 243.476501 47.275499 0)
			(layer "F.Fab")
			(hide yes)
			(effects
				(font
					(size 1 1)
					(thickness 0.15)
				)
			)
		)
		(property "Manufacturer" ""
			(at 243.476501 47.275499 0)
			(layer "F.Fab")
			(hide yes)
			(effects
				(font
					(size 1 1)
					(thickness 0.15)
				)
			)
		)
		(sheetname "/I^{2}C/")
		(sheetfile "i2c.kicad_sch")
		(attr exclude_from_pos_files)
		(pad "1" smd circle
			(at 0 0 90)
			(size 1 1)
			(layers "F.Cu" "F.Mask")
			(net 387 "Net-(U16-EN)")
			(pinfunction "1")
			(pintype "passive")
		)
	)
	(footprint "antmicro-footprints:R_0402_1005Metric"
		(layer "F.Cu")
		(at 202.895501 187.6605 -90)
		(descr "Resistor SMD 0402")
		(tags "resistor SMD 0402")
		(property "Reference" "R164"
			(at 3.8395 -0.354499 270)
			(layer "F.SilkS")
			(effects
				(font
					(size 0.7 0.7)
					(thickness 0.15)
				)
				(justify left bottom)
			)
		)
		(property "Value" "R_0R_0402"
			(at -1.011843 1.772047 270)
			(layer "F.Fab")
			(effects
				(font
					(size 0.7 0.7)
					(thickness 0.15)
				)
				(justify left bottom)
			)
		)
		(property "Datasheet" "https://industrial.panasonic.com/cdbs/www-data/pdf/RDA0000/AOA0000C301.pdf"
			(at 0 0 270)
			(layer "F.Fab")
			(hide yes)
			(effects
				(font
					(size 1.27 1.27)
					(thickness 0.15)
				)
			)
		)
		(property "Author" "Antmicro"
			(at 15.235001 390.556001 0)
			(layer "F.Fab")
			(hide yes)
			(effects
				(font
					(size 1 1)
					(thickness 0.15)
				)
			)
		)
		(property "Current" "1A"
			(at 15.235001 390.556001 0)
			(layer "F.Fab")
			(hide yes)
			(effects
				(font
					(size 1 1)
					(thickness 0.15)
				)
			)
		)
		(property "License" "Apache-2.0"
			(at 15.235001 390.556001 0)
			(layer "F.Fab")
			(hide yes)
			(effects
				(font
					(size 1 1)
					(thickness 0.15)
				)
			)
		)
		(property "MPN" "ERJ2GE0R00X"
			(at 15.235001 390.556001 0)
			(layer "F.Fab")
			(hide yes)
			(effects
				(font
					(size 1 1)
					(thickness 0.15)
				)
			)
		)
		(property "Manufacturer" "Panasonic"
			(at 15.235001 390.556001 0)
			(layer "F.Fab")
			(hide yes)
			(effects
				(font
					(size 1 1)
					(thickness 0.15)
				)
			)
		)
		(property "Tolerance" ""
			(at 15.235001 390.556001 0)
			(layer "F.Fab")
			(hide yes)
			(effects
				(font
					(size 1 1)
					(thickness 0.15)
				)
			)
		)
		(property "Val" "0R"
			(at 15.235001 390.556001 0)
			(layer "F.Fab")
			(hide yes)
			(effects
				(font
					(size 1 1)
					(thickness 0.15)
				)
			)
		)
		(sheetname "/Supply/")
		(sheetfile "supply.kicad_sch")
		(attr smd)
		(fp_rect
			(start -0.93 -0.47)
			(end 0.93 0.47)
			(stroke
				(width 0.05)
				(type solid)
			)
			(fill no)
			(layer "F.CrtYd")
		)
		(fp_rect
			(start -0.5 -0.25)
			(end 0.5 0.25)
			(stroke
				(width 0.15)
				(type solid)
			)
			(fill no)
			(layer "F.Fab")
		)
		(pad "1" smd roundrect
			(at -0.485 0 270)
			(size 0.59 0.64)
			(layers "F.Cu" "F.Mask" "F.Paste")
			(roundrect_rratio 0.25)
			(net 220 "/Supply/FB4")
			(pintype "passive")
		)
		(pad "2" smd roundrect
			(at 0.485 0 270)
			(size 0.59 0.64)
			(layers "F.Cu" "F.Mask" "F.Paste")
			(roundrect_rratio 0.25)
			(net 58 "/Supply/1V7_local")
			(pintype "passive")
		)
	)
	(footprint "antmicro-footprints:Vishay_PowerPAK_1212-8_Single"
		(layer "F.Cu")
		(at 118.67 202.47 -90)
		(descr "PowerPAK 1212-8 Single")
		(tags "Vishay PowerPAK 1212-8 Single")
		(property "Reference" "Q13"
			(at 0 -2 270)
			(layer "F.SilkS")
			(hide yes)
			(effects
				(font
					(size 0.7 0.7)
					(thickness 0.15)
				)
				(justify left bottom)
			)
		)
		(property "Value" "SI7613DN-T1-GE3"
			(at 0 2.7 270)
			(layer "F.Fab")
			(effects
				(font
					(size 0.7 0.7)
					(thickness 0.15)
				)
				(justify left bottom)
			)
		)
		(property "Datasheet" "https://www.vishay.com/docs/64809/si7613dn.pdf"
			(at 0 0 270)
			(layer "F.Fab")
			(hide yes)
			(effects
				(font
					(size 1.27 1.27)
					(thickness 0.15)
				)
			)
		)
		(property "Author" "Antmicro"
			(at -83.8 321.14 0)
			(layer "F.Fab")
			(hide yes)
			(effects
				(font
					(size 1 1)
					(thickness 0.15)
				)
			)
		)
		(property "License" "Apache-2.0"
			(at -83.8 321.14 0)
			(layer "F.Fab")
			(hide yes)
			(effects
				(font
					(size 1 1)
					(thickness 0.15)
				)
			)
		)
		(property "MPN" "SI7613DN-T1-GE3"
			(at -83.8 321.14 0)
			(layer "F.Fab")
			(hide yes)
			(effects
				(font
					(size 1 1)
					(thickness 0.15)
				)
			)
		)
		(property "Manufacturer" "Vishay"
			(at -83.8 321.14 0)
			(layer "F.Fab")
			(hide yes)
			(effects
				(font
					(size 1 1)
					(thickness 0.15)
				)
			)
		)
		(sheetname "/Supply/")
		(sheetfile "supply.kicad_sch")
		(attr smd)
		(fp_line
			(start -1.635 1.634)
			(end 1.634 1.634)
			(stroke
				(width 0.15)
				(type solid)
			)
			(layer "F.SilkS")
		)
		(fp_line
			(start -1.635 1.3)
			(end -1.635 1.634)
			(stroke
				(width 0.15)
				(type solid)
			)
			(layer "F.SilkS")
		)
		(fp_line
			(start 1.634 1.3)
			(end 1.634 1.634)
			(stroke
				(width 0.15)
				(type solid)
			)
			(layer "F.SilkS")
		)
		(fp_line
			(start -1.651 -1.651)
			(end -1.651 -1.317)
			(stroke
				(width 0.15)
				(type solid)
			)
			(layer "F.SilkS")
		)
		(fp_line
			(start -1.651 -1.651)
			(end 1.648 -1.651)
			(stroke
				(width 0.15)
				(type solid)
			)
			(layer "F.SilkS")
		)
		(fp_line
			(start 1.648 -1.651)
			(end 1.648 -1.317)
			(stroke
				(width 0.15)
				(type solid)
			)
			(layer "F.SilkS")
		)
		(fp_circle
			(center -1.9 -1.4)
			(end -1.85 -1.4)
			(stroke
				(width 0.15)
				(type solid)
			)
			(fill yes)
			(layer "F.SilkS")
		)
		(fp_rect
			(start -2 -1.8)
			(end 2 1.798)
			(stroke
				(width 0.05)
				(type solid)
			)
			(fill no)
			(layer "F.CrtYd")
		)
		(fp_line
			(start -1.6425 -1.4175)
			(end -1.4175 -1.6425)
			(stroke
				(width 0.15)
				(type solid)
			)
			(layer "F.Fab")
		)
		(fp_rect
			(start -1.651 -1.651)
			(end 1.648 1.648)
			(stroke
				(width 0.15)
				(type solid)
			)
			(fill no)
			(layer "F.Fab")
		)
		(pad "1" smd rect
			(at -1.436 -0.99 270)
			(size 0.99 0.405)
			(layers "F.Cu" "F.Mask" "F.Paste")
			(net 38 "VDC")
			(pinfunction "S")
			(pintype "passive")
		)
		(pad "2" smd rect
			(at -1.436 -0.332 270)
			(size 0.99 0.405)
			(layers "F.Cu" "F.Mask" "F.Paste")
			(net 38 "VDC")
			(pinfunction "S")
			(pintype "passive")
		)
		(pad "3" smd rect
			(at -1.436 0.33 270)
			(size 0.99 0.405)
			(layers "F.Cu" "F.Mask" "F.Paste")
			(net 38 "VDC")
			(pinfunction "S")
			(pintype "passive")
		)
		(pad "4" smd rect
			(at -1.436 0.988 270)
			(size 0.99 0.405)
			(layers "F.Cu" "F.Mask" "F.Paste")
			(net 366 "Net-(Q13-G)")
			(pinfunction "G")
			(pintype "passive")
		)
		(pad "5" smd custom
			(at 0.557 0 270)
			(size 1.725 2.235)
			(layers "F.Cu" "F.Mask" "F.Paste")
			(net 596 "/Supply/12V_PCIE_fused")
			(pinfunction "D")
			(pintype "passive")
			(zone_connect 2)
			(options
				(clearance outline)
				(anchor rect)
			)
			(primitives
				(gr_poly
					(pts
						(xy 0.8625 0.1275) (xy 0.8625 -0.1275) (xy 1.3725 -0.1275) (xy 1.3725 -0.5325) (xy 0.8625 -0.5325)
						(xy 0.8625 -0.7875) (xy 1.3725 -0.7875) (xy 1.3725 -1.195) (xy 0.6125 -1.195) (xy 0.6125 1.195)
						(xy 1.3725 1.195) (xy 1.3725 0.7875) (xy 0.8625 0.7875) (xy 0.8625 0.5325) (xy 1.3725 0.5325)
						(xy 1.3725 0.1275)
					)
					(width 0)
					(fill yes)
				)
			)
		)
	)
	(footprint "antmicro-footprints:R_0402_1005Metric"
		(layer "F.Cu")
		(at 99.850501 115.026 -90)
		(descr "Resistor SMD 0402")
		(tags "resistor SMD 0402")
		(property "Reference" "R61"
			(at -1.122484 -0.772697 270)
			(layer "F.SilkS")
			(hide yes)
			(effects
				(font
					(size 0.7 0.7)
					(thickness 0.15)
				)
				(justify left bottom)
			)
		)
		(property "Value" "R_330R_0402"
			(at -1.011843 1.772047 270)
			(layer "F.Fab")
			(effects
				(font
					(size 0.7 0.7)
					(thickness 0.15)
				)
				(justify left bottom)
			)
		)
		(property "Datasheet" "https://www.bourns.com/docs/product-datasheets/cr.pdf"
			(at 0 0 270)
			(layer "F.Fab")
			(hide yes)
			(effects
				(font
					(size 1.27 1.27)
					(thickness 0.15)
				)
			)
		)
		(property "Author" "Antmicro"
			(at -15.175499 214.876501 0)
			(layer "F.Fab")
			(hide yes)
			(effects
				(font
					(size 1 1)
					(thickness 0.15)
				)
			)
		)
		(property "License" "Apache-2.0"
			(at -15.175499 214.876501 0)
			(layer "F.Fab")
			(hide yes)
			(effects
				(font
					(size 1 1)
					(thickness 0.15)
				)
			)
		)
		(property "MPN" "CR0402-FX-3300GLF"
			(at -15.175499 214.876501 0)
			(layer "F.Fab")
			(hide yes)
			(effects
				(font
					(size 1 1)
					(thickness 0.15)
				)
			)
		)
		(property "Manufacturer" "Bourns"
			(at -15.175499 214.876501 0)
			(layer "F.Fab")
			(hide yes)
			(effects
				(font
					(size 1 1)
					(thickness 0.15)
				)
			)
		)
		(property "Tolerance" "1%"
			(at -15.175499 214.876501 0)
			(layer "F.Fab")
			(hide yes)
			(effects
				(font
					(size 1 1)
					(thickness 0.15)
				)
			)
		)
		(property "Val" "330R"
			(at -15.175499 214.876501 0)
			(layer "F.Fab")
			(hide yes)
			(effects
				(font
					(size 1 1)
					(thickness 0.15)
				)
			)
		)
		(sheetname "/DDR5 SODIMM/")
		(sheetfile "ddr5-sodimm.kicad_sch")
		(attr smd)
		(fp_rect
			(start -0.93 -0.47)
			(end 0.93 0.47)
			(stroke
				(width 0.05)
				(type solid)
			)
			(fill no)
			(layer "F.CrtYd")
		)
		(fp_rect
			(start -0.5 -0.25)
			(end 0.5 0.25)
			(stroke
				(width 0.15)
				(type solid)
			)
			(fill no)
			(layer "F.Fab")
		)
		(pad "1" smd roundrect
			(at -0.485 0 270)
			(size 0.59 0.64)
			(layers "F.Cu" "F.Mask" "F.Paste")
			(roundrect_rratio 0.25)
			(net 312 "Net-(D9-C_{Y})")
			(pintype "passive")
		)
		(pad "2" smd roundrect
			(at 0.485 0 270)
			(size 0.59 0.64)
			(layers "F.Cu" "F.Mask" "F.Paste")
			(roundrect_rratio 0.25)
			(net 358 "Net-(Q9-D)")
			(pintype "passive")
		)
	)
	(footprint "antmicro-footprints:NetTie-2_SMD_Pad0.127mm"
		(layer "F.Cu")
		(at 200.274 173.974998)
		(descr "Net tie, 2 pin, 0.127mm  SMD pads")
		(tags "net tie")
		(property "Reference" "NT8"
			(at -0.128 -1.345 0)
			(layer "F.SilkS")
			(hide yes)
			(effects
				(font
					(size 0.7 0.7)
					(thickness 0.15)
				)
				(justify left bottom)
			)
		)
		(property "Value" "Net-Tie_P0.127mm"
			(at 0 1.199 0)
			(layer "F.Fab")
			(effects
				(font
					(size 0.7 0.7)
					(thickness 0.15)
				)
				(justify left bottom)
			)
		)
		(property "Author" "Antmicro"
			(at 0 0 0)
			(layer "F.Fab")
			(hide yes)
			(effects
				(font
					(size 1 1)
					(thickness 0.15)
				)
			)
		)
		(property "License" "Apache-2.0"
			(at 0 0 0)
			(layer "F.Fab")
			(hide yes)
			(effects
				(font
					(size 1 1)
					(thickness 0.15)
				)
			)
		)
		(property "MPN" ""
			(at 0 0 0)
			(layer "F.Fab")
			(hide yes)
			(effects
				(font
					(size 1 1)
					(thickness 0.15)
				)
			)
		)
		(property "Manufacturer" ""
			(at 0 0 0)
			(layer "F.Fab")
			(hide yes)
			(effects
				(font
					(size 1 1)
					(thickness 0.15)
				)
			)
		)
		(property ki_fp_filters "Net*Tie*")
		(sheetname "/Supply/")
		(sheetfile "supply.kicad_sch")
		(attr smd exclude_from_pos_files exclude_from_bom)
		(net_tie_pad_groups "1, 2")
		(fp_poly
			(pts
				(xy -0.0635 -0.0635) (xy 0.0625 -0.0635) (xy 0.0625 0.0635) (xy -0.0635 0.0635)
			)
			(stroke
				(width 0)
				(type solid)
			)
			(fill yes)
			(layer "F.Cu")
		)
		(pad "1" smd roundrect
			(at -0.127 0 180)
			(size 0.127 0.127)
			(layers "F.Cu")
			(roundrect_rratio 0.5)
			(chamfer_ratio 0)
			(chamfer top_left bottom_left)
			(net 90 "/Supply/1V2_SEN_+")
			(pinfunction "1")
			(pintype "passive")
		)
		(pad "2" smd roundrect
			(at 0.126 0)
			(size 0.127 0.127)
			(layers "F.Cu")
			(roundrect_rratio 0.5)
			(chamfer_ratio 0)
			(chamfer top_left bottom_left)
			(net 56 "/Supply/1V2_local")
			(pinfunction "2")
			(pintype "passive")
		)
	)
	(footprint "antmicro-footprints:DHVQFN-14-1EP_2.5x3mm"
		(layer "F.Cu")
		(at 104.651 181.685 -90)
		(property "Reference" "U13"
			(at 1.915 4.151 0)
			(layer "F.SilkS")
			(effects
				(font
					(size 0.7 0.7)
					(thickness 0.15)
				)
				(justify left bottom)
			)
		)
		(property "Value" "TXU0304BQAR"
			(at 0 2.898 270)
			(layer "F.Fab")
			(effects
				(font
					(size 0.7 0.7)
					(thickness 0.15)
				)
				(justify left bottom)
			)
		)
		(property "Datasheet" "https://www.ti.com/lit/ds/symlink/txu0304.pdf?ts=1637748643258&ref_url=https%253A%252F%252Fwww.ti.com%252Fproduct%252FTXU0304"
			(at 0 0 270)
			(layer "F.Fab")
			(hide yes)
			(effects
				(font
					(size 1.27 1.27)
					(thickness 0.15)
				)
			)
		)
		(property "Author" "Antmicro"
			(at -77.034 286.336 0)
			(layer "F.Fab")
			(hide yes)
			(effects
				(font
					(size 1 1)
					(thickness 0.15)
				)
			)
		)
		(property "License" "Apache-2.0"
			(at -77.034 286.336 0)
			(layer "F.Fab")
			(hide yes)
			(effects
				(font
					(size 1 1)
					(thickness 0.15)
				)
			)
		)
		(property "MPN" "TXU0304BQAR"
			(at -77.034 286.336 0)
			(layer "F.Fab")
			(hide yes)
			(effects
				(font
					(size 1 1)
					(thickness 0.15)
				)
			)
		)
		(property "Manufacturer" "Texas Instruments"
			(at -77.034 286.336 0)
			(layer "F.Fab")
			(hide yes)
			(effects
				(font
					(size 1 1)
					(thickness 0.15)
				)
			)
		)
		(sheetname "/Debug FTDI/")
		(sheetfile "debug-ftdi.kicad_sch")
		(attr smd)
		(fp_line
			(start -1.351 1.6)
			(end -0.5 1.6)
			(stroke
				(width 0.15)
				(type solid)
			)
			(layer "F.SilkS")
		)
		(fp_line
			(start -1.351 1.6)
			(end -1.351 1.249)
			(stroke
				(width 0.15)
				(type solid)
			)
			(layer "F.SilkS")
		)
		(fp_line
			(start 0.494 1.6)
			(end 1.35 1.6)
			(stroke
				(width 0.15)
				(type solid)
			)
			(layer "F.SilkS")
		)
		(fp_line
			(start 1.35 1.6)
			(end 1.35 1.249)
			(stroke
				(width 0.15)
				(type solid)
			)
			(layer "F.SilkS")
		)
		(fp_line
			(start -1.351 -1.601)
			(end -0.5 -1.601)
			(stroke
				(width 0.15)
				(type solid)
			)
			(layer "F.SilkS")
		)
		(fp_line
			(start -1.35 -1.601)
			(end -1.35 -1.25)
			(stroke
				(width 0.15)
				(type solid)
			)
			(layer "F.SilkS")
		)
		(fp_line
			(start 1.35 -1.601)
			(end 1.35 -1.25)
			(stroke
				(width 0.15)
				(type solid)
			)
			(layer "F.SilkS")
		)
		(fp_line
			(start 1.35 -1.601)
			(end 0.494 -1.601)
			(stroke
				(width 0.15)
				(type solid)
			)
			(layer "F.SilkS")
		)
		(fp_circle
			(center -0.7 -1.85)
			(end -0.653 -1.85)
			(stroke
				(width 0.15)
				(type solid)
			)
			(fill yes)
			(layer "F.SilkS")
		)
		(fp_rect
			(start -1.85 -2)
			(end 1.8 1.95)
			(stroke
				(width 0.05)
				(type solid)
			)
			(fill no)
			(layer "F.CrtYd")
		)
		(fp_line
			(start -1.25 1.499)
			(end -1.25 -1.25)
			(stroke
				(width 0.15)
				(type solid)
			)
			(layer "F.Fab")
		)
		(fp_line
			(start 1.249 1.499)
			(end -1.25 1.499)
			(stroke
				(width 0.15)
				(type solid)
			)
			(layer "F.Fab")
		)
		(fp_line
			(start -1.25 -1.25)
			(end -1 -1.5)
			(stroke
				(width 0.15)
				(type solid)
			)
			(layer "F.Fab")
		)
		(fp_line
			(start -1 -1.5)
			(end 1.249 -1.5)
			(stroke
				(width 0.15)
				(type solid)
			)
			(layer "F.Fab")
		)
		(fp_line
			(start 1.249 -1.5)
			(end 1.249 1.499)
			(stroke
				(width 0.15)
				(type solid)
			)
			(layer "F.Fab")
		)
		(pad "1" smd oval
			(at -0.25 -1.5 270)
			(size 0.3 0.8)
			(layers "F.Cu" "F.Mask" "F.Paste")
			(net 6 "/Debug FTDI/FTDI_3V3")
			(pinfunction "VCCA")
			(pintype "power_in")
		)
		(pad "2" smd oval
			(at -1.25 -1)
			(size 0.3 0.8)
			(layers "F.Cu" "F.Mask" "F.Paste")
			(net 646 "/Debug FTDI/BDBUS0")
			(pinfunction "A1")
			(pintype "input")
		)
		(pad "3" smd oval
			(at -1.25 -0.5)
			(size 0.3 0.8)
			(layers "F.Cu" "F.Mask" "F.Paste")
			(net 1 "GND")
			(pinfunction "A2")
			(pintype "input")
		)
		(pad "4" smd oval
			(at -1.25 0)
			(size 0.3 0.8)
			(layers "F.Cu" "F.Mask" "F.Paste")
			(net 648 "/Debug FTDI/BDBUS1")
			(pinfunction "A3")
			(pintype "input")
		)
		(pad "5" smd oval
			(at -1.25 0.494)
			(size 0.3 0.8)
			(layers "F.Cu" "F.Mask" "F.Paste")
			(net 650 "/Debug FTDI/BDBUS2")
			(pinfunction "A4Y")
			(pintype "output")
		)
		(pad "6" smd oval
			(at -1.25 0.994)
			(size 0.3 0.8)
			(layers "F.Cu" "F.Mask" "F.Paste")
			(net 718 "unconnected-(U13-NC-Pad6)")
			(pinfunction "NC")
			(pintype "no_connect")
		)
		(pad "7" smd oval
			(at -0.25 1.499 270)
			(size 0.3 0.8)
			(layers "F.Cu" "F.Mask" "F.Paste")
			(net 1 "GND")
			(pinfunction "GND")
			(pintype "passive")
		)
		(pad "8" smd oval
			(at 0.244 1.499 270)
			(size 0.3 0.8)
			(layers "F.Cu" "F.Mask" "F.Paste")
			(net 383 "Net-(U13-OE)")
			(pinfunction "OE")
			(pintype "tri_state")
		)
		(pad "9" smd oval
			(at 1.249 0.994)
			(size 0.3 0.8)
			(layers "F.Cu" "F.Mask" "F.Paste")
			(net 719 "unconnected-(U13-NC-Pad9)")
			(pinfunction "NC")
			(pintype "no_connect")
		)
		(pad "10" smd oval
			(at 1.249 0.494)
			(size 0.3 0.8)
			(layers "F.Cu" "F.Mask" "F.Paste")
			(net 43 "/Debug FTDI/FTDI_SDA_IN")
			(pinfunction "B4")
			(pintype "input")
		)
		(pad "11" smd oval
			(at 1.249 0)
			(size 0.3 0.8)
			(layers "F.Cu" "F.Mask" "F.Paste")
			(net 37 "/Debug FTDI/FTDI_SDA_OUT")
			(pinfunction "B3Y")
			(pintype "output")
		)
		(pad "12" smd oval
			(at 1.249 -0.5)
			(size 0.3 0.8)
			(layers "F.Cu" "F.Mask" "F.Paste")
			(net 720 "unconnected-(U13-B2Y-Pad12)")
			(pinfunction "B2Y")
			(pintype "output+no_connect")
		)
		(pad "13" smd oval
			(at 1.249 -1)
			(size 0.3 0.8)
			(layers "F.Cu" "F.Mask" "F.Paste")
			(net 670 "/Debug FTDI/FTDI_SCL")
			(pinfunction "B1Y")
			(pintype "output")
		)
		(pad "14" smd oval
			(at 0.244 -1.5 270)
			(size 0.3 0.8)
			(layers "F.Cu" "F.Mask" "F.Paste")
			(net 41 "+3V3_AON")
			(pinfunction "VCCB")
			(pintype "power_in")
		)
		(pad "15" smd rect
			(at 0 0 270)
			(size 1 1.5)
			(layers "F.Cu" "F.Mask" "F.Paste")
			(net 1 "GND")
			(pinfunction "GND")
			(pintype "power_in")
		)
	)
	(footprint "antmicro-footprints:C_0805_2012Metric"
		(layer "F.Cu")
		(at 205.395501 184.4605 90)
		(descr "Capacitor SMD 0805")
		(tags "capacitor SMD 0805")
		(property "Reference" "C177"
			(at -2.10551 -1.198678 90)
			(layer "F.SilkS")
			(hide yes)
			(effects
				(font
					(size 0.7 0.7)
					(thickness 0.15)
				)
				(justify left bottom)
			)
		)
		(property "Value" "C_22u_25V_0805"
			(at -2.055717 1.963152 90)
			(layer "F.Fab")
			(effects
				(font
					(size 0.7 0.7)
					(thickness 0.15)
				)
				(justify left bottom)
			)
		)
		(property "Datasheet" "https://product.samsungsem.com/mlcc/CL21A226MAYNNN.do"
			(at 0 0 90)
			(layer "F.Fab")
			(hide yes)
			(effects
				(font
					(size 1.27 1.27)
					(thickness 0.15)
				)
			)
		)
		(property "Author" "Antmicro"
			(at 389.856001 -20.935001 0)
			(layer "F.Fab")
			(hide yes)
			(effects
				(font
					(size 1 1)
					(thickness 0.15)
				)
			)
		)
		(property "Dielectric" ""
			(at 389.856001 -20.935001 0)
			(layer "F.Fab")
			(hide yes)
			(effects
				(font
					(size 1 1)
					(thickness 0.15)
				)
			)
		)
		(property "License" "Apache-2.0"
			(at 389.856001 -20.935001 0)
			(layer "F.Fab")
			(hide yes)
			(effects
				(font
					(size 1 1)
					(thickness 0.15)
				)
			)
		)
		(property "MPN" "CL21A226MAYNNNE"
			(at 389.856001 -20.935001 0)
			(layer "F.Fab")
			(hide yes)
			(effects
				(font
					(size 1 1)
					(thickness 0.15)
				)
			)
		)
		(property "Manufacturer" "Samsung Electro-Mechanics"
			(at 389.856001 -20.935001 0)
			(layer "F.Fab")
			(hide yes)
			(effects
				(font
					(size 1 1)
					(thickness 0.15)
				)
			)
		)
		(property "Val" "22u_25V"
			(at 389.856001 -20.935001 0)
			(layer "F.Fab")
			(hide yes)
			(effects
				(font
					(size 1 1)
					(thickness 0.15)
				)
			)
		)
		(property "Voltage" ""
			(at 389.856001 -20.935001 0)
			(layer "F.Fab")
			(hide yes)
			(effects
				(font
					(size 1 1)
					(thickness 0.15)
				)
			)
		)
		(sheetname "/Supply/")
		(sheetfile "supply.kicad_sch")
		(attr smd)
		(fp_line
			(start -0.3 -0.8)
			(end 0.3 -0.8)
			(stroke
				(width 0.15)
				(type solid)
			)
			(layer "F.SilkS")
		)
		(fp_line
			(start -0.3 0.8)
			(end 0.3 0.8)
			(stroke
				(width 0.15)
				(type solid)
			)
			(layer "F.SilkS")
		)
		(fp_rect
			(start -1.9 -0.93)
			(end 1.9 0.93)
			(stroke
				(width 0.05)
				(type solid)
			)
			(fill no)
			(layer "F.CrtYd")
		)
		(fp_rect
			(start -0.95 -0.675)
			(end 0.95 0.675)
			(stroke
				(width 0.15)
				(type solid)
			)
			(fill no)
			(layer "F.Fab")
		)
		(pad "1" smd rect
			(at -1.05 0 90)
			(size 1.2 1.2)
			(layers "F.Cu" "F.Mask" "F.Paste")
			(net 1 "GND")
			(pintype "passive")
		)
		(pad "2" smd rect
			(at 1.05 0 90)
			(size 1.2 1.2)
			(layers "F.Cu" "F.Mask" "F.Paste")
			(net 38 "VDC")
			(pintype "passive")
		)
	)
	(footprint "antmicro-footprints:C_0402_1005Metric"
		(layer "F.Cu")
		(at 181.55 149.65 180)
		(descr "Capacitor SMD 0402")
		(tags "capacitor SMD 0402")
		(property "Reference" "C220"
			(at 0 -0.699 180)
			(layer "F.SilkS")
			(hide yes)
			(effects
				(font
					(size 0.7 0.7)
					(thickness 0.15)
				)
				(justify left bottom)
			)
		)
		(property "Value" "C_100n_0402"
			(at -1.022927 2.155213 180)
			(layer "F.Fab")
			(effects
				(font
					(size 0.7 0.7)
					(thickness 0.15)
				)
				(justify left bottom)
			)
		)
		(property "Datasheet" "https://www.murata.com/products/productdetail?partno=GRM155R61H104KE14%23"
			(at 0 0 180)
			(layer "F.Fab")
			(hide yes)
			(effects
				(font
					(size 1.27 1.27)
					(thickness 0.15)
				)
			)
		)
		(property "Author" "Antmicro"
			(at 363.1 299.3 0)
			(layer "F.Fab")
			(hide yes)
			(effects
				(font
					(size 1 1)
					(thickness 0.15)
				)
			)
		)
		(property "Dielectric" "X5R"
			(at 363.1 299.3 0)
			(layer "F.Fab")
			(hide yes)
			(effects
				(font
					(size 1 1)
					(thickness 0.15)
				)
			)
		)
		(property "License" "Apache-2.0"
			(at 363.1 299.3 0)
			(layer "F.Fab")
			(hide yes)
			(effects
				(font
					(size 1 1)
					(thickness 0.15)
				)
			)
		)
		(property "MPN" "GRM155R61H104KE14D"
			(at 363.1 299.3 0)
			(layer "F.Fab")
			(hide yes)
			(effects
				(font
					(size 1 1)
					(thickness 0.15)
				)
			)
		)
		(property "Manufacturer" "Murata"
			(at 363.1 299.3 0)
			(layer "F.Fab")
			(hide yes)
			(effects
				(font
					(size 1 1)
					(thickness 0.15)
				)
			)
		)
		(property "Val" "100n"
			(at 363.1 299.3 0)
			(layer "F.Fab")
			(hide yes)
			(effects
				(font
					(size 1 1)
					(thickness 0.15)
				)
			)
		)
		(property "Voltage" "50V"
			(at 363.1 299.3 0)
			(layer "F.Fab")
			(hide yes)
			(effects
				(font
					(size 1 1)
					(thickness 0.15)
				)
			)
		)
		(sheetname "/Supply/")
		(sheetfile "supply.kicad_sch")
		(attr smd)
		(fp_rect
			(start -0.9659 -0.481258)
			(end 0.9649 0.458742)
			(stroke
				(width 0.05)
				(type solid)
			)
			(fill no)
			(layer "F.CrtYd")
		)
		(fp_line
			(start 0.499 0.248)
			(end -0.499 0.248)
			(stroke
				(width 0.15)
				(type solid)
			)
			(layer "F.Fab")
		)
		(fp_line
			(start 0.499 -0.25)
			(end 0.499 0.248)
			(stroke
				(width 0.15)
				(type solid)
			)
			(layer "F.Fab")
		)
		(fp_line
			(start -0.499 0.248)
			(end -0.499 -0.25)
			(stroke
				(width 0.15)
				(type solid)
			)
			(layer "F.Fab")
		)
		(fp_line
			(start -0.499 -0.25)
			(end 0.499 -0.25)
			(stroke
				(width 0.15)
				(type solid)
			)
			(layer "F.Fab")
		)
		(pad "1" smd roundrect
			(at -0.484 0 180)
			(size 0.59 0.64)
			(layers "F.Cu" "F.Mask" "F.Paste")
			(roundrect_rratio 0.25)
			(net 1 "GND")
			(pintype "passive")
		)
		(pad "2" smd roundrect
			(at 0.484 0 180)
			(size 0.59 0.64)
			(layers "F.Cu" "F.Mask" "F.Paste")
			(roundrect_rratio 0.25)
			(net 36 "DAC_VREF")
			(pintype "passive")
		)
	)
	(footprint "antmicro-footprints:R_1206_3216Metric"
		(layer "F.Cu")
		(at 188.675 171.7 180)
		(property "Reference" "R145"
			(at 0.025 1.2 180)
			(layer "F.SilkS")
			(effects
				(font
					(size 0.7 0.7)
					(thickness 0.15)
				)
				(justify left bottom)
			)
		)
		(property "Value" "R_0R01_1206"
			(at -2.422356 2.103591 180)
			(layer "F.Fab")
			(effects
				(font
					(size 0.7 0.7)
					(thickness 0.15)
				)
				(justify left bottom)
			)
		)
		(property "Datasheet" "https://www.yageo.com/upload/media/product/productsearch/datasheet/rchip/PYu-RL_Group_521_RoHS_L_2.pdf"
			(at 0 0 180)
			(layer "F.Fab")
			(hide yes)
			(effects
				(font
					(size 1.27 1.27)
					(thickness 0.15)
				)
			)
		)
		(property "Author" "Antmicro"
			(at 377.35 343.4 0)
			(layer "F.Fab")
			(hide yes)
			(effects
				(font
					(size 1 1)
					(thickness 0.15)
				)
			)
		)
		(property "License" "Apache-2.0"
			(at 377.35 343.4 0)
			(layer "F.Fab")
			(hide yes)
			(effects
				(font
					(size 1 1)
					(thickness 0.15)
				)
			)
		)
		(property "MPN" "RL1206FR-7W0R01L"
			(at 377.35 343.4 0)
			(layer "F.Fab")
			(hide yes)
			(effects
				(font
					(size 1 1)
					(thickness 0.15)
				)
			)
		)
		(property "Manufacturer" "YAGEO"
			(at 377.35 343.4 0)
			(layer "F.Fab")
			(hide yes)
			(effects
				(font
					(size 1 1)
					(thickness 0.15)
				)
			)
		)
		(property "Tolerance" "1%"
			(at 377.35 343.4 0)
			(layer "F.Fab")
			(hide yes)
			(effects
				(font
					(size 1 1)
					(thickness 0.15)
				)
			)
		)
		(property "Val" "0R01"
			(at 377.35 343.4 0)
			(layer "F.Fab")
			(hide yes)
			(effects
				(font
					(size 1 1)
					(thickness 0.15)
				)
			)
		)
		(sheetname "/Supply/")
		(sheetfile "supply.kicad_sch")
		(attr smd)
		(fp_line
			(start 0 0.9)
			(end 0.498 0.9)
			(stroke
				(width 0.15)
				(type solid)
			)
			(layer "F.SilkS")
		)
		(fp_line
			(start 0 0.9)
			(end -0.5 0.9)
			(stroke
				(width 0.15)
				(type solid)
			)
			(layer "F.SilkS")
		)
		(fp_line
			(start 0 -0.902)
			(end 0.498 -0.902)
			(stroke
				(width 0.15)
				(type solid)
			)
			(layer "F.SilkS")
		)
		(fp_line
			(start 0 -0.902)
			(end -0.5 -0.902)
			(stroke
				(width 0.15)
				(type solid)
			)
			(layer "F.SilkS")
		)
		(fp_rect
			(start -2.25 -1.05)
			(end 2.25 1.05)
			(stroke
				(width 0.05)
				(type solid)
			)
			(fill no)
			(layer "F.CrtYd")
		)
		(fp_line
			(start 1.6 -0.802)
			(end 1.6 0.8)
			(stroke
				(width 0.15)
				(type solid)
			)
			(layer "F.Fab")
		)
		(fp_line
			(start -1.601 0.8)
			(end 1.6 0.8)
			(stroke
				(width 0.15)
				(type solid)
			)
			(layer "F.Fab")
		)
		(fp_line
			(start -1.601 -0.802)
			(end 1.6 -0.802)
			(stroke
				(width 0.15)
				(type solid)
			)
			(layer "F.Fab")
		)
		(fp_line
			(start -1.601 -0.802)
			(end -1.601 0.8)
			(stroke
				(width 0.15)
				(type solid)
			)
			(layer "F.Fab")
		)
		(pad "1" smd roundrect
			(at -1.5 0 180)
			(size 1.2 1.8)
			(layers "F.Cu" "F.Mask" "F.Paste")
			(roundrect_rratio 0.15)
			(net 52 "/Supply/3V3_local")
			(pintype "passive")
		)
		(pad "2" smd roundrect
			(at 1.499 0 180)
			(size 1.2 1.8)
			(layers "F.Cu" "F.Mask" "F.Paste")
			(roundrect_rratio 0.15)
			(net 200 "+3V3")
			(pintype "passive")
		)
	)
	(footprint "antmicro-footprints:Edge_Conn_Bus_PCIexpress_x4"
		(layer "F.Cu")
		(at 114.525501 210.801)
		(descr "PCIexpress x4")
		(tags "PCIexpress")
		(property "Reference" "J9"
			(at -0.025 -3.175 0)
			(layer "F.SilkS")
			(effects
				(font
					(size 0.7 0.7)
					(thickness 0.15)
				)
				(justify left bottom)
			)
		)
		(property "Value" "Edge_Conn_Bus_PCIe_x4"
			(at -0.8 7.3 0)
			(layer "F.Fab")
			(effects
				(font
					(size 0.7 0.7)
					(thickness 0.15)
				)
				(justify left bottom)
			)
		)
		(property "Author" "Antmicro"
			(at 0 0 0)
			(layer "F.Fab")
			(hide yes)
			(effects
				(font
					(size 1 1)
					(thickness 0.15)
				)
			)
		)
		(property "License" "Apache-2.0"
			(at 0 0 0)
			(layer "F.Fab")
			(hide yes)
			(effects
				(font
					(size 1 1)
					(thickness 0.15)
				)
			)
		)
		(property "MPN" ""
			(at 0 0 0)
			(layer "F.Fab")
			(hide yes)
			(effects
				(font
					(size 1 1)
					(thickness 0.15)
				)
			)
		)
		(property "Manufacturer" ""
			(at 0 0 0)
			(layer "F.Fab")
			(hide yes)
			(effects
				(font
					(size 1 1)
					(thickness 0.15)
				)
			)
		)
		(sheetname "/PCIe connector/")
		(sheetfile "pcie-connector.kicad_sch")
		(attr exclude_from_pos_files exclude_from_bom)
		(fp_poly
			(pts
				(xy -0.85 -2) (xy 33.65 -2) (xy 33.65 3.5) (xy -0.85 3.5)
			)
			(stroke
				(width 0.2)
				(type solid)
			)
			(fill yes)
			(layer "F.Mask")
		)
		(fp_poly
			(pts
				(xy -0.85 -2) (xy 33.65 -2) (xy 33.65 3.5) (xy -0.85 3.5)
			)
			(stroke
				(width 0.2)
				(type solid)
			)
			(fill yes)
			(layer "B.Mask")
		)
		(fp_circle
			(center 0 -2.675)
			(end 0.05 -2.675)
			(stroke
				(width 0.15)
				(type solid)
			)
			(fill yes)
			(layer "F.SilkS")
		)
		(fp_line
			(start -0.65 -4.9)
			(end -0.65 3)
			(stroke
				(width 0.15)
				(type solid)
			)
			(layer "Edge.Cuts")
		)
		(fp_line
			(start -0.65 3)
			(end -0.15 3.5)
			(stroke
				(width 0.15)
				(type solid)
			)
			(layer "Edge.Cuts")
		)
		(fp_line
			(start -0.15 3.5)
			(end 10.05 3.5)
			(stroke
				(width 0.15)
				(type solid)
			)
			(layer "Edge.Cuts")
		)
		(fp_line
			(start 10.55 -3.95)
			(end 10.55 3)
			(stroke
				(width 0.15)
				(type solid)
			)
			(layer "Edge.Cuts")
		)
		(fp_line
			(start 10.55 3)
			(end 10.05 3.5)
			(stroke
				(width 0.15)
				(type solid)
			)
			(layer "Edge.Cuts")
		)
		(fp_line
			(start 12.45 -3.95)
			(end 12.45 3)
			(stroke
				(width 0.15)
				(type solid)
			)
			(layer "Edge.Cuts")
		)
		(fp_line
			(start 12.45 3)
			(end 12.95 3.5)
			(stroke
				(width 0.15)
				(type solid)
			)
			(layer "Edge.Cuts")
		)
		(fp_line
			(start 12.95 3.5)
			(end 33.15 3.5)
			(stroke
				(width 0.15)
				(type solid)
			)
			(layer "Edge.Cuts")
		)
		(fp_line
			(start 33.65 -4.9)
			(end 33.65 3)
			(stroke
				(width 0.15)
				(type solid)
			)
			(layer "Edge.Cuts")
		)
		(fp_line
			(start 33.65 3)
			(end 33.15 3.5)
			(stroke
				(width 0.15)
				(type solid)
			)
			(layer "Edge.Cuts")
		)
		(fp_arc
			(start 10.55 -3.95)
			(mid 11.5 -4.9)
			(end 12.45 -3.95)
			(stroke
				(width 0.15)
				(type solid)
			)
			(layer "Edge.Cuts")
		)
		(pad "A1" connect rect
			(at 0 -0.5)
			(size 0.7 3.2)
			(layers "B.Cu" "B.Mask")
			(net 229 "/PCIe connector/PRSNT#1")
			(pinfunction "~{PRSNT1}")
			(pintype "passive")
		)
		(pad "A2" connect rect
			(at 1 0)
			(size 0.7 4.2)
			(layers "B.Cu" "B.Mask")
			(net 11 "+12V")
			(pinfunction "12V")
			(pintype "power_out")
		)
		(pad "A3" connect rect
			(at 2 0)
			(size 0.7 4.2)
			(layers "B.Cu" "B.Mask")
			(net 11 "+12V")
			(pinfunction "12V")
			(pintype "passive")
		)
		(pad "A4" connect rect
			(at 3 0)
			(size 0.7 4.2)
			(layers "B.Cu" "B.Mask")
			(net 1 "GND")
			(pinfunction "GND")
			(pintype "passive")
		)
		(pad "A5" connect rect
			(at 4 0)
			(size 0.7 4.2)
			(layers "B.Cu" "B.Mask")
			(net 333 "unconnected-(J9-TCK-PadA5)")
			(pinfunction "TCK")
			(pintype "input+no_connect")
		)
		(pad "A6" connect rect
			(at 5 0)
			(size 0.7 4.2)
			(layers "B.Cu" "B.Mask")
			(net 334 "unconnected-(J9-TDI-PadA6)")
			(pinfunction "TDI")
			(pintype "input+no_connect")
		)
		(pad "A7" connect rect
			(at 6 0)
			(size 0.7 4.2)
			(layers "B.Cu" "B.Mask")
			(net 335 "unconnected-(J9-TDO-PadA7)")
			(pinfunction "TDO")
			(pintype "output+no_connect")
		)
		(pad "A8" connect rect
			(at 7 0)
			(size 0.7 4.2)
			(layers "B.Cu" "B.Mask")
			(net 336 "unconnected-(J9-TMS-PadA8)")
			(pinfunction "TMS")
			(pintype "input+no_connect")
		)
		(pad "A9" connect rect
			(at 8 0)
			(size 0.7 4.2)
			(layers "B.Cu" "B.Mask")
			(net 752 "unconnected-(J9-3V3-PadA10)_2")
			(pinfunction "3V3")
			(pintype "passive+no_connect")
		)
		(pad "A10" connect rect
			(at 9 0)
			(size 0.7 4.2)
			(layers "B.Cu" "B.Mask")
			(net 337 "unconnected-(J9-3V3-PadA10)")
			(pinfunction "3V3")
			(pintype "power_out+no_connect")
		)
		(pad "A11" connect rect
			(at 10 0)
			(size 0.7 4.2)
			(layers "B.Cu" "B.Mask")
			(net 135 "PCIE.PWRGD")
			(pinfunction "~{PERST}")
			(pintype "open_collector")
		)
		(pad "A12" connect rect
			(at 13 0)
			(size 0.7 4.2)
			(layers "B.Cu" "B.Mask")
			(net 1 "GND")
			(pinfunction "GND")
			(pintype "passive")
		)
		(pad "A13" connect rect
			(at 14 0)
			(size 0.7 4.2)
			(layers "B.Cu" "B.Mask")
			(net 12 "/FPGA MGT Interface/PCIE.CLK_P")
			(pinfunction "REFCLK_p")
			(pintype "input")
		)
		(pad "A14" connect rect
			(at 15 0)
			(size 0.7 4.2)
			(layers "B.Cu" "B.Mask")
			(net 14 "/FPGA MGT Interface/PCIE.CLK_N")
			(pinfunction "REFCLK_n")
			(pintype "input")
		)
		(pad "A15" connect rect
			(at 16 0)
			(size 0.7 4.2)
			(layers "B.Cu" "B.Mask")
			(net 1 "GND")
			(pinfunction "GND")
			(pintype "passive")
		)
		(pad "A16" connect rect
			(at 17 0)
			(size 0.7 4.2)
			(layers "B.Cu" "B.Mask")
			(net 22 "/FPGA MGT Interface/PCIE.TXD0_P")
			(pinfunction "HSI0_p")
			(pintype "output")
		)
		(pad "A17" connect rect
			(at 18 0)
			(size 0.7 4.2)
			(layers "B.Cu" "B.Mask")
			(net 28 "/FPGA MGT Interface/PCIE.TXD0_N")
			(pinfunction "HSI0_n")
			(pintype "output")
		)
		(pad "A18" connect rect
			(at 19 0)
			(size 0.7 4.2)
			(layers "B.Cu" "B.Mask")
			(net 1 "GND")
			(pinfunction "GND")
			(pintype "passive")
		)
		(pad "A19" connect rect
			(at 20 0)
			(size 0.7 4.2)
			(layers "B.Cu" "B.Mask")
			(net 338 "unconnected-(J9-NC-PadA19)")
			(pinfunction "NC")
			(pintype "no_connect")
		)
		(pad "A20" connect rect
			(at 21 0)
			(size 0.7 4.2)
			(layers "B.Cu" "B.Mask")
			(net 1 "GND")
			(pinfunction "GND")
			(pintype "passive")
		)
		(pad "A21" connect rect
			(at 22 0)
			(size 0.7 4.2)
			(layers "B.Cu" "B.Mask")
			(net 20 "/FPGA MGT Interface/PCIE.TXD1_P")
			(pinfunction "HSI1_p")
			(pintype "output")
		)
		(pad "A22" connect rect
			(at 23 0)
			(size 0.7 4.2)
			(layers "B.Cu" "B.Mask")
			(net 31 "/FPGA MGT Interface/PCIE.TXD1_N")
			(pinfunction "HSI1_n")
			(pintype "output")
		)
		(pad "A23" connect rect
			(at 24 0)
			(size 0.7 4.2)
			(layers "B.Cu" "B.Mask")
			(net 1 "GND")
			(pinfunction "GND")
			(pintype "passive")
		)
		(pad "A24" connect rect
			(at 25 0)
			(size 0.7 4.2)
			(layers "B.Cu" "B.Mask")
			(net 1 "GND")
			(pinfunction "GND")
			(pintype "passive")
		)
		(pad "A25" connect rect
			(at 26 0)
			(size 0.7 4.2)
			(layers "B.Cu" "B.Mask")
			(net 18 "/FPGA MGT Interface/PCIE.TXD2_P")
			(pinfunction "HSI2_p")
			(pintype "output")
		)
		(pad "A26" connect rect
			(at 27 0)
			(size 0.7 4.2)
			(layers "B.Cu" "B.Mask")
			(net 26 "/FPGA MGT Interface/PCIE.TXD2_N")
			(pinfunction "HSI2_n")
			(pintype "output")
		)
		(pad "A27" connect rect
			(at 28 0)
			(size 0.7 4.2)
			(layers "B.Cu" "B.Mask")
			(net 1 "GND")
			(pinfunction "GND")
			(pintype "passive")
		)
		(pad "A28" connect rect
			(at 29 0)
			(size 0.7 4.2)
			(layers "B.Cu" "B.Mask")
			(net 1 "GND")
			(pinfunction "GND")
			(pintype "passive")
		)
		(pad "A29" connect rect
			(at 30 0)
			(size 0.7 4.2)
			(layers "B.Cu" "B.Mask")
			(net 16 "/FPGA MGT Interface/PCIE.TXD3_P")
			(pinfunction "HSI3_p")
			(pintype "output")
		)
		(pad "A30" connect rect
			(at 31 0)
			(size 0.7 4.2)
			(layers "B.Cu" "B.Mask")
			(net 24 "/FPGA MGT Interface/PCIE.TXD3_N")
			(pinfunction "HSI3_n")
			(pintype "output")
		)
		(pad "A31" connect rect
			(at 32 0)
			(size 0.7 4.2)
			(layers "B.Cu" "B.Mask")
			(net 1 "GND")
			(pinfunction "GND")
			(pintype "passive")
		)
		(pad "A32" connect rect
			(at 33 0)
			(size 0.7 4.2)
			(layers "B.Cu" "B.Mask")
			(net 339 "unconnected-(J9-NC-PadA32)")
			(pinfunction "NC")
			(pintype "no_connect")
		)
		(pad "B1" connect rect
			(at 0 0)
			(size 0.7 4.2)
			(layers "F.Cu" "F.Mask")
			(net 11 "+12V")
			(pinfunction "12V")
			(pintype "passive")
		)
		(pad "B2" connect rect
			(at 1 0)
			(size 0.7 4.2)
			(layers "F.Cu" "F.Mask")
			(net 11 "+12V")
			(pinfunction "12V")
			(pintype "passive")
		)
		(pad "B3" connect rect
			(at 2 0)
			(size 0.7 4.2)
			(layers "F.Cu" "F.Mask")
			(net 11 "+12V")
			(pinfunction "12V")
			(pintype "passive")
		)
		(pad "B4" connect rect
			(at 3 0)
			(size 0.7 4.2)
			(layers "F.Cu" "F.Mask")
			(net 1 "GND")
			(pinfunction "GND")
			(pintype "passive")
		)
		(pad "B5" connect rect
			(at 4 0)
			(size 0.7 4.2)
			(layers "F.Cu" "F.Mask")
			(net 340 "unconnected-(J9-SMCLK-PadB5)")
			(pinfunction "SMCLK")
			(pintype "open_collector+no_connect")
		)
		(pad "B6" connect rect
			(at 5 0)
			(size 0.7 4.2)
			(layers "F.Cu" "F.Mask")
			(net 341 "unconnected-(J9-SMDAT-PadB6)")
			(pinfunction "SMDAT")
			(pintype "open_collector+no_connect")
		)
		(pad "B7" connect rect
			(at 6 0)
			(size 0.7 4.2)
			(layers "F.Cu" "F.Mask")
			(net 1 "GND")
			(pinfunction "GND")
			(pintype "passive")
		)
		(pad "B8" connect rect
			(at 7 0)
			(size 0.7 4.2)
			(layers "F.Cu" "F.Mask")
			(net 715 "unconnected-(J9-3V3-PadA10)_1")
			(pinfunction "3V3")
			(pintype "passive+no_connect")
		)
		(pad "B9" connect rect
			(at 8 0)
			(size 0.7 4.2)
			(layers "F.Cu" "F.Mask")
			(net 342 "unconnected-(J9-~{TRST}-PadB9)")
			(pinfunction "~{TRST}")
			(pintype "input+no_connect")
		)
		(pad "B10" connect rect
			(at 9 0)
			(size 0.7 4.2)
			(layers "F.Cu" "F.Mask")
			(net 343 "unconnected-(J9-3V3AUX-PadB10)")
			(pinfunction "3V3AUX")
			(pintype "power_out+no_connect")
		)
		(pad "B11" connect rect
			(at 10 0)
			(size 0.7 4.2)
			(layers "F.Cu" "F.Mask")
			(net 344 "unconnected-(J9-~{WAKE}-PadB11)")
			(pinfunction "~{WAKE}")
			(pintype "open_collector+no_connect")
		)
		(pad "B12" connect rect
			(at 13 0)
			(size 0.7 4.2)
			(layers "F.Cu" "F.Mask")
			(net 345 "unconnected-(J9-~{CLKREQ}-PadB12)")
			(pinfunction "~{CLKREQ}")
			(pintype "open_collector+no_connect")
		)
		(pad "B13" connect rect
			(at 14 0)
			(size 0.7 4.2)
			(layers "F.Cu" "F.Mask")
			(net 1 "GND")
			(pinfunction "GND")
			(pintype "passive")
		)
		(pad "B14" connect rect
			(at 15 0)
			(size 0.7 4.2)
			(layers "F.Cu" "F.Mask")
			(net 604 "/FPGA MGT Interface/PCIE.RXD0_P")
			(pinfunction "HSO0_p")
			(pintype "input")
		)
		(pad "B15" connect rect
			(at 16 0)
			(size 0.7 4.2)
			(layers "F.Cu" "F.Mask")
			(net 605 "/FPGA MGT Interface/PCIE.RXD0_N")
			(pinfunction "HSO0_n")
			(pintype "input")
		)
		(pad "B16" connect rect
			(at 17 0)
			(size 0.7 4.2)
			(layers "F.Cu" "F.Mask")
			(net 1 "GND")
			(pinfunction "GND")
			(pintype "passive")
		)
		(pad "B17" connect rect
			(at 18 -0.5)
			(size 0.7 3.2)
			(layers "F.Cu" "F.Mask")
			(net 230 "/PCIe connector/x1")
			(pinfunction "~{PRSNT2_x1}")
			(pintype "passive")
		)
		(pad "B18" connect rect
			(at 19 0)
			(size 0.7 4.2)
			(layers "F.Cu" "F.Mask")
			(net 1 "GND")
			(pinfunction "GND")
			(pintype "passive")
		)
		(pad "B19" connect rect
			(at 20 0)
			(size 0.7 4.2)
			(layers "F.Cu" "F.Mask")
			(net 606 "/FPGA MGT Interface/PCIE.RXD1_P")
			(pinfunction "HSO1_p")
			(pintype "input")
		)
		(pad "B20" connect rect
			(at 21 0)
			(size 0.7 4.2)
			(layers "F.Cu" "F.Mask")
			(net 607 "/FPGA MGT Interface/PCIE.RXD1_N")
			(pinfunction "HSO1_n")
			(pintype "input")
		)
		(pad "B21" connect rect
			(at 22 0)
			(size 0.7 4.2)
			(layers "F.Cu" "F.Mask")
			(net 1 "GND")
			(pinfunction "GND")
			(pintype "passive")
		)
		(pad "B22" connect rect
			(at 23 0)
			(size 0.7 4.2)
			(layers "F.Cu" "F.Mask")
			(net 1 "GND")
			(pinfunction "GND")
			(pintype "passive")
		)
		(pad "B23" connect rect
			(at 24 0)
			(size 0.7 4.2)
			(layers "F.Cu" "F.Mask")
			(net 608 "/FPGA MGT Interface/PCIE.RXD2_P")
			(pinfunction "HSO2_p")
			(pintype "input")
		)
		(pad "B24" connect rect
			(at 25 0)
			(size 0.7 4.2)
			(layers "F.Cu" "F.Mask")
			(net 609 "/FPGA MGT Interface/PCIE.RXD2_N")
			(pinfunction "HSO2_n")
			(pintype "input")
		)
		(pad "B25" connect rect
			(at 26 0)
			(size 0.7 4.2)
			(layers "F.Cu" "F.Mask")
			(net 1 "GND")
			(pinfunction "GND")
			(pintype "passive")
		)
		(pad "B26" connect rect
			(at 27 0)
			(size 0.7 4.2)
			(layers "F.Cu" "F.Mask")
			(net 1 "GND")
			(pinfunction "GND")
			(pintype "passive")
		)
		(pad "B27" connect rect
			(at 28 0)
			(size 0.7 4.2)
			(layers "F.Cu" "F.Mask")
			(net 610 "/FPGA MGT Interface/PCIE.RXD3_P")
			(pinfunction "HSO3_p")
			(pintype "input")
		)
		(pad "B28" connect rect
			(at 29 0)
			(size 0.7 4.2)
			(layers "F.Cu" "F.Mask")
			(net 611 "/FPGA MGT Interface/PCIE.RXD3_N")
			(pinfunction "HSO3_n")
			(pintype "input")
		)
		(pad "B29" connect rect
			(at 30 0)
			(size 0.7 4.2)
			(layers "F.Cu" "F.Mask")
			(net 1 "GND")
			(pinfunction "GND")
			(pintype "passive")
		)
		(pad "B30" connect rect
			(at 31 0)
			(size 0.7 4.2)
			(layers "F.Cu" "F.Mask")
			(net 346 "unconnected-(J9-~{PWRBRK}-PadB30)")
			(pinfunction "~{PWRBRK}")
			(pintype "open_collector+no_connect")
		)
		(pad "B31" connect rect
			(at 32 -0.5)
			(size 0.7 3.2)
			(layers "F.Cu" "F.Mask")
			(net 231 "/PCIe connector/x4")
			(pinfunction "~{PRSNT2_x4}")
			(pintype "passive")
		)
		(pad "B32" connect rect
			(at 33 0)
			(size 0.7 4.2)
			(layers "F.Cu" "F.Mask")
			(net 1 "GND")
			(pinfunction "GND")
			(pintype "passive")
		)
	)
	(footprint "antmicro-footprints:R_0402_1005Metric"
		(layer "F.Cu")
		(at 99.423 132.981)
		(descr "Resistor SMD 0402")
		(tags "resistor SMD 0402")
		(property "Reference" "R126"
			(at -4.154968 0.309606 0)
			(layer "F.SilkS")
			(effects
				(font
					(size 0.7 0.7)
					(thickness 0.15)
				)
				(justify left bottom)
			)
		)
		(property "Value" "R_0R_0402"
			(at -1.011843 1.772047 0)
			(layer "F.Fab")
			(effects
				(font
					(size 0.7 0.7)
					(thickness 0.15)
				)
				(justify left bottom)
			)
		)
		(property "Datasheet" "https://industrial.panasonic.com/cdbs/www-data/pdf/RDA0000/AOA0000C301.pdf"
			(at 0 0 0)
			(layer "F.Fab")
			(hide yes)
			(effects
				(font
					(size 1.27 1.27)
					(thickness 0.15)
				)
			)
		)
		(property "Author" "Antmicro"
			(at 0 0 0)
			(layer "F.Fab")
			(hide yes)
			(effects
				(font
					(size 1 1)
					(thickness 0.15)
				)
			)
		)
		(property "Current" "1A"
			(at 0 0 0)
			(layer "F.Fab")
			(hide yes)
			(effects
				(font
					(size 1 1)
					(thickness 0.15)
				)
			)
		)
		(property "License" "Apache-2.0"
			(at 0 0 0)
			(layer "F.Fab")
			(hide yes)
			(effects
				(font
					(size 1 1)
					(thickness 0.15)
				)
			)
		)
		(property "MPN" "ERJ2GE0R00X"
			(at 0 0 0)
			(layer "F.Fab")
			(hide yes)
			(effects
				(font
					(size 1 1)
					(thickness 0.15)
				)
			)
		)
		(property "Manufacturer" "Panasonic"
			(at 0 0 0)
			(layer "F.Fab")
			(hide yes)
			(effects
				(font
					(size 1 1)
					(thickness 0.15)
				)
			)
		)
		(property "Tolerance" ""
			(at 0 0 0)
			(layer "F.Fab")
			(hide yes)
			(effects
				(font
					(size 1 1)
					(thickness 0.15)
				)
			)
		)
		(property "Val" "0R"
			(at 0 0 0)
			(layer "F.Fab")
			(hide yes)
			(effects
				(font
					(size 1 1)
					(thickness 0.15)
				)
			)
		)
		(sheetname "/I^{2}C/")
		(sheetfile "i2c.kicad_sch")
		(attr exclude_from_pos_files exclude_from_bom dnp)
		(fp_rect
			(start -0.93 -0.47)
			(end 0.93 0.47)
			(stroke
				(width 0.05)
				(type solid)
			)
			(fill no)
			(layer "F.CrtYd")
		)
		(fp_rect
			(start -0.5 -0.25)
			(end 0.5 0.25)
			(stroke
				(width 0.15)
				(type solid)
			)
			(fill no)
			(layer "F.Fab")
		)
		(pad "1" smd roundrect
			(at -0.485 0)
			(size 0.59 0.64)
			(layers "F.Cu" "F.Mask" "F.Paste")
			(roundrect_rratio 0.25)
			(net 227 "+1V0")
			(pintype "passive")
		)
		(pad "2" smd roundrect
			(at 0.485 0)
			(size 0.59 0.64)
			(layers "F.Cu" "F.Mask" "F.Paste")
			(roundrect_rratio 0.25)
			(net 267 "VDDSPD")
			(pintype "passive")
		)
	)
	(footprint "antmicro-footprints:Vishay_PowerPAK_1212-8_Single"
		(layer "F.Cu")
		(at 187.870501 133.123 90)
		(descr "PowerPAK 1212-8 Single")
		(tags "Vishay PowerPAK 1212-8 Single")
		(property "Reference" "Q12"
			(at 0 2.883499 90)
			(layer "F.SilkS")
			(effects
				(font
					(size 0.7 0.7)
					(thickness 0.15)
				)
				(justify left bottom)
			)
		)
		(property "Value" "SI7613DN-T1-GE3"
			(at 0 2.7 90)
			(layer "F.Fab")
			(effects
				(font
					(size 0.7 0.7)
					(thickness 0.15)
				)
				(justify left bottom)
			)
		)
		(property "Datasheet" "https://www.vishay.com/docs/64809/si7613dn.pdf"
			(at 0 0 90)
			(layer "F.Fab")
			(hide yes)
			(effects
				(font
					(size 1.27 1.27)
					(thickness 0.15)
				)
			)
		)
		(property "Author" "Antmicro"
			(at 320.993501 -54.747501 0)
			(layer "F.Fab")
			(hide yes)
			(effects
				(font
					(size 1 1)
					(thickness 0.15)
				)
			)
		)
		(property "License" "Apache-2.0"
			(at 320.993501 -54.747501 0)
			(layer "F.Fab")
			(hide yes)
			(effects
				(font
					(size 1 1)
					(thickness 0.15)
				)
			)
		)
		(property "MPN" "SI7613DN-T1-GE3"
			(at 320.993501 -54.747501 0)
			(layer "F.Fab")
			(hide yes)
			(effects
				(font
					(size 1 1)
					(thickness 0.15)
				)
			)
		)
		(property "Manufacturer" "Vishay"
			(at 320.993501 -54.747501 0)
			(layer "F.Fab")
			(hide yes)
			(effects
				(font
					(size 1 1)
					(thickness 0.15)
				)
			)
		)
		(sheetname "/Supply/")
		(sheetfile "supply.kicad_sch")
		(attr smd)
		(fp_line
			(start 1.648 -1.651)
			(end 1.648 -1.317)
			(stroke
				(width 0.15)
				(type solid)
			)
			(layer "F.SilkS")
		)
		(fp_line
			(start -1.651 -1.651)
			(end 1.648 -1.651)
			(stroke
				(width 0.15)
				(type solid)
			)
			(layer "F.SilkS")
		)
		(fp_line
			(start -1.651 -1.651)
			(end -1.651 -1.317)
			(stroke
				(width 0.15)
				(type solid)
			)
			(layer "F.SilkS")
		)
		(fp_line
			(start 1.634 1.3)
			(end 1.634 1.634)
			(stroke
				(width 0.15)
				(type solid)
			)
			(layer "F.SilkS")
		)
		(fp_line
			(start -1.635 1.3)
			(end -1.635 1.634)
			(stroke
				(width 0.15)
				(type solid)
			)
			(layer "F.SilkS")
		)
		(fp_line
			(start -1.635 1.634)
			(end 1.634 1.634)
			(stroke
				(width 0.15)
				(type solid)
			)
			(layer "F.SilkS")
		)
		(fp_circle
			(center -1.9 -1.4)
			(end -1.85 -1.4)
			(stroke
				(width 0.15)
				(type solid)
			)
			(fill yes)
			(layer "F.SilkS")
		)
		(fp_rect
			(start -2 -1.8)
			(end 2 1.798)
			(stroke
				(width 0.05)
				(type solid)
			)
			(fill no)
			(layer "F.CrtYd")
		)
		(fp_line
			(start -1.6425 -1.4175)
			(end -1.4175 -1.6425)
			(stroke
				(width 0.15)
				(type solid)
			)
			(layer "F.Fab")
		)
		(fp_rect
			(start -1.651 -1.651)
			(end 1.648 1.648)
			(stroke
				(width 0.15)
				(type solid)
			)
			(fill no)
			(layer "F.Fab")
		)
		(pad "1" smd rect
			(at -1.436 -0.99 90)
			(size 0.99 0.405)
			(layers "F.Cu" "F.Mask" "F.Paste")
			(net 38 "VDC")
			(pinfunction "S")
			(pintype "passive")
		)
		(pad "2" smd rect
			(at -1.436 -0.332 90)
			(size 0.99 0.405)
			(layers "F.Cu" "F.Mask" "F.Paste")
			(net 38 "VDC")
			(pinfunction "S")
			(pintype "passive")
		)
		(pad "3" smd rect
			(at -1.436 0.33 90)
			(size 0.99 0.405)
			(layers "F.Cu" "F.Mask" "F.Paste")
			(net 38 "VDC")
			(pinfunction "S")
			(pintype "passive")
		)
		(pad "4" smd rect
			(at -1.436 0.988 90)
			(size 0.99 0.405)
			(layers "F.Cu" "F.Mask" "F.Paste")
			(net 365 "Net-(Q12-G)")
			(pinfunction "G")
			(pintype "passive")
		)
		(pad "5" smd custom
			(at 0.557 0 90)
			(size 1.725 2.235)
			(layers "F.Cu" "F.Mask" "F.Paste")
			(net 595 "/Supply/12V_aux_fused")
			(pinfunction "D")
			(pintype "passive")
			(zone_connect 2)
			(options
				(clearance outline)
				(anchor rect)
			)
			(primitives
				(gr_poly
					(pts
						(xy 0.8625 0.1275) (xy 0.8625 -0.1275) (xy 1.3725 -0.1275) (xy 1.3725 -0.5325) (xy 0.8625 -0.5325)
						(xy 0.8625 -0.7875) (xy 1.3725 -0.7875) (xy 1.3725 -1.195) (xy 0.6125 -1.195) (xy 0.6125 1.195)
						(xy 1.3725 1.195) (xy 1.3725 0.7875) (xy 0.8625 0.7875) (xy 0.8625 0.5325) (xy 1.3725 0.5325)
						(xy 1.3725 0.1275)
					)
					(width 0)
					(fill yes)
				)
			)
		)
	)
	(footprint "antmicro-footprints:SC70-3"
		(layer "F.Cu")
		(at 94.450501 122.926 90)
		(property "Reference" "Q8"
			(at 0 -1.6 90)
			(layer "F.SilkS")
			(hide yes)
			(effects
				(font
					(size 0.7 0.7)
					(thickness 0.15)
				)
				(justify left bottom)
			)
		)
		(property "Value" "BSS138PW,115"
			(at 0 2.3 90)
			(layer "F.Fab")
			(effects
				(font
					(size 0.7 0.7)
					(thickness 0.15)
				)
				(justify left bottom)
			)
		)
		(property "Datasheet" "https://assets.nexperia.com/documents/data-sheet/BSS138PW.pdf"
			(at 0 0 90)
			(layer "F.Fab")
			(hide yes)
			(effects
				(font
					(size 1.27 1.27)
					(thickness 0.15)
				)
			)
		)
		(property "Description" "Power MOSFET, N Channel, 60 V, 320 mA, 0.9 ohm, SOT-323, Surface Mount"
			(at 0 0 90)
			(layer "F.Fab")
			(hide yes)
			(effects
				(font
					(size 1.27 1.27)
					(thickness 0.15)
				)
			)
		)
		(property "Author" "Antmicro"
			(at 217.376501 28.475499 0)
			(layer "F.Fab")
			(hide yes)
			(effects
				(font
					(size 1 1)
					(thickness 0.15)
				)
			)
		)
		(property "License" "Apache-2.0"
			(at 217.376501 28.475499 0)
			(layer "F.Fab")
			(hide yes)
			(effects
				(font
					(size 1 1)
					(thickness 0.15)
				)
			)
		)
		(property "MPN" "BSS138PW,115"
			(at 217.376501 28.475499 0)
			(layer "F.Fab")
			(hide yes)
			(effects
				(font
					(size 1 1)
					(thickness 0.15)
				)
			)
		)
		(property "Manufacturer" "Nexperia"
			(at 217.376501 28.475499 0)
			(layer "F.Fab")
			(hide yes)
			(effects
				(font
					(size 1 1)
					(thickness 0.15)
				)
			)
		)
		(sheetname "/FPGA bank 14/")
		(sheetfile "fpga-bank-14.kicad_sch")
		(attr smd)
		(fp_line
			(start -0.3 -1)
			(end 0.627 -0.999)
			(stroke
				(width 0.15)
				(type solid)
			)
			(layer "F.SilkS")
		)
		(fp_line
			(start 0.627 -0.6)
			(end 0.627 -0.999)
			(stroke
				(width 0.15)
				(type solid)
			)
			(layer "F.SilkS")
		)
		(fp_line
			(start 0.627 0.6)
			(end 0.627 1.001)
			(stroke
				(width 0.15)
				(type solid)
			)
			(layer "F.SilkS")
		)
		(fp_line
			(start -0.3 1)
			(end 0.627 1.001)
			(stroke
				(width 0.15)
				(type solid)
			)
			(layer "F.SilkS")
		)
		(fp_line
			(start 0.9 -1.3)
			(end 0.9 -0.4)
			(stroke
				(width 0.05)
				(type solid)
			)
			(layer "F.CrtYd")
		)
		(fp_line
			(start -0.9 -1.3)
			(end 0.9 -1.3)
			(stroke
				(width 0.05)
				(type solid)
			)
			(layer "F.CrtYd")
		)
		(fp_line
			(start -0.9 -1.3)
			(end -0.9 -1)
			(stroke
				(width 0.05)
				(type solid)
			)
			(layer "F.CrtYd")
		)
		(fp_line
			(start -0.9 -1)
			(end -1.4 -1)
			(stroke
				(width 0.05)
				(type solid)
			)
			(layer "F.CrtYd")
		)
		(fp_line
			(start 1.4 -0.4)
			(end 1.4 0.4)
			(stroke
				(width 0.05)
				(type solid)
			)
			(layer "F.CrtYd")
		)
		(fp_line
			(start 0.9 -0.4)
			(end 1.4 -0.4)
			(stroke
				(width 0.05)
				(type solid)
			)
			(layer "F.CrtYd")
		)
		(fp_line
			(start 1.4 0.4)
			(end 0.9 0.4)
			(stroke
				(width 0.05)
				(type solid)
			)
			(layer "F.CrtYd")
		)
		(fp_line
			(start 0.9 0.4)
			(end 0.9 1.3)
			(stroke
				(width 0.05)
				(type solid)
			)
			(layer "F.CrtYd")
		)
		(fp_line
			(start -0.9 1)
			(end -1.4 1)
			(stroke
				(width 0.05)
				(type solid)
			)
			(layer "F.CrtYd")
		)
		(fp_line
			(start -1.4 1)
			(end -1.4 -1)
			(stroke
				(width 0.05)
				(type solid)
			)
			(layer "F.CrtYd")
		)
		(fp_line
			(start 0.9 1.3)
			(end -0.9 1.3)
			(stroke
				(width 0.05)
				(type solid)
			)
			(layer "F.CrtYd")
		)
		(fp_line
			(start -0.9 1.3)
			(end -0.9 1)
			(stroke
				(width 0.05)
				(type solid)
			)
			(layer "F.CrtYd")
		)
		(fp_rect
			(start -0.623 -0.999)
			(end 0.627 1.001)
			(stroke
				(width 0.15)
				(type solid)
			)
			(fill no)
			(layer "F.Fab")
		)
		(pad "1" smd rect
			(at -1.051 -0.65 180)
			(size 0.6 0.6)
			(layers "F.Cu" "F.Mask" "F.Paste")
			(net 622 "/FPGA bank 14/USR_LED5")
			(pinfunction "G")
			(pintype "input")
		)
		(pad "2" smd rect
			(at -1.051 0.65 180)
			(size 0.6 0.6)
			(layers "F.Cu" "F.Mask" "F.Paste")
			(net 1 "GND")
			(pinfunction "S")
			(pintype "passive")
		)
		(pad "3" smd rect
			(at 1.05 0 180)
			(size 0.6 0.6)
			(layers "F.Cu" "F.Mask" "F.Paste")
			(net 357 "Net-(Q8-D)")
			(pinfunction "D")
			(pintype "passive")
		)
	)
	(footprint "antmicro-footprints:R_0402_1005Metric"
		(layer "F.Cu")
		(at 191.775 195.335 90)
		(descr "Resistor SMD 0402")
		(tags "resistor SMD 0402")
		(property "Reference" "R180"
			(at -1.122484 -0.772697 90)
			(layer "F.SilkS")
			(hide yes)
			(effects
				(font
					(size 0.7 0.7)
					(thickness 0.15)
				)
				(justify left bottom)
			)
		)
		(property "Value" "R_4k7_0402"
			(at -1.011843 1.772047 90)
			(layer "F.Fab")
			(effects
				(font
					(size 0.7 0.7)
					(thickness 0.15)
				)
				(justify left bottom)
			)
		)
		(property "Datasheet" "https://www.bourns.com/docs/product-datasheets/cr.pdf"
			(at 0 0 90)
			(layer "F.Fab")
			(hide yes)
			(effects
				(font
					(size 1.27 1.27)
					(thickness 0.15)
				)
			)
		)
		(property "Author" "Antmicro"
			(at 387.11 3.56 0)
			(layer "F.Fab")
			(hide yes)
			(effects
				(font
					(size 1 1)
					(thickness 0.15)
				)
			)
		)
		(property "License" "Apache-2.0"
			(at 387.11 3.56 0)
			(layer "F.Fab")
			(hide yes)
			(effects
				(font
					(size 1 1)
					(thickness 0.15)
				)
			)
		)
		(property "MPN" "CR0402-FX-4701GLF"
			(at 387.11 3.56 0)
			(layer "F.Fab")
			(hide yes)
			(effects
				(font
					(size 1 1)
					(thickness 0.15)
				)
			)
		)
		(property "Manufacturer" "Bourns"
			(at 387.11 3.56 0)
			(layer "F.Fab")
			(hide yes)
			(effects
				(font
					(size 1 1)
					(thickness 0.15)
				)
			)
		)
		(property "Tolerance" "1%"
			(at 387.11 3.56 0)
			(layer "F.Fab")
			(hide yes)
			(effects
				(font
					(size 1 1)
					(thickness 0.15)
				)
			)
		)
		(property "Val" "4k7"
			(at 387.11 3.56 0)
			(layer "F.Fab")
			(hide yes)
			(effects
				(font
					(size 1 1)
					(thickness 0.15)
				)
			)
		)
		(sheetname "/Supply/")
		(sheetfile "supply.kicad_sch")
		(attr smd)
		(fp_rect
			(start -0.93 -0.47)
			(end 0.93 0.47)
			(stroke
				(width 0.05)
				(type solid)
			)
			(fill no)
			(layer "F.CrtYd")
		)
		(fp_rect
			(start -0.5 -0.25)
			(end 0.5 0.25)
			(stroke
				(width 0.15)
				(type solid)
			)
			(fill no)
			(layer "F.Fab")
		)
		(pad "1" smd roundrect
			(at -0.485 0 90)
			(size 0.59 0.64)
			(layers "F.Cu" "F.Mask" "F.Paste")
			(roundrect_rratio 0.25)
			(net 1 "GND")
			(pintype "passive")
		)
		(pad "2" smd roundrect
			(at 0.485 0 90)
			(size 0.59 0.64)
			(layers "F.Cu" "F.Mask" "F.Paste")
			(roundrect_rratio 0.25)
			(net 224 "/Supply/MGTAVTT_ILIM")
			(pintype "passive")
		)
	)
	(footprint "antmicro-footprints:LED_0603_1608Metric_G"
		(layer "F.Cu")
		(at 83.650501 116.426 -90)
		(descr "LED SMD 0603 Green")
		(tags "LED SMD 0603 Green")
		(property "Reference" "D4"
			(at -0.001 -0.901 270)
			(layer "F.SilkS")
			(hide yes)
			(effects
				(font
					(size 0.7 0.7)
					(thickness 0.15)
				)
				(justify left bottom)
			)
		)
		(property "Value" "LED_G_0603_KP-1608CGCK"
			(at -0.001 1.599 270)
			(layer "F.Fab")
			(effects
				(font
					(size 0.7 0.7)
					(thickness 0.15)
				)
				(justify left bottom)
			)
		)
		(property "Datasheet" "http://www.farnell.com/datasheets/2045956.pdf"
			(at 0 0 270)
			(layer "F.Fab")
			(hide yes)
			(effects
				(font
					(size 1.27 1.27)
					(thickness 0.15)
				)
			)
		)
		(property "Author" "Antmicro"
			(at -32.775499 200.076501 0)
			(layer "F.Fab")
			(hide yes)
			(effects
				(font
					(size 1 1)
					(thickness 0.15)
				)
			)
		)
		(property "License" "Apache-2.0"
			(at -32.775499 200.076501 0)
			(layer "F.Fab")
			(hide yes)
			(effects
				(font
					(size 1 1)
					(thickness 0.15)
				)
			)
		)
		(property "MPN" "KP-1608CGCK"
			(at -32.775499 200.076501 0)
			(layer "F.Fab")
			(hide yes)
			(effects
				(font
					(size 1 1)
					(thickness 0.15)
				)
			)
		)
		(property "Manufacturer" "Kingbright"
			(at -32.775499 200.076501 0)
			(layer "F.Fab")
			(hide yes)
			(effects
				(font
					(size 1 1)
					(thickness 0.15)
				)
			)
		)
		(sheetname "/FPGA bank 14/")
		(sheetfile "fpga-bank-14.kicad_sch")
		(attr smd)
		(fp_line
			(start -0.271 0.348)
			(end 0.269 0.348)
			(stroke
				(width 0.15)
				(type solid)
			)
			(layer "F.SilkS")
		)
		(fp_line
			(start 1.249 0.319)
			(end 1.249 -0.321)
			(stroke
				(width 0.15)
				(type solid)
			)
			(layer "F.SilkS")
		)
		(fp_line
			(start -0.107 -0.001)
			(end -0.291 -0.001)
			(stroke
				(width 0.1)
				(type solid)
			)
			(layer "F.SilkS")
		)
		(fp_line
			(start 0.092 -0.001)
			(end -0.107 0.198)
			(stroke
				(width 0.1)
				(type solid)
			)
			(layer "F.SilkS")
		)
		(fp_line
			(start 0.092 -0.001)
			(end 0.292 -0.001)
			(stroke
				(width 0.1)
				(type solid)
			)
			(layer "F.SilkS")
		)
		(fp_line
			(start -0.107 -0.201)
			(end -0.107 0.198)
			(stroke
				(width 0.1)
				(type solid)
			)
			(layer "F.SilkS")
		)
		(fp_line
			(start -0.107 -0.201)
			(end 0.092 -0.001)
			(stroke
				(width 0.1)
				(type solid)
			)
			(layer "F.SilkS")
		)
		(fp_line
			(start 0.092 -0.201)
			(end 0.092 0.198)
			(stroke
				(width 0.1)
				(type solid)
			)
			(layer "F.SilkS")
		)
		(fp_line
			(start -0.271 -0.349)
			(end 0.269 -0.349)
			(stroke
				(width 0.15)
				(type solid)
			)
			(layer "F.SilkS")
		)
		(fp_rect
			(start -1.2192 -0.6096)
			(end 1.27 0.6016)
			(stroke
				(width 0.05)
				(type solid)
			)
			(fill no)
			(layer "F.CrtYd")
		)
		(fp_line
			(start -0.202 0.201)
			(end 0.1 -0.001)
			(stroke
				(width 0.15)
				(type solid)
			)
			(layer "F.Fab")
		)
		(fp_line
			(start 0.198 0.201)
			(end 0.198 -0.101)
			(stroke
				(width 0.15)
				(type solid)
			)
			(layer "F.Fab")
		)
		(fp_line
			(start -0.849 0.025)
			(end -0.442 0.381)
			(stroke
				(width 0.15)
				(type solid)
			)
			(layer "F.Fab")
		)
		(fp_line
			(start -0.6 -0.001)
			(end -0.202 -0.001)
			(stroke
				(width 0.15)
				(type solid)
			)
			(layer "F.Fab")
		)
		(fp_line
			(start -0.202 -0.001)
			(end -0.202 0.201)
			(stroke
				(width 0.15)
				(type solid)
			)
			(layer "F.Fab")
		)
		(fp_line
			(start 0.1 -0.001)
			(end -0.202 -0.201)
			(stroke
				(width 0.15)
				(type solid)
			)
			(layer "F.Fab")
		)
		(fp_line
			(start 0.198 -0.001)
			(end 0.596 -0.001)
			(stroke
				(width 0.15)
				(type solid)
			)
			(layer "F.Fab")
		)
		(fp_line
			(start -0.202 -0.201)
			(end -0.202 -0.001)
			(stroke
				(width 0.15)
				(type solid)
			)
			(layer "F.Fab")
		)
		(fp_line
			(start 0.198 -0.201)
			(end 0.198 -0.101)
			(stroke
				(width 0.15)
				(type solid)
			)
			(layer "F.Fab")
		)
		(fp_rect
			(start -0.849 -0.401)
			(end 0.849 0.401)
			(stroke
				(width 0.15)
				(type solid)
			)
			(fill no)
			(layer "F.Fab")
		)
		(pad "1" smd rect
			(at -0.751 -0.001 90)
			(size 0.8 0.8)
			(layers "F.Cu" "F.Mask" "F.Paste")
			(net 200 "+3V3")
			(pinfunction "1")
			(pintype "passive")
		)
		(pad "2" smd rect
			(at 0.749 -0.001 90)
			(size 0.8 0.8)
			(layers "F.Cu" "F.Mask" "F.Paste")
			(net 307 "Net-(D4-Pad2)")
			(pinfunction "2")
			(pintype "passive")
		)
	)
	(footprint "antmicro-footprints:R_0402_1005Metric"
		(layer "F.Cu")
		(at 91.750501 119.926 -90)
		(descr "Resistor SMD 0402")
		(tags "resistor SMD 0402")
		(property "Reference" "R45"
			(at -1.122484 -0.772697 270)
			(layer "F.SilkS")
			(hide yes)
			(effects
				(font
					(size 0.7 0.7)
					(thickness 0.15)
				)
				(justify left bottom)
			)
		)
		(property "Value" "R_330R_0402"
			(at -1.011843 1.772047 270)
			(layer "F.Fab")
			(effects
				(font
					(size 0.7 0.7)
					(thickness 0.15)
				)
				(justify left bottom)
			)
		)
		(property "Datasheet" "https://www.bourns.com/docs/product-datasheets/cr.pdf"
			(at 0 0 270)
			(layer "F.Fab")
			(hide yes)
			(effects
				(font
					(size 1.27 1.27)
					(thickness 0.15)
				)
			)
		)
		(property "Author" "Antmicro"
			(at -28.175499 211.676501 0)
			(layer "F.Fab")
			(hide yes)
			(effects
				(font
					(size 1 1)
					(thickness 0.15)
				)
			)
		)
		(property "License" "Apache-2.0"
			(at -28.175499 211.676501 0)
			(layer "F.Fab")
			(hide yes)
			(effects
				(font
					(size 1 1)
					(thickness 0.15)
				)
			)
		)
		(property "MPN" "CR0402-FX-3300GLF"
			(at -28.175499 211.676501 0)
			(layer "F.Fab")
			(hide yes)
			(effects
				(font
					(size 1 1)
					(thickness 0.15)
				)
			)
		)
		(property "Manufacturer" "Bourns"
			(at -28.175499 211.676501 0)
			(layer "F.Fab")
			(hide yes)
			(effects
				(font
					(size 1 1)
					(thickness 0.15)
				)
			)
		)
		(property "Tolerance" "1%"
			(at -28.175499 211.676501 0)
			(layer "F.Fab")
			(hide yes)
			(effects
				(font
					(size 1 1)
					(thickness 0.15)
				)
			)
		)
		(property "Val" "330R"
			(at -28.175499 211.676501 0)
			(layer "F.Fab")
			(hide yes)
			(effects
				(font
					(size 1 1)
					(thickness 0.15)
				)
			)
		)
		(sheetname "/FPGA bank 14/")
		(sheetfile "fpga-bank-14.kicad_sch")
		(attr smd)
		(fp_rect
			(start -0.93 -0.47)
			(end 0.93 0.47)
			(stroke
				(width 0.05)
				(type solid)
			)
			(fill no)
			(layer "F.CrtYd")
		)
		(fp_rect
			(start -0.5 -0.25)
			(end 0.5 0.25)
			(stroke
				(width 0.15)
				(type solid)
			)
			(fill no)
			(layer "F.Fab")
		)
		(pad "1" smd roundrect
			(at -0.485 0 270)
			(size 0.59 0.64)
			(layers "F.Cu" "F.Mask" "F.Paste")
			(roundrect_rratio 0.25)
			(net 310 "Net-(D7-Pad2)")
			(pintype "passive")
		)
		(pad "2" smd roundrect
			(at 0.485 0 270)
			(size 0.59 0.64)
			(layers "F.Cu" "F.Mask" "F.Paste")
			(roundrect_rratio 0.25)
			(net 356 "Net-(Q7-D)")
			(pintype "passive")
		)
	)
	(footprint "antmicro-footprints:C_0402_1005Metric"
		(layer "F.Cu")
		(at 96.55 182.7 90)
		(descr "Capacitor SMD 0402")
		(tags "capacitor SMD 0402")
		(property "Reference" "C124"
			(at 0 -0.699 90)
			(layer "F.SilkS")
			(hide yes)
			(effects
				(font
					(size 0.7 0.7)
					(thickness 0.15)
				)
				(justify left bottom)
			)
		)
		(property "Value" "C_100n_0402"
			(at -1.022927 2.155213 90)
			(layer "F.Fab")
			(effects
				(font
					(size 0.7 0.7)
					(thickness 0.15)
				)
				(justify left bottom)
			)
		)
		(property "Datasheet" "https://www.murata.com/products/productdetail?partno=GRM155R61H104KE14%23"
			(at 0 0 90)
			(layer "F.Fab")
			(hide yes)
			(effects
				(font
					(size 1.27 1.27)
					(thickness 0.15)
				)
			)
		)
		(property "Author" "Antmicro"
			(at 279.25 86.15 0)
			(layer "F.Fab")
			(hide yes)
			(effects
				(font
					(size 1 1)
					(thickness 0.15)
				)
			)
		)
		(property "Dielectric" "X5R"
			(at 279.25 86.15 0)
			(layer "F.Fab")
			(hide yes)
			(effects
				(font
					(size 1 1)
					(thickness 0.15)
				)
			)
		)
		(property "License" "Apache-2.0"
			(at 279.25 86.15 0)
			(layer "F.Fab")
			(hide yes)
			(effects
				(font
					(size 1 1)
					(thickness 0.15)
				)
			)
		)
		(property "MPN" "GRM155R61H104KE14D"
			(at 279.25 86.15 0)
			(layer "F.Fab")
			(hide yes)
			(effects
				(font
					(size 1 1)
					(thickness 0.15)
				)
			)
		)
		(property "Manufacturer" "Murata"
			(at 279.25 86.15 0)
			(layer "F.Fab")
			(hide yes)
			(effects
				(font
					(size 1 1)
					(thickness 0.15)
				)
			)
		)
		(property "Val" "100n"
			(at 279.25 86.15 0)
			(layer "F.Fab")
			(hide yes)
			(effects
				(font
					(size 1 1)
					(thickness 0.15)
				)
			)
		)
		(property "Voltage" "50V"
			(at 279.25 86.15 0)
			(layer "F.Fab")
			(hide yes)
			(effects
				(font
					(size 1 1)
					(thickness 0.15)
				)
			)
		)
		(sheetname "/Debug FTDI/")
		(sheetfile "debug-ftdi.kicad_sch")
		(attr smd)
		(fp_rect
			(start -0.9659 -0.481258)
			(end 0.9649 0.458742)
			(stroke
				(width 0.05)
				(type solid)
			)
			(fill no)
			(layer "F.CrtYd")
		)
		(fp_line
			(start 0.499 -0.25)
			(end 0.499 0.248)
			(stroke
				(width 0.15)
				(type solid)
			)
			(layer "F.Fab")
		)
		(fp_line
			(start -0.499 -0.25)
			(end 0.499 -0.25)
			(stroke
				(width 0.15)
				(type solid)
			)
			(layer "F.Fab")
		)
		(fp_line
			(start 0.499 0.248)
			(end -0.499 0.248)
			(stroke
				(width 0.15)
				(type solid)
			)
			(layer "F.Fab")
		)
		(fp_line
			(start -0.499 0.248)
			(end -0.499 -0.25)
			(stroke
				(width 0.15)
				(type solid)
			)
			(layer "F.Fab")
		)
		(pad "1" smd roundrect
			(at -0.484 0 90)
			(size 0.59 0.64)
			(layers "F.Cu" "F.Mask" "F.Paste")
			(roundrect_rratio 0.25)
			(net 1 "GND")
			(pintype "passive")
		)
		(pad "2" smd roundrect
			(at 0.484 0 90)
			(size 0.59 0.64)
			(layers "F.Cu" "F.Mask" "F.Paste")
			(roundrect_rratio 0.25)
			(net 200 "+3V3")
			(pintype "passive")
		)
	)
	(footprint "antmicro-footprints:C_Pol_EIA-B"
		(layer "F.Cu")
		(at 129.9 191.9 -90)
		(property "Reference" "C38"
			(at 0 -2.3 270)
			(layer "F.SilkS")
			(hide yes)
			(effects
				(font
					(size 0.7 0.7)
					(thickness 0.15)
				)
				(justify left bottom)
			)
		)
		(property "Value" "C_Pol_330u_6.3V_KEMET-T520-B"
			(at 0 2.85 270)
			(layer "F.Fab")
			(effects
				(font
					(size 0.7 0.7)
					(thickness 0.15)
				)
				(justify left bottom)
			)
		)
		(property "Datasheet" "https://content.kemet.com/datasheets/KEM_T2076_T52X-530.pdf"
			(at 0 0 270)
			(layer "F.Fab")
			(hide yes)
			(effects
				(font
					(size 1.27 1.27)
					(thickness 0.15)
				)
			)
		)
		(property "Author" "Antmicro"
			(at -62 321.8 0)
			(layer "F.Fab")
			(hide yes)
			(effects
				(font
					(size 1 1)
					(thickness 0.15)
				)
			)
		)
		(property "License" "Apache-2.0"
			(at -62 321.8 0)
			(layer "F.Fab")
			(hide yes)
			(effects
				(font
					(size 1 1)
					(thickness 0.15)
				)
			)
		)
		(property "MPN" "T520B337M006ATE040"
			(at -62 321.8 0)
			(layer "F.Fab")
			(hide yes)
			(effects
				(font
					(size 1 1)
					(thickness 0.15)
				)
			)
		)
		(property "Manufacturer" "KEMET"
			(at -62 321.8 0)
			(layer "F.Fab")
			(hide yes)
			(effects
				(font
					(size 1 1)
					(thickness 0.15)
				)
			)
		)
		(property "Val" "330u/6.3V"
			(at -62 321.8 0)
			(layer "F.Fab")
			(hide yes)
			(effects
				(font
					(size 1 1)
					(thickness 0.15)
				)
			)
		)
		(property "Voltage" "6.3V"
			(at -62 321.8 0)
			(layer "F.Fab")
			(hide yes)
			(effects
				(font
					(size 1 1)
					(thickness 0.15)
				)
			)
		)
		(sheetname "/FPGA power/")
		(sheetfile "fpga-power.kicad_sch")
		(zone_connect 2)
		(attr smd)
		(fp_line
			(start 1.8 1.6)
			(end -1.8 1.6)
			(stroke
				(width 0.15)
				(type solid)
			)
			(layer "F.SilkS")
		)
		(fp_line
			(start -1.8 1.3)
			(end -1.8 1.6)
			(stroke
				(width 0.15)
				(type solid)
			)
			(layer "F.SilkS")
		)
		(fp_line
			(start 1.8 1.3)
			(end 1.8 1.6)
			(stroke
				(width 0.15)
				(type solid)
			)
			(layer "F.SilkS")
		)
		(fp_line
			(start -1.8 -1.3)
			(end -1.8 -1.6)
			(stroke
				(width 0.15)
				(type solid)
			)
			(layer "F.SilkS")
		)
		(fp_line
			(start 1.8 -1.3)
			(end 1.8 -1.6)
			(stroke
				(width 0.15)
				(type solid)
			)
			(layer "F.SilkS")
		)
		(fp_line
			(start -2.325 -1.475)
			(end -2.325 -1.878)
			(stroke
				(width 0.15)
				(type solid)
			)
			(layer "F.SilkS")
		)
		(fp_line
			(start -1.8 -1.6)
			(end 1.8 -1.6)
			(stroke
				(width 0.15)
				(type solid)
			)
			(layer "F.SilkS")
		)
		(fp_line
			(start -2.521 -1.676)
			(end -2.123 -1.676)
			(stroke
				(width 0.15)
				(type solid)
			)
			(layer "F.SilkS")
		)
		(fp_line
			(start 1.96 1.75)
			(end -1.97 1.75)
			(stroke
				(width 0.05)
				(type solid)
			)
			(layer "F.CrtYd")
		)
		(fp_line
			(start -1.97 1.35)
			(end -1.97 1.75)
			(stroke
				(width 0.05)
				(type solid)
			)
			(layer "F.CrtYd")
		)
		(fp_line
			(start -1.97 1.35)
			(end -2.41 1.35)
			(stroke
				(width 0.05)
				(type solid)
			)
			(layer "F.CrtYd")
		)
		(fp_line
			(start 1.96 1.35)
			(end 1.96 1.75)
			(stroke
				(width 0.05)
				(type solid)
			)
			(layer "F.CrtYd")
		)
		(fp_line
			(start 2.4 1.35)
			(end 1.96 1.35)
			(stroke
				(width 0.05)
				(type solid)
			)
			(layer "F.CrtYd")
		)
		(fp_line
			(start -2.411 -1.35)
			(end -2.41 1.35)
			(stroke
				(width 0.05)
				(type solid)
			)
			(layer "F.CrtYd")
		)
		(fp_line
			(start -1.97 -1.35)
			(end -2.41 -1.35)
			(stroke
				(width 0.05)
				(type solid)
			)
			(layer "F.CrtYd")
		)
		(fp_line
			(start 2.399 -1.35)
			(end 2.4 1.35)
			(stroke
				(width 0.05)
				(type solid)
			)
			(layer "F.CrtYd")
		)
		(fp_line
			(start 2.399 -1.35)
			(end 1.959 -1.35)
			(stroke
				(width 0.05)
				(type solid)
			)
			(layer "F.CrtYd")
		)
		(fp_line
			(start -1.97 -1.75)
			(end -1.97 -1.35)
			(stroke
				(width 0.05)
				(type solid)
			)
			(layer "F.CrtYd")
		)
		(fp_line
			(start 1.959 -1.75)
			(end 1.959 -1.35)
			(stroke
				(width 0.05)
				(type solid)
			)
			(layer "F.CrtYd")
		)
		(fp_line
			(start 1.959 -1.75)
			(end -1.971 -1.75)
			(stroke
				(width 0.05)
				(type solid)
			)
			(layer "F.CrtYd")
		)
		(fp_line
			(start -1.7 1.324)
			(end -1.551 1.475)
			(stroke
				(width 0.15)
				(type solid)
			)
			(layer "F.Fab")
		)
		(fp_rect
			(start -1.72 -1.5)
			(end 1.719 1.499)
			(stroke
				(width 0.15)
				(type solid)
			)
			(fill no)
			(layer "F.Fab")
		)
		(pad "1" smd roundrect
			(at -1.551 0 270)
			(size 1.2 2.2)
			(layers "F.Cu" "F.Mask" "F.Paste")
			(roundrect_rratio 0.1)
			(net 227 "+1V0")
			(pintype "passive")
		)
		(pad "2" smd roundrect
			(at 1.55 0 270)
			(size 1.2 2.2)
			(layers "F.Cu" "F.Mask" "F.Paste")
			(roundrect_rratio 0.1)
			(net 1 "GND")
			(pintype "passive")
		)
	)
	(footprint "antmicro-footprints:R_1206_3216Metric"
		(layer "F.Cu")
		(at 188.7 189.1 180)
		(property "Reference" "R141"
			(at 0.1 1.2 180)
			(layer "F.SilkS")
			(effects
				(font
					(size 0.7 0.7)
					(thickness 0.15)
				)
				(justify left bottom)
			)
		)
		(property "Value" "R_0R01_1206"
			(at -2.422356 2.103591 180)
			(layer "F.Fab")
			(effects
				(font
					(size 0.7 0.7)
					(thickness 0.15)
				)
				(justify left bottom)
			)
		)
		(property "Datasheet" "https://www.yageo.com/upload/media/product/productsearch/datasheet/rchip/PYu-RL_Group_521_RoHS_L_2.pdf"
			(at 0 0 180)
			(layer "F.Fab")
			(hide yes)
			(effects
				(font
					(size 1.27 1.27)
					(thickness 0.15)
				)
			)
		)
		(property "Author" "Antmicro"
			(at 377.4 378.2 0)
			(layer "F.Fab")
			(hide yes)
			(effects
				(font
					(size 1 1)
					(thickness 0.15)
				)
			)
		)
		(property "License" "Apache-2.0"
			(at 377.4 378.2 0)
			(layer "F.Fab")
			(hide yes)
			(effects
				(font
					(size 1 1)
					(thickness 0.15)
				)
			)
		)
		(property "MPN" "RL1206FR-7W0R01L"
			(at 377.4 378.2 0)
			(layer "F.Fab")
			(hide yes)
			(effects
				(font
					(size 1 1)
					(thickness 0.15)
				)
			)
		)
		(property "Manufacturer" "YAGEO"
			(at 377.4 378.2 0)
			(layer "F.Fab")
			(hide yes)
			(effects
				(font
					(size 1 1)
					(thickness 0.15)
				)
			)
		)
		(property "Tolerance" "1%"
			(at 377.4 378.2 0)
			(layer "F.Fab")
			(hide yes)
			(effects
				(font
					(size 1 1)
					(thickness 0.15)
				)
			)
		)
		(property "Val" "0R01"
			(at 377.4 378.2 0)
			(layer "F.Fab")
			(hide yes)
			(effects
				(font
					(size 1 1)
					(thickness 0.15)
				)
			)
		)
		(sheetname "/Supply/")
		(sheetfile "supply.kicad_sch")
		(attr smd)
		(fp_line
			(start 0 0.9)
			(end 0.498 0.9)
			(stroke
				(width 0.15)
				(type solid)
			)
			(layer "F.SilkS")
		)
		(fp_line
			(start 0 0.9)
			(end -0.5 0.9)
			(stroke
				(width 0.15)
				(type solid)
			)
			(layer "F.SilkS")
		)
		(fp_line
			(start 0 -0.902)
			(end 0.498 -0.902)
			(stroke
				(width 0.15)
				(type solid)
			)
			(layer "F.SilkS")
		)
		(fp_line
			(start 0 -0.902)
			(end -0.5 -0.902)
			(stroke
				(width 0.15)
				(type solid)
			)
			(layer "F.SilkS")
		)
		(fp_rect
			(start -2.25 -1.05)
			(end 2.25 1.05)
			(stroke
				(width 0.05)
				(type solid)
			)
			(fill no)
			(layer "F.CrtYd")
		)
		(fp_line
			(start 1.6 -0.802)
			(end 1.6 0.8)
			(stroke
				(width 0.15)
				(type solid)
			)
			(layer "F.Fab")
		)
		(fp_line
			(start -1.601 0.8)
			(end 1.6 0.8)
			(stroke
				(width 0.15)
				(type solid)
			)
			(layer "F.Fab")
		)
		(fp_line
			(start -1.601 -0.802)
			(end 1.6 -0.802)
			(stroke
				(width 0.15)
				(type solid)
			)
			(layer "F.Fab")
		)
		(fp_line
			(start -1.601 -0.802)
			(end -1.601 0.8)
			(stroke
				(width 0.15)
				(type solid)
			)
			(layer "F.Fab")
		)
		(pad "1" smd roundrect
			(at -1.5 0 180)
			(size 1.2 1.8)
			(layers "F.Cu" "F.Mask" "F.Paste")
			(roundrect_rratio 0.15)
			(net 42 "/Supply/MGTAVCC_local")
			(pintype "passive")
		)
		(pad "2" smd roundrect
			(at 1.499 0 180)
			(size 1.2 1.8)
			(layers "F.Cu" "F.Mask" "F.Paste")
			(roundrect_rratio 0.15)
			(net 187 "+1V0_MGTAVCC")
			(pintype "passive")
		)
	)
	(footprint "antmicro-footprints:LED_0603_1608Metric_G"
		(layer "F.Cu")
		(at 96.3 197.1 -90)
		(descr "LED SMD 0603 Green")
		(tags "LED SMD 0603 Green")
		(property "Reference" "D12"
			(at -0.001 -0.901 270)
			(layer "F.SilkS")
			(hide yes)
			(effects
				(font
					(size 0.7 0.7)
					(thickness 0.15)
				)
				(justify left bottom)
			)
		)
		(property "Value" "LED_G_0603_KP-1608CGCK"
			(at -0.001 1.599 270)
			(layer "F.Fab")
			(effects
				(font
					(size 0.7 0.7)
					(thickness 0.15)
				)
				(justify left bottom)
			)
		)
		(property "Datasheet" "http://www.farnell.com/datasheets/2045956.pdf"
			(at 0 0 270)
			(layer "F.Fab")
			(hide yes)
			(effects
				(font
					(size 1.27 1.27)
					(thickness 0.15)
				)
			)
		)
		(property "Author" "Antmicro"
			(at -100.8 293.4 0)
			(layer "F.Fab")
			(hide yes)
			(effects
				(font
					(size 1 1)
					(thickness 0.15)
				)
			)
		)
		(property "License" "Apache-2.0"
			(at -100.8 293.4 0)
			(layer "F.Fab")
			(hide yes)
			(effects
				(font
					(size 1 1)
					(thickness 0.15)
				)
			)
		)
		(property "MPN" "KP-1608CGCK"
			(at -100.8 293.4 0)
			(layer "F.Fab")
			(hide yes)
			(effects
				(font
					(size 1 1)
					(thickness 0.15)
				)
			)
		)
		(property "Manufacturer" "Kingbright"
			(at -100.8 293.4 0)
			(layer "F.Fab")
			(hide yes)
			(effects
				(font
					(size 1 1)
					(thickness 0.15)
				)
			)
		)
		(sheetname "/Debug FTDI/")
		(sheetfile "debug-ftdi.kicad_sch")
		(attr smd)
		(fp_line
			(start -0.271 0.348)
			(end 0.269 0.348)
			(stroke
				(width 0.15)
				(type solid)
			)
			(layer "F.SilkS")
		)
		(fp_line
			(start 1.249 0.319)
			(end 1.249 -0.321)
			(stroke
				(width 0.15)
				(type solid)
			)
			(layer "F.SilkS")
		)
		(fp_line
			(start -0.107 -0.001)
			(end -0.291 -0.001)
			(stroke
				(width 0.1)
				(type solid)
			)
			(layer "F.SilkS")
		)
		(fp_line
			(start 0.092 -0.001)
			(end -0.107 0.198)
			(stroke
				(width 0.1)
				(type solid)
			)
			(layer "F.SilkS")
		)
		(fp_line
			(start 0.092 -0.001)
			(end 0.292 -0.001)
			(stroke
				(width 0.1)
				(type solid)
			)
			(layer "F.SilkS")
		)
		(fp_line
			(start -0.107 -0.201)
			(end -0.107 0.198)
			(stroke
				(width 0.1)
				(type solid)
			)
			(layer "F.SilkS")
		)
		(fp_line
			(start -0.107 -0.201)
			(end 0.092 -0.001)
			(stroke
				(width 0.1)
				(type solid)
			)
			(layer "F.SilkS")
		)
		(fp_line
			(start 0.092 -0.201)
			(end 0.092 0.198)
			(stroke
				(width 0.1)
				(type solid)
			)
			(layer "F.SilkS")
		)
		(fp_line
			(start -0.271 -0.349)
			(end 0.269 -0.349)
			(stroke
				(width 0.15)
				(type solid)
			)
			(layer "F.SilkS")
		)
		(fp_rect
			(start -1.2192 -0.6096)
			(end 1.27 0.6016)
			(stroke
				(width 0.05)
				(type solid)
			)
			(fill no)
			(layer "F.CrtYd")
		)
		(fp_line
			(start -0.202 0.201)
			(end 0.1 -0.001)
			(stroke
				(width 0.15)
				(type solid)
			)
			(layer "F.Fab")
		)
		(fp_line
			(start 0.198 0.201)
			(end 0.198 -0.101)
			(stroke
				(width 0.15)
				(type solid)
			)
			(layer "F.Fab")
		)
		(fp_line
			(start -0.849 0.025)
			(end -0.442 0.381)
			(stroke
				(width 0.15)
				(type solid)
			)
			(layer "F.Fab")
		)
		(fp_line
			(start -0.6 -0.001)
			(end -0.202 -0.001)
			(stroke
				(width 0.15)
				(type solid)
			)
			(layer "F.Fab")
		)
		(fp_line
			(start -0.202 -0.001)
			(end -0.202 0.201)
			(stroke
				(width 0.15)
				(type solid)
			)
			(layer "F.Fab")
		)
		(fp_line
			(start 0.1 -0.001)
			(end -0.202 -0.201)
			(stroke
				(width 0.15)
				(type solid)
			)
			(layer "F.Fab")
		)
		(fp_line
			(start 0.198 -0.001)
			(end 0.596 -0.001)
			(stroke
				(width 0.15)
				(type solid)
			)
			(layer "F.Fab")
		)
		(fp_line
			(start -0.202 -0.201)
			(end -0.202 -0.001)
			(stroke
				(width 0.15)
				(type solid)
			)
			(layer "F.Fab")
		)
		(fp_line
			(start 0.198 -0.201)
			(end 0.198 -0.101)
			(stroke
				(width 0.15)
				(type solid)
			)
			(layer "F.Fab")
		)
		(fp_rect
			(start -0.849 -0.401)
			(end 0.849 0.401)
			(stroke
				(width 0.15)
				(type solid)
			)
			(fill no)
			(layer "F.Fab")
		)
		(pad "1" smd rect
			(at -0.751 -0.001 90)
			(size 0.8 0.8)
			(layers "F.Cu" "F.Mask" "F.Paste")
			(net 317 "Net-(D12-Pad1)")
			(pinfunction "1")
			(pintype "passive")
		)
		(pad "2" smd rect
			(at 0.749 -0.001 90)
			(size 0.8 0.8)
			(layers "F.Cu" "F.Mask" "F.Paste")
			(net 1 "GND")
			(pinfunction "2")
			(pintype "passive")
		)
	)
	(footprint "antmicro-footprints:R_0402_1005Metric"
		(layer "F.Cu")
		(at 96.3 194.83 90)
		(descr "Resistor SMD 0402")
		(tags "resistor SMD 0402")
		(property "Reference" "R66"
			(at -1.122484 -0.772697 90)
			(layer "F.SilkS")
			(hide yes)
			(effects
				(font
					(size 0.7 0.7)
					(thickness 0.15)
				)
				(justify left bottom)
			)
		)
		(property "Value" "R_330R_0402"
			(at -1.011843 1.772047 90)
			(layer "F.Fab")
			(effects
				(font
					(size 0.7 0.7)
					(thickness 0.15)
				)
				(justify left bottom)
			)
		)
		(property "Datasheet" "https://www.bourns.com/docs/product-datasheets/cr.pdf"
			(at 0 0 90)
			(layer "F.Fab")
			(hide yes)
			(effects
				(font
					(size 1.27 1.27)
					(thickness 0.15)
				)
			)
		)
		(property "Author" "Antmicro"
			(at 291.13 98.53 0)
			(layer "F.Fab")
			(hide yes)
			(effects
				(font
					(size 1 1)
					(thickness 0.15)
				)
			)
		)
		(property "License" "Apache-2.0"
			(at 291.13 98.53 0)
			(layer "F.Fab")
			(hide yes)
			(effects
				(font
					(size 1 1)
					(thickness 0.15)
				)
			)
		)
		(property "MPN" "CR0402-FX-3300GLF"
			(at 291.13 98.53 0)
			(layer "F.Fab")
			(hide yes)
			(effects
				(font
					(size 1 1)
					(thickness 0.15)
				)
			)
		)
		(property "Manufacturer" "Bourns"
			(at 291.13 98.53 0)
			(layer "F.Fab")
			(hide yes)
			(effects
				(font
					(size 1 1)
					(thickness 0.15)
				)
			)
		)
		(property "Tolerance" "1%"
			(at 291.13 98.53 0)
			(layer "F.Fab")
			(hide yes)
			(effects
				(font
					(size 1 1)
					(thickness 0.15)
				)
			)
		)
		(property "Val" "330R"
			(at 291.13 98.53 0)
			(layer "F.Fab")
			(hide yes)
			(effects
				(font
					(size 1 1)
					(thickness 0.15)
				)
			)
		)
		(sheetname "/Debug FTDI/")
		(sheetfile "debug-ftdi.kicad_sch")
		(attr smd)
		(fp_rect
			(start -0.93 -0.47)
			(end 0.93 0.47)
			(stroke
				(width 0.05)
				(type solid)
			)
			(fill no)
			(layer "F.CrtYd")
		)
		(fp_rect
			(start -0.5 -0.25)
			(end 0.5 0.25)
			(stroke
				(width 0.15)
				(type solid)
			)
			(fill no)
			(layer "F.Fab")
		)
		(pad "1" smd roundrect
			(at -0.485 0 90)
			(size 0.59 0.64)
			(layers "F.Cu" "F.Mask" "F.Paste")
			(roundrect_rratio 0.25)
			(net 317 "Net-(D12-Pad1)")
			(pintype "passive")
		)
		(pad "2" smd roundrect
			(at 0.485 0 90)
			(size 0.59 0.64)
			(layers "F.Cu" "F.Mask" "F.Paste")
			(roundrect_rratio 0.25)
			(net 658 "/Debug FTDI/LED_TX1")
			(pintype "passive")
		)
	)
	(footprint "antmicro-footprints:SC70-3"
		(layer "F.Cu")
		(at 192.645 138.945)
		(property "Reference" "Q14"
			(at 0 -1.6 0)
			(layer "F.SilkS")
			(hide yes)
			(effects
				(font
					(size 0.7 0.7)
					(thickness 0.15)
				)
				(justify left bottom)
			)
		)
		(property "Value" "BSS138PW,115"
			(at 0 2.3 0)
			(layer "F.Fab")
			(effects
				(font
					(size 0.7 0.7)
					(thickness 0.15)
				)
				(justify left bottom)
			)
		)
		(property "Datasheet" "https://assets.nexperia.com/documents/data-sheet/BSS138PW.pdf"
			(at 0 0 0)
			(layer "F.Fab")
			(hide yes)
			(effects
				(font
					(size 1.27 1.27)
					(thickness 0.15)
				)
			)
		)
		(property "Description" "Power MOSFET, N Channel, 60 V, 320 mA, 0.9 ohm, SOT-323, Surface Mount"
			(at 0 0 0)
			(layer "F.Fab")
			(hide yes)
			(effects
				(font
					(size 1.27 1.27)
					(thickness 0.15)
				)
			)
		)
		(property "Author" "Antmicro"
			(at 0 0 0)
			(layer "F.Fab")
			(hide yes)
			(effects
				(font
					(size 1 1)
					(thickness 0.15)
				)
			)
		)
		(property "License" "Apache-2.0"
			(at 0 0 0)
			(layer "F.Fab")
			(hide yes)
			(effects
				(font
					(size 1 1)
					(thickness 0.15)
				)
			)
		)
		(property "MPN" "BSS138PW,115"
			(at 0 0 0)
			(layer "F.Fab")
			(hide yes)
			(effects
				(font
					(size 1 1)
					(thickness 0.15)
				)
			)
		)
		(property "Manufacturer" "Nexperia"
			(at 0 0 0)
			(layer "F.Fab")
			(hide yes)
			(effects
				(font
					(size 1 1)
					(thickness 0.15)
				)
			)
		)
		(sheetname "/Supply/")
		(sheetfile "supply.kicad_sch")
		(attr smd)
		(fp_line
			(start -0.3 -1)
			(end 0.627 -0.999)
			(stroke
				(width 0.15)
				(type solid)
			)
			(layer "F.SilkS")
		)
		(fp_line
			(start -0.3 1)
			(end 0.627 1.001)
			(stroke
				(width 0.15)
				(type solid)
			)
			(layer "F.SilkS")
		)
		(fp_line
			(start 0.627 -0.6)
			(end 0.627 -0.999)
			(stroke
				(width 0.15)
				(type solid)
			)
			(layer "F.SilkS")
		)
		(fp_line
			(start 0.627 0.6)
			(end 0.627 1.001)
			(stroke
				(width 0.15)
				(type solid)
			)
			(layer "F.SilkS")
		)
		(fp_line
			(start -1.4 1)
			(end -1.4 -1)
			(stroke
				(width 0.05)
				(type solid)
			)
			(layer "F.CrtYd")
		)
		(fp_line
			(start -0.9 -1.3)
			(end -0.9 -1)
			(stroke
				(width 0.05)
				(type solid)
			)
			(layer "F.CrtYd")
		)
		(fp_line
			(start -0.9 -1.3)
			(end 0.9 -1.3)
			(stroke
				(width 0.05)
				(type solid)
			)
			(layer "F.CrtYd")
		)
		(fp_line
			(start -0.9 -1)
			(end -1.4 -1)
			(stroke
				(width 0.05)
				(type solid)
			)
			(layer "F.CrtYd")
		)
		(fp_line
			(start -0.9 1)
			(end -1.4 1)
			(stroke
				(width 0.05)
				(type solid)
			)
			(layer "F.CrtYd")
		)
		(fp_line
			(start -0.9 1.3)
			(end -0.9 1)
			(stroke
				(width 0.05)
				(type solid)
			)
			(layer "F.CrtYd")
		)
		(fp_line
			(start 0.9 -1.3)
			(end 0.9 -0.4)
			(stroke
				(width 0.05)
				(type solid)
			)
			(layer "F.CrtYd")
		)
		(fp_line
			(start 0.9 -0.4)
			(end 1.4 -0.4)
			(stroke
				(width 0.05)
				(type solid)
			)
			(layer "F.CrtYd")
		)
		(fp_line
			(start 0.9 0.4)
			(end 0.9 1.3)
			(stroke
				(width 0.05)
				(type solid)
			)
			(layer "F.CrtYd")
		)
		(fp_line
			(start 0.9 1.3)
			(end -0.9 1.3)
			(stroke
				(width 0.05)
				(type solid)
			)
			(layer "F.CrtYd")
		)
		(fp_line
			(start 1.4 -0.4)
			(end 1.4 0.4)
			(stroke
				(width 0.05)
				(type solid)
			)
			(layer "F.CrtYd")
		)
		(fp_line
			(start 1.4 0.4)
			(end 0.9 0.4)
			(stroke
				(width 0.05)
				(type solid)
			)
			(layer "F.CrtYd")
		)
		(fp_rect
			(start -0.623 -0.999)
			(end 0.627 1.001)
			(stroke
				(width 0.15)
				(type solid)
			)
			(fill no)
			(layer "F.Fab")
		)
		(pad "1" smd rect
			(at -1.051 -0.65 90)
			(size 0.6 0.6)
			(layers "F.Cu" "F.Mask" "F.Paste")
			(net 242 "FPGA_POWER_OFF")
			(pinfunction "G")
			(pintype "input")
		)
		(pad "2" smd rect
			(at -1.051 0.65 90)
			(size 0.6 0.6)
			(layers "F.Cu" "F.Mask" "F.Paste")
			(net 1 "GND")
			(pinfunction "S")
			(pintype "passive")
		)
		(pad "3" smd rect
			(at 1.05 0 90)
			(size 0.6 0.6)
			(layers "F.Cu" "F.Mask" "F.Paste")
			(net 185 "/Supply/~{PB_CTRL_CLR}")
			(pinfunction "D")
			(pintype "passive")
		)
	)
	(footprint "antmicro-footprints:R_0402_1005Metric"
		(layer "F.Cu")
		(at 190.545 141.745 90)
		(descr "Resistor SMD 0402")
		(tags "resistor SMD 0402")
		(property "Reference" "R171"
			(at -1.122484 -0.772697 90)
			(layer "F.SilkS")
			(hide yes)
			(effects
				(font
					(size 0.7 0.7)
					(thickness 0.15)
				)
				(justify left bottom)
			)
		)
		(property "Value" "R_47k_0402"
			(at -1.011843 1.772047 90)
			(layer "F.Fab")
			(effects
				(font
					(size 0.7 0.7)
					(thickness 0.15)
				)
				(justify left bottom)
			)
		)
		(property "Datasheet" "https://www.bourns.com/docs/product-datasheets/cr.pdf"
			(at 0 0 90)
			(layer "F.Fab")
			(hide yes)
			(effects
				(font
					(size 1.27 1.27)
					(thickness 0.15)
				)
			)
		)
		(property "Author" "Antmicro"
			(at 332.29 -48.8 0)
			(layer "F.Fab")
			(hide yes)
			(effects
				(font
					(size 1 1)
					(thickness 0.15)
				)
			)
		)
		(property "License" "Apache-2.0"
			(at 332.29 -48.8 0)
			(layer "F.Fab")
			(hide yes)
			(effects
				(font
					(size 1 1)
					(thickness 0.15)
				)
			)
		)
		(property "MPN" "CR0402-FX-4702GLF"
			(at 332.29 -48.8 0)
			(layer "F.Fab")
			(hide yes)
			(effects
				(font
					(size 1 1)
					(thickness 0.15)
				)
			)
		)
		(property "Manufacturer" "Bourns"
			(at 332.29 -48.8 0)
			(layer "F.Fab")
			(hide yes)
			(effects
				(font
					(size 1 1)
					(thickness 0.15)
				)
			)
		)
		(property "Tolerance" "1%"
			(at 332.29 -48.8 0)
			(layer "F.Fab")
			(hide yes)
			(effects
				(font
					(size 1 1)
					(thickness 0.15)
				)
			)
		)
		(property "Val" "47k"
			(at 332.29 -48.8 0)
			(layer "F.Fab")
			(hide yes)
			(effects
				(font
					(size 1 1)
					(thickness 0.15)
				)
			)
		)
		(sheetname "/Supply/")
		(sheetfile "supply.kicad_sch")
		(attr smd)
		(fp_rect
			(start -0.93 -0.47)
			(end 0.93 0.47)
			(stroke
				(width 0.05)
				(type solid)
			)
			(fill no)
			(layer "F.CrtYd")
		)
		(fp_rect
			(start -0.5 -0.25)
			(end 0.5 0.25)
			(stroke
				(width 0.15)
				(type solid)
			)
			(fill no)
			(layer "F.Fab")
		)
		(pad "1" smd roundrect
			(at -0.485 0 90)
			(size 0.59 0.64)
			(layers "F.Cu" "F.Mask" "F.Paste")
			(roundrect_rratio 0.25)
			(net 1 "GND")
			(pintype "passive")
		)
		(pad "2" smd roundrect
			(at 0.485 0 90)
			(size 0.59 0.64)
			(layers "F.Cu" "F.Mask" "F.Paste")
			(roundrect_rratio 0.25)
			(net 241 "FPGA_POWER_CYCLE")
			(pintype "passive")
		)
	)
	(footprint "antmicro-footprints:LED_0603_1608Metric_G"
		(layer "F.Cu")
		(at 78.6 126.3)
		(descr "LED SMD 0603 Green")
		(tags "LED SMD 0603 Green")
		(property "Reference" "D1"
			(at -0.001 -0.901 0)
			(layer "F.SilkS")
			(hide yes)
			(effects
				(font
					(size 0.7 0.7)
					(thickness 0.15)
				)
				(justify left bottom)
			)
		)
		(property "Value" "LED_G_0603_KP-1608CGCK"
			(at -0.001 1.599 0)
			(layer "F.Fab")
			(effects
				(font
					(size 0.7 0.7)
					(thickness 0.15)
				)
				(justify left bottom)
			)
		)
		(property "Datasheet" "http://www.farnell.com/datasheets/2045956.pdf"
			(at 0 0 0)
			(layer "F.Fab")
			(hide yes)
			(effects
				(font
					(size 1.27 1.27)
					(thickness 0.15)
				)
			)
		)
		(property "Author" "Antmicro"
			(at 0 0 0)
			(layer "F.Fab")
			(hide yes)
			(effects
				(font
					(size 1 1)
					(thickness 0.15)
				)
			)
		)
		(property "License" "Apache-2.0"
			(at 0 0 0)
			(layer "F.Fab")
			(hide yes)
			(effects
				(font
					(size 1 1)
					(thickness 0.15)
				)
			)
		)
		(property "MPN" "KP-1608CGCK"
			(at 0 0 0)
			(layer "F.Fab")
			(hide yes)
			(effects
				(font
					(size 1 1)
					(thickness 0.15)
				)
			)
		)
		(property "Manufacturer" "Kingbright"
			(at 0 0 0)
			(layer "F.Fab")
			(hide yes)
			(effects
				(font
					(size 1 1)
					(thickness 0.15)
				)
			)
		)
		(sheetname "/FPGA Config/")
		(sheetfile "fpga-config.kicad_sch")
		(attr smd)
		(fp_line
			(start -0.271 -0.349)
			(end 0.269 -0.349)
			(stroke
				(width 0.15)
				(type solid)
			)
			(layer "F.SilkS")
		)
		(fp_line
			(start -0.271 0.348)
			(end 0.269 0.348)
			(stroke
				(width 0.15)
				(type solid)
			)
			(layer "F.SilkS")
		)
		(fp_line
			(start -0.107 -0.201)
			(end -0.107 0.198)
			(stroke
				(width 0.1)
				(type solid)
			)
			(layer "F.SilkS")
		)
		(fp_line
			(start -0.107 -0.201)
			(end 0.092 -0.001)
			(stroke
				(width 0.1)
				(type solid)
			)
			(layer "F.SilkS")
		)
		(fp_line
			(start -0.107 -0.001)
			(end -0.291 -0.001)
			(stroke
				(width 0.1)
				(type solid)
			)
			(layer "F.SilkS")
		)
		(fp_line
			(start 0.092 -0.201)
			(end 0.092 0.198)
			(stroke
				(width 0.1)
				(type solid)
			)
			(layer "F.SilkS")
		)
		(fp_line
			(start 0.092 -0.001)
			(end -0.107 0.198)
			(stroke
				(width 0.1)
				(type solid)
			)
			(layer "F.SilkS")
		)
		(fp_line
			(start 0.092 -0.001)
			(end 0.292 -0.001)
			(stroke
				(width 0.1)
				(type solid)
			)
			(layer "F.SilkS")
		)
		(fp_line
			(start 1.249 0.319)
			(end 1.249 -0.321)
			(stroke
				(width 0.15)
				(type solid)
			)
			(layer "F.SilkS")
		)
		(fp_rect
			(start -1.2192 -0.6096)
			(end 1.27 0.6016)
			(stroke
				(width 0.05)
				(type solid)
			)
			(fill no)
			(layer "F.CrtYd")
		)
		(fp_line
			(start -0.849 0.025)
			(end -0.442 0.381)
			(stroke
				(width 0.15)
				(type solid)
			)
			(layer "F.Fab")
		)
		(fp_line
			(start -0.6 -0.001)
			(end -0.202 -0.001)
			(stroke
				(width 0.15)
				(type solid)
			)
			(layer "F.Fab")
		)
		(fp_line
			(start -0.202 -0.201)
			(end -0.202 -0.001)
			(stroke
				(width 0.15)
				(type solid)
			)
			(layer "F.Fab")
		)
		(fp_line
			(start -0.202 -0.001)
			(end -0.202 0.201)
			(stroke
				(width 0.15)
				(type solid)
			)
			(layer "F.Fab")
		)
		(fp_line
			(start -0.202 0.201)
			(end 0.1 -0.001)
			(stroke
				(width 0.15)
				(type solid)
			)
			(layer "F.Fab")
		)
		(fp_line
			(start 0.1 -0.001)
			(end -0.202 -0.201)
			(stroke
				(width 0.15)
				(type solid)
			)
			(layer "F.Fab")
		)
		(fp_line
			(start 0.198 -0.201)
			(end 0.198 -0.101)
			(stroke
				(width 0.15)
				(type solid)
			)
			(layer "F.Fab")
		)
		(fp_line
			(start 0.198 -0.001)
			(end 0.596 -0.001)
			(stroke
				(width 0.15)
				(type solid)
			)
			(layer "F.Fab")
		)
		(fp_line
			(start 0.198 0.201)
			(end 0.198 -0.101)
			(stroke
				(width 0.15)
				(type solid)
			)
			(layer "F.Fab")
		)
		(fp_rect
			(start -0.849 -0.401)
			(end 0.849 0.401)
			(stroke
				(width 0.15)
				(type solid)
			)
			(fill no)
			(layer "F.Fab")
		)
		(pad "1" smd rect
			(at -0.751 -0.001 180)
			(size 0.4 0.8)
			(layers "F.Cu" "F.Mask" "F.Paste")
			(net 200 "+3V3")
			(pinfunction "1")
			(pintype "passive")
		)
		(pad "2" smd rect
			(at 0.749 -0.001 180)
			(size 0.4 0.8)
			(layers "F.Cu" "F.Mask" "F.Paste")
			(net 304 "Net-(D1-Pad2)")
			(pinfunction "2")
			(pintype "passive")
		)
	)
	(footprint "antmicro-footprints:ESDA25P35-1U1M"
		(layer "F.Cu")
		(at 185.825 128.55 -90)
		(descr "DIODE SMD 0603")
		(tags "DIODE SMD 0603")
		(property "Reference" "D16"
			(at 0 -0.9 270)
			(layer "F.SilkS")
			(hide yes)
			(effects
				(font
					(size 0.7 0.7)
					(thickness 0.15)
				)
				(justify left bottom)
			)
		)
		(property "Value" "ESDA25P35-1U1M"
			(at 0 1.6 270)
			(layer "F.Fab")
			(effects
				(font
					(size 0.7 0.7)
					(thickness 0.15)
				)
				(justify left bottom)
			)
		)
		(property "Datasheet" "https://www.st.com/resource/en/datasheet/esda25p35-1u1m.pdf"
			(at 0 0 270)
			(layer "F.Fab")
			(hide yes)
			(effects
				(font
					(size 1.27 1.27)
					(thickness 0.15)
				)
			)
		)
		(property "Author" "Antmicro"
			(at 57.275 314.375 0)
			(layer "F.Fab")
			(hide yes)
			(effects
				(font
					(size 1 1)
					(thickness 0.15)
				)
			)
		)
		(property "License" "Apache-2.0"
			(at 57.275 314.375 0)
			(layer "F.Fab")
			(hide yes)
			(effects
				(font
					(size 1 1)
					(thickness 0.15)
				)
			)
		)
		(property "MPN" "ESDA25P35-1U1M"
			(at 57.275 314.375 0)
			(layer "F.Fab")
			(hide yes)
			(effects
				(font
					(size 1 1)
					(thickness 0.15)
				)
			)
		)
		(property "Manufacturer" "STMicroelectronics"
			(at 57.275 314.375 0)
			(layer "F.Fab")
			(hide yes)
			(effects
				(font
					(size 1 1)
					(thickness 0.15)
				)
			)
		)
		(sheetname "/Supply/")
		(sheetfile "supply.kicad_sch")
		(attr smd)
		(fp_line
			(start 1.25 0.5)
			(end 1.25 -0.498)
			(stroke
				(width 0.15)
				(type solid)
			)
			(layer "F.SilkS")
		)
		(fp_line
			(start -0.27 0.3)
			(end 0.27 0.3)
			(stroke
				(width 0.15)
				(type solid)
			)
			(layer "F.SilkS")
		)
		(fp_line
			(start -0.27 -0.3)
			(end 0.27 -0.3)
			(stroke
				(width 0.15)
				(type solid)
			)
			(layer "F.SilkS")
		)
		(fp_rect
			(start 1.31 0.7)
			(end -1.31 -0.7)
			(stroke
				(width 0.05)
				(type solid)
			)
			(fill no)
			(layer "F.CrtYd")
		)
		(fp_line
			(start -0.201 0.202)
			(end 0.101 0)
			(stroke
				(width 0.15)
				(type solid)
			)
			(layer "F.Fab")
		)
		(fp_line
			(start 0.199 0.202)
			(end 0.199 -0.1)
			(stroke
				(width 0.15)
				(type solid)
			)
			(layer "F.Fab")
		)
		(fp_line
			(start -0.599 0)
			(end -0.201 0)
			(stroke
				(width 0.15)
				(type solid)
			)
			(layer "F.Fab")
		)
		(fp_line
			(start -0.201 0)
			(end -0.201 0.202)
			(stroke
				(width 0.15)
				(type solid)
			)
			(layer "F.Fab")
		)
		(fp_line
			(start 0.101 0)
			(end -0.201 -0.2)
			(stroke
				(width 0.15)
				(type solid)
			)
			(layer "F.Fab")
		)
		(fp_line
			(start 0.199 0)
			(end 0.597 0)
			(stroke
				(width 0.15)
				(type solid)
			)
			(layer "F.Fab")
		)
		(fp_line
			(start -0.201 -0.2)
			(end -0.201 0)
			(stroke
				(width 0.15)
				(type solid)
			)
			(layer "F.Fab")
		)
		(fp_line
			(start 0.199 -0.2)
			(end 0.199 -0.1)
			(stroke
				(width 0.15)
				(type solid)
			)
			(layer "F.Fab")
		)
		(fp_rect
			(start -0.848 -0.4)
			(end 0.85 0.402)
			(stroke
				(width 0.15)
				(type solid)
			)
			(fill no)
			(layer "F.Fab")
		)
		(pad "1" smd rect
			(at -0.75 0 90)
			(size 0.8 0.8)
			(layers "F.Cu" "F.Mask" "F.Paste")
			(net 1 "GND")
			(pinfunction "K")
			(pintype "passive")
		)
		(pad "2" smd rect
			(at 0.75 0 90)
			(size 0.8 0.8)
			(layers "F.Cu" "F.Mask" "F.Paste")
			(net 595 "/Supply/12V_aux_fused")
			(pinfunction "A")
			(pintype "passive")
		)
	)
	(footprint "antmicro-footprints:USON-10_2.5x1mm_P0.5mm"
		(layer "F.Cu")
		(at 77.7 155.3 180)
		(descr "USON-10 2.5x1mm_ Pitch 0.5mm")
		(tags "USON-10 2.5x1mm Pitch 0.5mm")
		(property "Reference" "U8"
			(at 0.018 -1.7 180)
			(layer "F.SilkS")
			(hide yes)
			(effects
				(font
					(size 0.7 0.7)
					(thickness 0.15)
				)
				(justify left bottom)
			)
		)
		(property "Value" "TPD4E05U06QDQARQ1"
			(at 0.018 2.499 180)
			(layer "F.Fab")
			(effects
				(font
					(size 0.7 0.7)
					(thickness 0.15)
				)
				(justify left bottom)
			)
		)
		(property "Datasheet" "https://www.ti.com/lit/ds/symlink/tpd4e05u06-q1.pdf?HQS=dis-mous-null-mousermode-dsf-pf-null-wwe&ts=1663591265741&ref_url=https%253A%252F%252Fwww.mouser.com%252F"
			(at 0 0 180)
			(layer "F.Fab")
			(hide yes)
			(effects
				(font
					(size 1.27 1.27)
					(thickness 0.15)
				)
			)
		)
		(property "Author" "Antmicro"
			(at 155.4 310.6 0)
			(layer "F.Fab")
			(hide yes)
			(effects
				(font
					(size 1 1)
					(thickness 0.15)
				)
			)
		)
		(property "License" "Apache-2.0"
			(at 155.4 310.6 0)
			(layer "F.Fab")
			(hide yes)
			(effects
				(font
					(size 1 1)
					(thickness 0.15)
				)
			)
		)
		(property "MPN" "TPD4E05U06QDQARQ1"
			(at 155.4 310.6 0)
			(layer "F.Fab")
			(hide yes)
			(effects
				(font
					(size 1 1)
					(thickness 0.15)
				)
			)
		)
		(property "Manufacturer" "Texas Instruments"
			(at 155.4 310.6 0)
			(layer "F.Fab")
			(hide yes)
			(effects
				(font
					(size 1 1)
					(thickness 0.15)
				)
			)
		)
		(sheetname "/Debug FTDI/")
		(sheetfile "debug-ftdi.kicad_sch")
		(attr smd)
		(fp_line
			(start 0.498 1.398)
			(end -0.5 1.398)
			(stroke
				(width 0.15)
				(type solid)
			)
			(layer "F.SilkS")
		)
		(fp_line
			(start 0.498 -1.401)
			(end -0.5 -1.401)
			(stroke
				(width 0.15)
				(type solid)
			)
			(layer "F.SilkS")
		)
		(fp_circle
			(center -0.68 -1.27)
			(end -0.63 -1.27)
			(stroke
				(width 0.15)
				(type solid)
			)
			(fill yes)
			(layer "F.SilkS")
		)
		(fp_rect
			(start -0.8 -1.5)
			(end 0.8 1.499)
			(stroke
				(width 0.05)
				(type solid)
			)
			(fill no)
			(layer "F.CrtYd")
		)
		(fp_line
			(start 0.498 -1.25)
			(end 0.498 1.249)
			(stroke
				(width 0.15)
				(type solid)
			)
			(layer "F.Fab")
		)
		(fp_line
			(start 0.498 -1.25)
			(end -0.25 -1.25)
			(stroke
				(width 0.15)
				(type solid)
			)
			(layer "F.Fab")
		)
		(fp_line
			(start -0.25 -1.25)
			(end -0.5 -1)
			(stroke
				(width 0.15)
				(type solid)
			)
			(layer "F.Fab")
		)
		(fp_line
			(start -0.5 1.249)
			(end 0.498 1.249)
			(stroke
				(width 0.15)
				(type solid)
			)
			(layer "F.Fab")
		)
		(fp_line
			(start -0.5 -1)
			(end -0.5 1.249)
			(stroke
				(width 0.15)
				(type solid)
			)
			(layer "F.Fab")
		)
		(pad "1" smd roundrect
			(at -0.387 -1 90)
			(size 0.25 0.55)
			(layers "F.Cu" "F.Mask" "F.Paste")
			(roundrect_rratio 0.25)
			(net 571 "unconnected-(U8-Pad1)")
			(pintype "passive+no_connect")
		)
		(pad "2" smd roundrect
			(at -0.387 -0.5 90)
			(size 0.25 0.55)
			(layers "F.Cu" "F.Mask" "F.Paste")
			(roundrect_rratio 0.25)
			(net 290 "/Debug FTDI/DBG_USB_P")
			(pintype "passive")
		)
		(pad "3" smd roundrect
			(at -0.387 0 90)
			(size 0.4 0.55)
			(layers "F.Cu" "F.Mask" "F.Paste")
			(roundrect_rratio 0.25)
			(net 1 "GND")
			(pintype "power_in")
		)
		(pad "4" smd roundrect
			(at -0.387 0.498 90)
			(size 0.25 0.55)
			(layers "F.Cu" "F.Mask" "F.Paste")
			(roundrect_rratio 0.25)
			(net 291 "/Debug FTDI/DBG_USB_N")
			(pintype "passive")
		)
		(pad "5" smd roundrect
			(at -0.387 0.998 90)
			(size 0.25 0.55)
			(layers "F.Cu" "F.Mask" "F.Paste")
			(roundrect_rratio 0.25)
			(net 753 "unconnected-(U8-Pad5)_1")
			(pintype "passive+no_connect")
		)
		(pad "6" smd roundrect
			(at 0.385 0.998 90)
			(size 0.25 0.55)
			(layers "F.Cu" "F.Mask" "F.Paste")
			(roundrect_rratio 0.25)
			(net 572 "unconnected-(U8-Pad5)")
			(pintype "passive+no_connect")
		)
		(pad "7" smd roundrect
			(at 0.385 0.498 90)
			(size 0.25 0.55)
			(layers "F.Cu" "F.Mask" "F.Paste")
			(roundrect_rratio 0.25)
			(net 291 "/Debug FTDI/DBG_USB_N")
			(pintype "passive")
		)
		(pad "8" smd roundrect
			(at 0.385 0 90)
			(size 0.4 0.55)
			(layers "F.Cu" "F.Mask" "F.Paste")
			(roundrect_rratio 0.25)
			(net 1 "GND")
			(pintype "passive")
		)
		(pad "9" smd roundrect
			(at 0.385 -0.5 90)
			(size 0.25 0.55)
			(layers "F.Cu" "F.Mask" "F.Paste")
			(roundrect_rratio 0.25)
			(net 290 "/Debug FTDI/DBG_USB_P")
			(pintype "passive")
		)
		(pad "10" smd roundrect
			(at 0.385 -1 90)
			(size 0.25 0.55)
			(layers "F.Cu" "F.Mask" "F.Paste")
			(roundrect_rratio 0.25)
			(net 754 "unconnected-(U8-Pad1)_1")
			(pintype "passive+no_connect")
		)
	)
	(footprint "antmicro-footprints:SW_KMR211NGLFS_SMD"
		(layer "F.Cu")
		(at 202.95 144.8 90)
		(property "Reference" "SW2"
			(at -1.1 -2 90)
			(layer "F.SilkS")
			(effects
				(font
					(size 0.7 0.7)
					(thickness 0.15)
				)
				(justify left bottom)
			)
		)
		(property "Value" "SW_KMR211NGLFS_SMD"
			(at 0 2.8 90)
			(layer "F.Fab")
			(effects
				(font
					(size 0.7 0.7)
					(thickness 0.15)
				)
				(justify left bottom)
			)
		)
		(property "Datasheet" "http://www.farnell.com/datasheets/2631211.pdf"
			(at 0 0 90)
			(layer "F.Fab")
			(hide yes)
			(effects
				(font
					(size 1.27 1.27)
					(thickness 0.15)
				)
			)
		)
		(property "Author" "Antmicro"
			(at 347.75 -58.15 0)
			(layer "F.Fab")
			(hide yes)
			(effects
				(font
					(size 1 1)
					(thickness 0.15)
				)
			)
		)
		(property "License" "Apache-2.0"
			(at 347.75 -58.15 0)
			(layer "F.Fab")
			(hide yes)
			(effects
				(font
					(size 1 1)
					(thickness 0.15)
				)
			)
		)
		(property "MPN" "KMR211NGLFS"
			(at 347.75 -58.15 0)
			(layer "F.Fab")
			(hide yes)
			(effects
				(font
					(size 1 1)
					(thickness 0.15)
				)
			)
		)
		(property "Manufacturer" "C&K"
			(at 347.75 -58.15 0)
			(layer "F.Fab")
			(hide yes)
			(effects
				(font
					(size 1 1)
					(thickness 0.15)
				)
			)
		)
		(sheetname "/FPGA Config/")
		(sheetfile "fpga-config.kicad_sch")
		(attr smd)
		(fp_line
			(start 2.101 -1.6)
			(end -2.1 -1.6)
			(stroke
				(width 0.15)
				(type solid)
			)
			(layer "F.SilkS")
		)
		(fp_line
			(start -2.1 -1.6)
			(end -2.1 -1.499)
			(stroke
				(width 0.15)
				(type solid)
			)
			(layer "F.SilkS")
		)
		(fp_line
			(start 2.101 -1.58)
			(end 2.101 -1.459)
			(stroke
				(width 0.15)
				(type solid)
			)
			(layer "F.SilkS")
		)
		(fp_line
			(start 2.101 1.601)
			(end 2.101 1.48)
			(stroke
				(width 0.15)
				(type solid)
			)
			(layer "F.SilkS")
		)
		(fp_line
			(start 2.101 1.601)
			(end -2.1 1.601)
			(stroke
				(width 0.15)
				(type solid)
			)
			(layer "F.SilkS")
		)
		(fp_line
			(start -2.1 1.601)
			(end -2.1 1.48)
			(stroke
				(width 0.15)
				(type solid)
			)
			(layer "F.SilkS")
		)
		(fp_rect
			(start 2.751 1.75)
			(end -2.748 -1.749)
			(stroke
				(width 0.05)
				(type solid)
			)
			(fill no)
			(layer "F.CrtYd")
		)
		(fp_line
			(start 2.101 -1.6)
			(end -2.1 -1.6)
			(stroke
				(width 0.15)
				(type solid)
			)
			(layer "F.Fab")
		)
		(fp_line
			(start -2.1 -1.6)
			(end -2.1 1.601)
			(stroke
				(width 0.15)
				(type solid)
			)
			(layer "F.Fab")
		)
		(fp_line
			(start -0.248 -0.8)
			(end 0.25 -0.8)
			(stroke
				(width 0.15)
				(type solid)
			)
			(layer "F.Fab")
		)
		(fp_line
			(start 0.25 0.802)
			(end -0.248 0.802)
			(stroke
				(width 0.15)
				(type solid)
			)
			(layer "F.Fab")
		)
		(fp_line
			(start 2.101 1.601)
			(end 2.101 -1.6)
			(stroke
				(width 0.15)
				(type solid)
			)
			(layer "F.Fab")
		)
		(fp_line
			(start -2.1 1.601)
			(end 2.101 1.601)
			(stroke
				(width 0.15)
				(type solid)
			)
			(layer "F.Fab")
		)
		(fp_arc
			(start 0.25 -0.8)
			(mid 1.051001 0.001)
			(end 0.25 0.802)
			(stroke
				(width 0.15)
				(type solid)
			)
			(layer "F.Fab")
		)
		(fp_arc
			(start -0.248 0.802)
			(mid -1.050001 0.001)
			(end -0.248 -0.8)
			(stroke
				(width 0.15)
				(type solid)
			)
			(layer "F.Fab")
		)
		(pad "1" smd rect
			(at -2.048 -0.8 270)
			(size 0.9 1)
			(layers "F.Cu" "F.Mask" "F.Paste")
			(net 634 "/FPGA Config/PROGRAM_B")
			(pinfunction "1")
			(pintype "passive")
		)
		(pad "2" smd rect
			(at 2.05 -0.8 270)
			(size 0.9 1)
			(layers "F.Cu" "F.Mask" "F.Paste")
			(net 634 "/FPGA Config/PROGRAM_B")
			(pinfunction "2")
			(pintype "passive")
		)
		(pad "3" smd rect
			(at -2.048 0.802 270)
			(size 0.9 1)
			(layers "F.Cu" "F.Mask" "F.Paste")
			(net 1 "GND")
			(pinfunction "3")
			(pintype "passive")
		)
		(pad "4" smd rect
			(at 2.05 0.802 270)
			(size 0.9 1)
			(layers "F.Cu" "F.Mask" "F.Paste")
			(net 1 "GND")
			(pinfunction "4")
			(pintype "passive")
		)
	)
	(footprint "antmicro-footprints:TP_SMD_1mm"
		(layer "F.Cu")
		(at 186.4 164.5845)
		(property "Reference" "TP12"
			(at 0 -0.731898 0)
			(layer "F.SilkS")
			(hide yes)
			(effects
				(font
					(size 0.7 0.7)
					(thickness 0.15)
				)
				(justify left bottom)
			)
		)
		(property "Value" "TP_1mm_SMD"
			(at 0 1.4 0)
			(layer "F.Fab")
			(effects
				(font
					(size 0.7 0.7)
					(thickness 0.15)
				)
				(justify left bottom)
			)
		)
		(property "Author" "Antmicro"
			(at 0 0 0)
			(layer "F.Fab")
			(hide yes)
			(effects
				(font
					(size 1 1)
					(thickness 0.15)
				)
			)
		)
		(property "License" "Apache-2.0"
			(at 0 0 0)
			(layer "F.Fab")
			(hide yes)
			(effects
				(font
					(size 1 1)
					(thickness 0.15)
				)
			)
		)
		(property "MPN" ""
			(at 0 0 0)
			(layer "F.Fab")
			(hide yes)
			(effects
				(font
					(size 1 1)
					(thickness 0.15)
				)
			)
		)
		(property "Manufacturer" ""
			(at 0 0 0)
			(layer "F.Fab")
			(hide yes)
			(effects
				(font
					(size 1 1)
					(thickness 0.15)
				)
			)
		)
		(sheetname "/Supply/")
		(sheetfile "supply.kicad_sch")
		(attr exclude_from_pos_files)
		(pad "1" smd circle
			(at 0 0)
			(size 1 1)
			(layers "F.Cu" "F.Mask")
			(net 201 "+5V")
			(pinfunction "1")
			(pintype "passive")
		)
	)
	(footprint "antmicro-footprints:USON-10_2.5x1mm_P0.5mm"
		(layer "F.Cu")
		(at 82.4 194.1 180)
		(descr "USON-10 2.5x1mm_ Pitch 0.5mm")
		(tags "USON-10 2.5x1mm Pitch 0.5mm")
		(property "Reference" "U10"
			(at 0.018 -1.7 180)
			(layer "F.SilkS")
			(hide yes)
			(effects
				(font
					(size 0.7 0.7)
					(thickness 0.15)
				)
				(justify left bottom)
			)
		)
		(property "Value" "TPD4E05U06QDQARQ1"
			(at 0.018 2.499 180)
			(layer "F.Fab")
			(effects
				(font
					(size 0.7 0.7)
					(thickness 0.15)
				)
				(justify left bottom)
			)
		)
		(property "Datasheet" "https://www.ti.com/lit/ds/symlink/tpd4e05u06-q1.pdf?HQS=dis-mous-null-mousermode-dsf-pf-null-wwe&ts=1663591265741&ref_url=https%253A%252F%252Fwww.mouser.com%252F"
			(at 0 0 180)
			(layer "F.Fab")
			(hide yes)
			(effects
				(font
					(size 1.27 1.27)
					(thickness 0.15)
				)
			)
		)
		(property "Author" "Antmicro"
			(at 164.8 388.2 0)
			(layer "F.Fab")
			(hide yes)
			(effects
				(font
					(size 1 1)
					(thickness 0.15)
				)
			)
		)
		(property "License" "Apache-2.0"
			(at 164.8 388.2 0)
			(layer "F.Fab")
			(hide yes)
			(effects
				(font
					(size 1 1)
					(thickness 0.15)
				)
			)
		)
		(property "MPN" "TPD4E05U06QDQARQ1"
			(at 164.8 388.2 0)
			(layer "F.Fab")
			(hide yes)
			(effects
				(font
					(size 1 1)
					(thickness 0.15)
				)
			)
		)
		(property "Manufacturer" "Texas Instruments"
			(at 164.8 388.2 0)
			(layer "F.Fab")
			(hide yes)
			(effects
				(font
					(size 1 1)
					(thickness 0.15)
				)
			)
		)
		(sheetname "/HDMI + SD Card/")
		(sheetfile "hdmi-sd-card.kicad_sch")
		(attr smd)
		(fp_line
			(start 0.498 1.398)
			(end -0.5 1.398)
			(stroke
				(width 0.15)
				(type solid)
			)
			(layer "F.SilkS")
		)
		(fp_line
			(start 0.498 -1.401)
			(end -0.5 -1.401)
			(stroke
				(width 0.15)
				(type solid)
			)
			(layer "F.SilkS")
		)
		(fp_circle
			(center -0.68 -1.27)
			(end -0.63 -1.27)
			(stroke
				(width 0.15)
				(type solid)
			)
			(fill yes)
			(layer "F.SilkS")
		)
		(fp_rect
			(start -0.8 -1.5)
			(end 0.8 1.499)
			(stroke
				(width 0.05)
				(type solid)
			)
			(fill no)
			(layer "F.CrtYd")
		)
		(fp_line
			(start 0.498 -1.25)
			(end 0.498 1.249)
			(stroke
				(width 0.15)
				(type solid)
			)
			(layer "F.Fab")
		)
		(fp_line
			(start 0.498 -1.25)
			(end -0.25 -1.25)
			(stroke
				(width 0.15)
				(type solid)
			)
			(layer "F.Fab")
		)
		(fp_line
			(start -0.25 -1.25)
			(end -0.5 -1)
			(stroke
				(width 0.15)
				(type solid)
			)
			(layer "F.Fab")
		)
		(fp_line
			(start -0.5 1.249)
			(end 0.498 1.249)
			(stroke
				(width 0.15)
				(type solid)
			)
			(layer "F.Fab")
		)
		(fp_line
			(start -0.5 -1)
			(end -0.5 1.249)
			(stroke
				(width 0.15)
				(type solid)
			)
			(layer "F.Fab")
		)
		(pad "1" smd roundrect
			(at -0.387 -1 90)
			(size 0.25 0.55)
			(layers "F.Cu" "F.Mask" "F.Paste")
			(roundrect_rratio 0.25)
			(net 292 "/HDMI + SD Card/HDMI_CONN_D2_P")
			(pintype "passive")
		)
		(pad "2" smd roundrect
			(at -0.387 -0.5 90)
			(size 0.25 0.55)
			(layers "F.Cu" "F.Mask" "F.Paste")
			(roundrect_rratio 0.25)
			(net 293 "/HDMI + SD Card/HDMI_CONN_D2_N")
			(pintype "passive")
		)
		(pad "3" smd roundrect
			(at -0.387 0 90)
			(size 0.4 0.55)
			(layers "F.Cu" "F.Mask" "F.Paste")
			(roundrect_rratio 0.25)
			(net 1 "GND")
			(pintype "power_in")
		)
		(pad "4" smd roundrect
			(at -0.387 0.498 90)
			(size 0.25 0.55)
			(layers "F.Cu" "F.Mask" "F.Paste")
			(roundrect_rratio 0.25)
			(net 294 "/HDMI + SD Card/HDMI_CONN_D1_P")
			(pintype "passive")
		)
		(pad "5" smd roundrect
			(at -0.387 0.998 90)
			(size 0.25 0.55)
			(layers "F.Cu" "F.Mask" "F.Paste")
			(roundrect_rratio 0.25)
			(net 295 "/HDMI + SD Card/HDMI_CONN_D1_N")
			(pintype "passive")
		)
		(pad "6" smd roundrect
			(at 0.385 0.998 90)
			(size 0.25 0.55)
			(layers "F.Cu" "F.Mask" "F.Paste")
			(roundrect_rratio 0.25)
			(net 295 "/HDMI + SD Card/HDMI_CONN_D1_N")
			(pintype "passive")
		)
		(pad "7" smd roundrect
			(at 0.385 0.498 90)
			(size 0.25 0.55)
			(layers "F.Cu" "F.Mask" "F.Paste")
			(roundrect_rratio 0.25)
			(net 294 "/HDMI + SD Card/HDMI_CONN_D1_P")
			(pintype "passive")
		)
		(pad "8" smd roundrect
			(at 0.385 0 90)
			(size 0.4 0.55)
			(layers "F.Cu" "F.Mask" "F.Paste")
			(roundrect_rratio 0.25)
			(net 1 "GND")
			(pintype "passive")
		)
		(pad "9" smd roundrect
			(at 0.385 -0.5 90)
			(size 0.25 0.55)
			(layers "F.Cu" "F.Mask" "F.Paste")
			(roundrect_rratio 0.25)
			(net 293 "/HDMI + SD Card/HDMI_CONN_D2_N")
			(pintype "passive")
		)
		(pad "10" smd roundrect
			(at 0.385 -1 90)
			(size 0.25 0.55)
			(layers "F.Cu" "F.Mask" "F.Paste")
			(roundrect_rratio 0.25)
			(net 292 "/HDMI + SD Card/HDMI_CONN_D2_P")
			(pintype "passive")
		)
	)
	(footprint "antmicro-footprints:VQFN-16-1EP_3x3mm_P0.5mm_EP1.1x1.1mm"
		(layer "F.Cu")
		(at 182.387107 166.75 -90)
		(descr "VQFN, 16 Pin (https://ww1.microchip.com/downloads/en/DeviceDoc/16L_VQFN-WFS_3x3mm_4MX_C04-00508a.pdf), generated with kicad-footprint-generator ipc_noLead_generator.py")
		(tags "VQFN NoLead")
		(property "Reference" "U30"
			(at 3.35 -0.012893 0)
			(layer "F.SilkS")
			(effects
				(font
					(size 0.7 0.7)
					(thickness 0.15)
				)
				(justify left bottom)
			)
		)
		(property "Value" "PAC1954T-E_VQFN"
			(at 0 2.797 270)
			(layer "F.Fab")
			(effects
				(font
					(size 0.7 0.7)
					(thickness 0.15)
				)
				(justify left bottom)
			)
		)
		(property "Datasheet" "https://ww1.microchip.com/downloads/aemDocuments/documents/MSLD/ProductDocuments/DataSheets/PAC195X-Family-Data-Sheet-DS20006539.pdf"
			(at 0 0 270)
			(layer "F.Fab")
			(hide yes)
			(effects
				(font
					(size 1.27 1.27)
					(thickness 0.15)
				)
			)
		)
		(property "Author" "Antmicro"
			(at 15.637107 349.137107 0)
			(layer "F.Fab")
			(hide yes)
			(effects
				(font
					(size 1 1)
					(thickness 0.15)
				)
			)
		)
		(property "License" "Apache-2.0"
			(at 15.637107 349.137107 0)
			(layer "F.Fab")
			(hide yes)
			(effects
				(font
					(size 1 1)
					(thickness 0.15)
				)
			)
		)
		(property "MPN" "PAC1954T-E/4MX"
			(at 15.637107 349.137107 0)
			(layer "F.Fab")
			(hide yes)
			(effects
				(font
					(size 1 1)
					(thickness 0.15)
				)
			)
		)
		(property "Manufacturer" "Microchip Technology"
			(at 15.637107 349.137107 0)
			(layer "F.Fab")
			(hide yes)
			(effects
				(font
					(size 1 1)
					(thickness 0.15)
				)
			)
		)
		(property ki_fp_filters "UQFN*1EP*4x4mm*P0.65mm*")
		(sheetname "/Supply/")
		(sheetfile "supply.kicad_sch")
		(attr smd)
		(fp_line
			(start -1.611 1.61)
			(end -1.611 1.134)
			(stroke
				(width 0.15)
				(type solid)
			)
			(layer "F.SilkS")
		)
		(fp_line
			(start -1.135 1.61)
			(end -1.611 1.61)
			(stroke
				(width 0.15)
				(type solid)
			)
			(layer "F.SilkS")
		)
		(fp_line
			(start 1.134 1.61)
			(end 1.61 1.61)
			(stroke
				(width 0.15)
				(type solid)
			)
			(layer "F.SilkS")
		)
		(fp_line
			(start 1.61 1.61)
			(end 1.61 1.134)
			(stroke
				(width 0.15)
				(type solid)
			)
			(layer "F.SilkS")
		)
		(fp_line
			(start -1.135 -1.611)
			(end -1.611 -1.611)
			(stroke
				(width 0.15)
				(type solid)
			)
			(layer "F.SilkS")
		)
		(fp_line
			(start 1.134 -1.611)
			(end 1.61 -1.611)
			(stroke
				(width 0.15)
				(type solid)
			)
			(layer "F.SilkS")
		)
		(fp_line
			(start 1.61 -1.611)
			(end 1.61 -1.135)
			(stroke
				(width 0.15)
				(type solid)
			)
			(layer "F.SilkS")
		)
		(fp_circle
			(center -2.3 -0.75)
			(end -2.25 -0.75)
			(stroke
				(width 0.15)
				(type solid)
			)
			(fill yes)
			(layer "F.SilkS")
		)
		(fp_rect
			(start -2 -2)
			(end 1.999 1.999)
			(stroke
				(width 0.05)
				(type solid)
			)
			(fill no)
			(layer "F.CrtYd")
		)
		(fp_line
			(start -1.5 1.499)
			(end -1.5 -0.75)
			(stroke
				(width 0.15)
				(type solid)
			)
			(layer "F.Fab")
		)
		(fp_line
			(start 1.499 1.499)
			(end -1.5 1.499)
			(stroke
				(width 0.15)
				(type solid)
			)
			(layer "F.Fab")
		)
		(fp_line
			(start -1.5 -0.75)
			(end -0.75 -1.5)
			(stroke
				(width 0.15)
				(type solid)
			)
			(layer "F.Fab")
		)
		(fp_line
			(start -0.75 -1.5)
			(end 1.499 -1.5)
			(stroke
				(width 0.15)
				(type solid)
			)
			(layer "F.Fab")
		)
		(fp_line
			(start 1.499 -1.5)
			(end 1.499 1.499)
			(stroke
				(width 0.15)
				(type solid)
			)
			(layer "F.Fab")
		)
		(fp_circle
			(center -2.3 -0.75)
			(end -2.25 -0.75)
			(stroke
				(width 0.15)
				(type solid)
			)
			(fill yes)
			(layer "F.Fab")
		)
		(pad "" smd roundrect
			(at 0 0 270)
			(size 0.89 0.89)
			(layers "F.Paste")
			(roundrect_rratio 0.25)
		)
		(pad "1" smd roundrect
			(at -1.464 -0.75 270)
			(size 0.775 0.25)
			(layers "F.Cu" "F.Mask" "F.Paste")
			(roundrect_rratio 0.25)
			(net 1 "GND")
			(pinfunction "SLOW/~{ALERT1}")
			(pintype "bidirectional")
		)
		(pad "2" smd roundrect
			(at -1.464 -0.25 270)
			(size 0.775 0.25)
			(layers "F.Cu" "F.Mask" "F.Paste")
			(roundrect_rratio 0.25)
			(net 200 "+3V3")
			(pinfunction "VDD")
			(pintype "power_in")
		)
		(pad "3" smd roundrect
			(at -1.464 0.247 270)
			(size 0.775 0.25)
			(layers "F.Cu" "F.Mask" "F.Paste")
			(roundrect_rratio 0.25)
			(net 1 "GND")
			(pinfunction "GND")
			(pintype "power_in")
		)
		(pad "4" smd roundrect
			(at -1.464 0.747 270)
			(size 0.775 0.25)
			(layers "F.Cu" "F.Mask" "F.Paste")
			(roundrect_rratio 0.25)
			(net 297 "/Supply/PWR_SCL_2")
			(pinfunction "SCL")
			(pintype "input")
		)
		(pad "5" smd roundrect
			(at -0.75 1.461 270)
			(size 0.25 0.775)
			(layers "F.Cu" "F.Mask" "F.Paste")
			(roundrect_rratio 0.25)
			(net 298 "/Supply/PWR_SDA_2")
			(pinfunction "SDA")
			(pintype "bidirectional")
		)
		(pad "6" smd roundrect
			(at -0.25 1.461 270)
			(size 0.25 0.775)
			(layers "F.Cu" "F.Mask" "F.Paste")
			(roundrect_rratio 0.25)
			(net 1 "GND")
			(pinfunction "ADDRSEL")
			(pintype "bidirectional")
		)
		(pad "7" smd roundrect
			(at 0.247 1.461 270)
			(size 0.25 0.775)
			(layers "F.Cu" "F.Mask" "F.Paste")
			(roundrect_rratio 0.25)
			(net 175 "/Supply/1V1_SEN_-")
			(pinfunction "IN3-")
			(pintype "input")
		)
		(pad "8" smd roundrect
			(at 0.747 1.461 270)
			(size 0.25 0.775)
			(layers "F.Cu" "F.Mask" "F.Paste")
			(roundrect_rratio 0.25)
			(net 142 "/Supply/1V1_SEN_+")
			(pinfunction "IN3+")
			(pintype "input")
		)
		(pad "9" smd roundrect
			(at 1.461 0.747 270)
			(size 0.775 0.25)
			(layers "F.Cu" "F.Mask" "F.Paste")
			(roundrect_rratio 0.25)
			(net 144 "/Supply/1V2_SEN_-")
			(pinfunction "IN4-")
			(pintype "input")
		)
		(pad "10" smd roundrect
			(at 1.461 0.247 270)
			(size 0.775 0.25)
			(layers "F.Cu" "F.Mask" "F.Paste")
			(roundrect_rratio 0.25)
			(net 90 "/Supply/1V2_SEN_+")
			(pinfunction "IN4+")
			(pintype "input")
		)
		(pad "11" smd roundrect
			(at 1.461 -0.25 270)
			(size 0.775 0.25)
			(layers "F.Cu" "F.Mask" "F.Paste")
			(roundrect_rratio 0.25)
			(net 243 "/Supply/3V3_SEN_+")
			(pinfunction "IN1+")
			(pintype "input")
		)
		(pad "12" smd roundrect
			(at 1.461 -0.75 270)
			(size 0.775 0.25)
			(layers "F.Cu" "F.Mask" "F.Paste")
			(roundrect_rratio 0.25)
			(net 245 "/Supply/3V3_SEN_-")
			(pinfunction "IN1-")
			(pintype "input")
		)
		(pad "13" smd roundrect
			(at 0.747 -1.464 270)
			(size 0.25 0.775)
			(layers "F.Cu" "F.Mask" "F.Paste")
			(roundrect_rratio 0.25)
			(net 141 "/Supply/5V_SEN_+")
			(pinfunction "IN2+")
			(pintype "input")
		)
		(pad "14" smd roundrect
			(at 0.247 -1.464 270)
			(size 0.25 0.775)
			(layers "F.Cu" "F.Mask" "F.Paste")
			(roundrect_rratio 0.25)
			(net 146 "/Supply/5V_SEN_-")
			(pinfunction "IN2-")
			(pintype "input")
		)
		(pad "15" smd roundrect
			(at -0.25 -1.464 270)
			(size 0.25 0.775)
			(layers "F.Cu" "F.Mask" "F.Paste")
			(roundrect_rratio 0.25)
			(net 1 "GND")
			(pinfunction "GPIO/~{ALERT2}")
			(pintype "bidirectional")
		)
		(pad "16" smd roundrect
			(at -0.75 -1.464 270)
			(size 0.25 0.775)
			(layers "F.Cu" "F.Mask" "F.Paste")
			(roundrect_rratio 0.25)
			(net 386 "Net-(U30-~{PWRDN})")
			(pinfunction "~{PWRDN}")
			(pintype "input")
		)
		(pad "17" smd rect
			(at 0 0 270)
			(size 1.1 1.1)
			(layers "F.Cu" "F.Mask")
			(net 743 "unconnected-(U30-EP-Pad17)")
			(pinfunction "EP")
			(pintype "no_connect")
		)
	)
	(footprint "antmicro-footprints:C_0402_1005Metric"
		(layer "F.Cu")
		(at 183.541 148.650001)
		(descr "Capacitor SMD 0402")
		(tags "capacitor SMD 0402")
		(property "Reference" "C205"
			(at 0 -0.699 0)
			(layer "F.SilkS")
			(hide yes)
			(effects
				(font
					(size 0.7 0.7)
					(thickness 0.15)
				)
				(justify left bottom)
			)
		)
		(property "Value" "C_100n_0402"
			(at -1.022927 2.155213 0)
			(layer "F.Fab")
			(effects
				(font
					(size 0.7 0.7)
					(thickness 0.15)
				)
				(justify left bottom)
			)
		)
		(property "Datasheet" "https://www.murata.com/products/productdetail?partno=GRM155R61H104KE14%23"
			(at 0 0 0)
			(layer "F.Fab")
			(hide yes)
			(effects
				(font
					(size 1.27 1.27)
					(thickness 0.15)
				)
			)
		)
		(property "Author" "Antmicro"
			(at 0 0 0)
			(layer "F.Fab")
			(hide yes)
			(effects
				(font
					(size 1 1)
					(thickness 0.15)
				)
			)
		)
		(property "Dielectric" "X5R"
			(at 0 0 0)
			(layer "F.Fab")
			(hide yes)
			(effects
				(font
					(size 1 1)
					(thickness 0.15)
				)
			)
		)
		(property "License" "Apache-2.0"
			(at 0 0 0)
			(layer "F.Fab")
			(hide yes)
			(effects
				(font
					(size 1 1)
					(thickness 0.15)
				)
			)
		)
		(property "MPN" "GRM155R61H104KE14D"
			(at 0 0 0)
			(layer "F.Fab")
			(hide yes)
			(effects
				(font
					(size 1 1)
					(thickness 0.15)
				)
			)
		)
		(property "Manufacturer" "Murata"
			(at 0 0 0)
			(layer "F.Fab")
			(hide yes)
			(effects
				(font
					(size 1 1)
					(thickness 0.15)
				)
			)
		)
		(property "Val" "100n"
			(at 0 0 0)
			(layer "F.Fab")
			(hide yes)
			(effects
				(font
					(size 1 1)
					(thickness 0.15)
				)
			)
		)
		(property "Voltage" "50V"
			(at 0 0 0)
			(layer "F.Fab")
			(hide yes)
			(effects
				(font
					(size 1 1)
					(thickness 0.15)
				)
			)
		)
		(sheetname "/Supply/")
		(sheetfile "supply.kicad_sch")
		(attr smd)
		(fp_rect
			(start -0.9659 -0.481258)
			(end 0.9649 0.458742)
			(stroke
				(width 0.05)
				(type solid)
			)
			(fill no)
			(layer "F.CrtYd")
		)
		(fp_line
			(start -0.499 -0.25)
			(end 0.499 -0.25)
			(stroke
				(width 0.15)
				(type solid)
			)
			(layer "F.Fab")
		)
		(fp_line
			(start -0.499 0.248)
			(end -0.499 -0.25)
			(stroke
				(width 0.15)
				(type solid)
			)
			(layer "F.Fab")
		)
		(fp_line
			(start 0.499 -0.25)
			(end 0.499 0.248)
			(stroke
				(width 0.15)
				(type solid)
			)
			(layer "F.Fab")
		)
		(fp_line
			(start 0.499 0.248)
			(end -0.499 0.248)
			(stroke
				(width 0.15)
				(type solid)
			)
			(layer "F.Fab")
		)
		(pad "1" smd roundrect
			(at -0.484 0)
			(size 0.59 0.64)
			(layers "F.Cu" "F.Mask" "F.Paste")
			(roundrect_rratio 0.25)
			(net 1 "GND")
			(pintype "passive")
		)
		(pad "2" smd roundrect
			(at 0.484 0)
			(size 0.59 0.64)
			(layers "F.Cu" "F.Mask" "F.Paste")
			(roundrect_rratio 0.25)
			(net 200 "+3V3")
			(pintype "passive")
		)
	)
	(footprint "antmicro-footprints:X1QFN-16-1EP_2.5x2.5mm"
		(layer "F.Cu")
		(at 95.299 191.85)
		(property "Reference" "U9"
			(at 1.651 1.85 0)
			(unlocked yes)
			(layer "F.SilkS")
			(effects
				(font
					(size 0.7 0.7)
					(thickness 0.15)
				)
				(justify left bottom)
			)
		)
		(property "Value" "SN74HC595B"
			(at -6.9 2.69 0)
			(unlocked yes)
			(layer "F.Fab")
			(effects
				(font
					(size 0.7 0.7)
					(thickness 0.15)
				)
				(justify left bottom)
			)
		)
		(property "Datasheet" "https://www.ti.com/general/docs/suppproductinfo.tsp?distId=26&gotoUrl=https://www.ti.com/lit/gpn/sn74hc595b"
			(at 0 0 0)
			(layer "F.Fab")
			(hide yes)
			(effects
				(font
					(size 1.27 1.27)
					(thickness 0.15)
				)
			)
		)
		(property "Author" "Antmicro"
			(at 0 0 0)
			(layer "F.Fab")
			(hide yes)
			(effects
				(font
					(size 1 1)
					(thickness 0.15)
				)
			)
		)
		(property "License" "Apache-2.0"
			(at 0 0 0)
			(layer "F.Fab")
			(hide yes)
			(effects
				(font
					(size 1 1)
					(thickness 0.15)
				)
			)
		)
		(property "MPN" "SN74HC595BRWNR"
			(at 0 0 0)
			(layer "F.Fab")
			(hide yes)
			(effects
				(font
					(size 1 1)
					(thickness 0.15)
				)
			)
		)
		(property "Manufacturer" "Texas Instruments"
			(at 0 0 0)
			(layer "F.Fab")
			(hide yes)
			(effects
				(font
					(size 1 1)
					(thickness 0.15)
				)
			)
		)
		(sheetname "/Debug FTDI/")
		(sheetfile "debug-ftdi.kicad_sch")
		(attr smd)
		(fp_line
			(start -1.351 -1.351)
			(end -0.803 -1.351)
			(stroke
				(width 0.15)
				(type solid)
			)
			(layer "F.SilkS")
		)
		(fp_line
			(start -1.351 1.35)
			(end -1.351 0.8)
			(stroke
				(width 0.15)
				(type solid)
			)
			(layer "F.SilkS")
		)
		(fp_line
			(start -0.803 1.35)
			(end -1.351 1.35)
			(stroke
				(width 0.15)
				(type solid)
			)
			(layer "F.SilkS")
		)
		(fp_line
			(start 0.8 -1.351)
			(end 1.35 -1.351)
			(stroke
				(width 0.15)
				(type solid)
			)
			(layer "F.SilkS")
		)
		(fp_line
			(start 1.35 -1.351)
			(end 1.35 -0.803)
			(stroke
				(width 0.15)
				(type solid)
			)
			(layer "F.SilkS")
		)
		(fp_line
			(start 1.35 0.8)
			(end 1.35 1.35)
			(stroke
				(width 0.15)
				(type solid)
			)
			(layer "F.SilkS")
		)
		(fp_line
			(start 1.35 1.35)
			(end 0.8 1.35)
			(stroke
				(width 0.15)
				(type solid)
			)
			(layer "F.SilkS")
		)
		(fp_circle
			(center -1.752 -0.6)
			(end -1.702 -0.6)
			(stroke
				(width 0.15)
				(type solid)
			)
			(fill yes)
			(layer "F.SilkS")
		)
		(fp_rect
			(start -1.75 -1.75)
			(end 1.749 1.749)
			(stroke
				(width 0.05)
				(type solid)
			)
			(fill no)
			(layer "F.CrtYd")
		)
		(fp_line
			(start -1.25 -1.05)
			(end -1.05 -1.25)
			(stroke
				(width 0.15)
				(type solid)
			)
			(layer "F.Fab")
		)
		(fp_rect
			(start -1.25 -1.25)
			(end 1.249 1.249)
			(stroke
				(width 0.15)
				(type solid)
			)
			(fill no)
			(layer "F.Fab")
		)
		(pad "1" smd roundrect
			(at -1.151 -0.6)
			(size 0.6 0.2)
			(layers "F.Cu" "F.Mask" "F.Paste")
			(roundrect_rratio 0.25)
			(net 712 "unconnected-(U9-QB-Pad1)")
			(pinfunction "QB")
			(pintype "output+no_connect")
		)
		(pad "2" smd roundrect
			(at -1.151 -0.203)
			(size 0.6 0.2)
			(layers "F.Cu" "F.Mask" "F.Paste")
			(roundrect_rratio 0.25)
			(net 713 "unconnected-(U9-QC-Pad2)")
			(pinfunction "QC")
			(pintype "output+no_connect")
		)
		(pad "3" smd roundrect
			(at -1.151 0.2)
			(size 0.6 0.2)
			(layers "F.Cu" "F.Mask" "F.Paste")
			(roundrect_rratio 0.25)
			(net 714 "unconnected-(U9-QD-Pad3)")
			(pinfunction "QD")
			(pintype "output+no_connect")
		)
		(pad "4" smd roundrect
			(at -1.151 0.597)
			(size 0.6 0.2)
			(layers "F.Cu" "F.Mask" "F.Paste")
			(roundrect_rratio 0.25)
			(net 656 "/Debug FTDI/LED_TX0")
			(pinfunction "QE")
			(pintype "output")
		)
		(pad "5" smd roundrect
			(at -0.6 1.148 90)
			(size 0.6 0.2)
			(layers "F.Cu" "F.Mask" "F.Paste")
			(roundrect_rratio 0.25)
			(net 657 "/Debug FTDI/LED_RX0")
			(pinfunction "QF")
			(pintype "output")
		)
		(pad "6" smd roundrect
			(at -0.203 1.148 90)
			(size 0.6 0.2)
			(layers "F.Cu" "F.Mask" "F.Paste")
			(roundrect_rratio 0.25)
			(net 658 "/Debug FTDI/LED_TX1")
			(pinfunction "QG")
			(pintype "output")
		)
		(pad "7" smd roundrect
			(at 0.2 1.148 90)
			(size 0.6 0.2)
			(layers "F.Cu" "F.Mask" "F.Paste")
			(roundrect_rratio 0.25)
			(net 659 "/Debug FTDI/LED_RX1")
			(pinfunction "QH")
			(pintype "output")
		)
		(pad "8" smd roundrect
			(at 0.597 1.148 90)
			(size 0.6 0.2)
			(layers "F.Cu" "F.Mask" "F.Paste")
			(roundrect_rratio 0.25)
			(net 1 "GND")
			(pinfunction "GND")
			(pintype "power_in")
		)
		(pad "9" smd roundrect
			(at 1.148 0.597)
			(size 0.6 0.2)
			(layers "F.Cu" "F.Mask" "F.Paste")
			(roundrect_rratio 0.25)
			(net 755 "unconnected-(U9-QH&apos;-Pad9)")
			(pinfunction "QH'")
			(pintype "output+no_connect")
		)
		(pad "10" smd roundrect
			(at 1.148 0.2)
			(size 0.6 0.2)
			(layers "F.Cu" "F.Mask" "F.Paste")
			(roundrect_rratio 0.25)
			(net 6 "/Debug FTDI/FTDI_3V3")
			(pinfunction "~{SRCLR}")
			(pintype "input")
		)
		(pad "11" smd roundrect
			(at 1.148 -0.203)
			(size 0.6 0.2)
			(layers "F.Cu" "F.Mask" "F.Paste")
			(roundrect_rratio 0.25)
			(net 745 "/Debug FTDI/FTDI_EECLK")
			(pinfunction "SRCLK")
			(pintype "input")
		)
		(pad "12" smd roundrect
			(at 1.148 -0.6)
			(size 0.6 0.2)
			(layers "F.Cu" "F.Mask" "F.Paste")
			(roundrect_rratio 0.25)
			(net 738 "/Debug FTDI/FTDI_EECS")
			(pinfunction "RCLK")
			(pintype "input")
		)
		(pad "13" smd roundrect
			(at 0.597 -1.151 90)
			(size 0.6 0.2)
			(layers "F.Cu" "F.Mask" "F.Paste")
			(roundrect_rratio 0.25)
			(net 668 "/Debug FTDI/FTDI_PWREN")
			(pinfunction "~{OE}")
			(pintype "input")
		)
		(pad "14" smd roundrect
			(at 0.2 -1.151 90)
			(size 0.6 0.2)
			(layers "F.Cu" "F.Mask" "F.Paste")
			(roundrect_rratio 0.25)
			(net 744 "/Debug FTDI/FTDI_EEDAT")
			(pinfunction "SER")
			(pintype "input")
		)
		(pad "15" smd roundrect
			(at -0.203 -1.151 90)
			(size 0.6 0.2)
			(layers "F.Cu" "F.Mask" "F.Paste")
			(roundrect_rratio 0.25)
			(net 716 "unconnected-(U9-QA-Pad15)")
			(pinfunction "QA")
			(pintype "output+no_connect")
		)
		(pad "16" smd roundrect
			(at -0.6 -1.151 90)
			(size 0.6 0.2)
			(layers "F.Cu" "F.Mask" "F.Paste")
			(roundrect_rratio 0.25)
			(net 6 "/Debug FTDI/FTDI_3V3")
			(pinfunction "VCC")
			(pintype "power_in")
		)
		(pad "17" smd roundrect
			(at 0 0 90)
			(size 1.2 1.2)
			(layers "F.Cu" "F.Mask" "F.Paste")
			(roundrect_rratio 0.04166666667)
			(net 717 "unconnected-(U9-EP-Pad17)")
			(pinfunction "EP")
			(pintype "no_connect")
		)
	)
	(footprint "antmicro-footprints:C_0805_2012Metric"
		(layer "F.Cu")
		(at 203.331001 166.922 90)
		(descr "Capacitor SMD 0805")
		(tags "capacitor SMD 0805")
		(property "Reference" "C178"
			(at -2.10551 -1.198678 90)
			(layer "F.SilkS")
			(hide yes)
			(effects
				(font
					(size 0.7 0.7)
					(thickness 0.15)
				)
				(justify left bottom)
			)
		)
		(property "Value" "C_22u_25V_0805"
			(at -2.055717 1.963152 90)
			(layer "F.Fab")
			(effects
				(font
					(size 0.7 0.7)
					(thickness 0.15)
				)
				(justify left bottom)
			)
		)
		(property "Datasheet" "https://product.samsungsem.com/mlcc/CL21A226MAYNNN.do"
			(at 0 0 90)
			(layer "F.Fab")
			(hide yes)
			(effects
				(font
					(size 1.27 1.27)
					(thickness 0.15)
				)
			)
		)
		(property "Author" "Antmicro"
			(at 370.253001 -36.409001 0)
			(layer "F.Fab")
			(hide yes)
			(effects
				(font
					(size 1 1)
					(thickness 0.15)
				)
			)
		)
		(property "Dielectric" ""
			(at 370.253001 -36.409001 0)
			(layer "F.Fab")
			(hide yes)
			(effects
				(font
					(size 1 1)
					(thickness 0.15)
				)
			)
		)
		(property "License" "Apache-2.0"
			(at 370.253001 -36.409001 0)
			(layer "F.Fab")
			(hide yes)
			(effects
				(font
					(size 1 1)
					(thickness 0.15)
				)
			)
		)
		(property "MPN" "CL21A226MAYNNNE"
			(at 370.253001 -36.409001 0)
			(layer "F.Fab")
			(hide yes)
			(effects
				(font
					(size 1 1)
					(thickness 0.15)
				)
			)
		)
		(property "Manufacturer" "Samsung Electro-Mechanics"
			(at 370.253001 -36.409001 0)
			(layer "F.Fab")
			(hide yes)
			(effects
				(font
					(size 1 1)
					(thickness 0.15)
				)
			)
		)
		(property "Val" "22u_25V"
			(at 370.253001 -36.409001 0)
			(layer "F.Fab")
			(hide yes)
			(effects
				(font
					(size 1 1)
					(thickness 0.15)
				)
			)
		)
		(property "Voltage" ""
			(at 370.253001 -36.409001 0)
			(layer "F.Fab")
			(hide yes)
			(effects
				(font
					(size 1 1)
					(thickness 0.15)
				)
			)
		)
		(sheetname "/Supply/")
		(sheetfile "supply.kicad_sch")
		(attr smd)
		(fp_line
			(start -0.3 -0.8)
			(end 0.3 -0.8)
			(stroke
				(width 0.15)
				(type solid)
			)
			(layer "F.SilkS")
		)
		(fp_line
			(start -0.3 0.8)
			(end 0.3 0.8)
			(stroke
				(width 0.15)
				(type solid)
			)
			(layer "F.SilkS")
		)
		(fp_rect
			(start -1.9 -0.93)
			(end 1.9 0.93)
			(stroke
				(width 0.05)
				(type solid)
			)
			(fill no)
			(layer "F.CrtYd")
		)
		(fp_rect
			(start -0.95 -0.675)
			(end 0.95 0.675)
			(stroke
				(width 0.15)
				(type solid)
			)
			(fill no)
			(layer "F.Fab")
		)
		(pad "1" smd rect
			(at -1.05 0 90)
			(size 1.2 1.2)
			(layers "F.Cu" "F.Mask" "F.Paste")
			(net 1 "GND")
			(pintype "passive")
		)
		(pad "2" smd rect
			(at 1.05 0 90)
			(size 1.2 1.2)
			(layers "F.Cu" "F.Mask" "F.Paste")
			(net 38 "VDC")
			(pintype "passive")
		)
	)
	(footprint "antmicro-footprints:LED_0603_1608Metric_G"
		(layer "F.Cu")
		(at 94.3 197.1 -90)
		(descr "LED SMD 0603 Green")
		(tags "LED SMD 0603 Green")
		(property "Reference" "D11"
			(at -0.001 -0.901 270)
			(layer "F.SilkS")
			(hide yes)
			(effects
				(font
					(size 0.7 0.7)
					(thickness 0.15)
				)
				(justify left bottom)
			)
		)
		(property "Value" "LED_G_0603_KP-1608CGCK"
			(at -0.001 1.599 270)
			(layer "F.Fab")
			(effects
				(font
					(size 0.7 0.7)
					(thickness 0.15)
				)
				(justify left bottom)
			)
		)
		(property "Datasheet" "http://www.farnell.com/datasheets/2045956.pdf"
			(at 0 0 270)
			(layer "F.Fab")
			(hide yes)
			(effects
				(font
					(size 1.27 1.27)
					(thickness 0.15)
				)
			)
		)
		(property "Author" "Antmicro"
			(at -102.8 291.4 0)
			(layer "F.Fab")
			(hide yes)
			(effects
				(font
					(size 1 1)
					(thickness 0.15)
				)
			)
		)
		(property "License" "Apache-2.0"
			(at -102.8 291.4 0)
			(layer "F.Fab")
			(hide yes)
			(effects
				(font
					(size 1 1)
					(thickness 0.15)
				)
			)
		)
		(property "MPN" "KP-1608CGCK"
			(at -102.8 291.4 0)
			(layer "F.Fab")
			(hide yes)
			(effects
				(font
					(size 1 1)
					(thickness 0.15)
				)
			)
		)
		(property "Manufacturer" "Kingbright"
			(at -102.8 291.4 0)
			(layer "F.Fab")
			(hide yes)
			(effects
				(font
					(size 1 1)
					(thickness 0.15)
				)
			)
		)
		(sheetname "/Debug FTDI/")
		(sheetfile "debug-ftdi.kicad_sch")
		(attr smd)
		(fp_line
			(start -0.271 0.348)
			(end 0.269 0.348)
			(stroke
				(width 0.15)
				(type solid)
			)
			(layer "F.SilkS")
		)
		(fp_line
			(start 1.249 0.319)
			(end 1.249 -0.321)
			(stroke
				(width 0.15)
				(type solid)
			)
			(layer "F.SilkS")
		)
		(fp_line
			(start -0.107 -0.001)
			(end -0.291 -0.001)
			(stroke
				(width 0.1)
				(type solid)
			)
			(layer "F.SilkS")
		)
		(fp_line
			(start 0.092 -0.001)
			(end -0.107 0.198)
			(stroke
				(width 0.1)
				(type solid)
			)
			(layer "F.SilkS")
		)
		(fp_line
			(start 0.092 -0.001)
			(end 0.292 -0.001)
			(stroke
				(width 0.1)
				(type solid)
			)
			(layer "F.SilkS")
		)
		(fp_line
			(start -0.107 -0.201)
			(end -0.107 0.198)
			(stroke
				(width 0.1)
				(type solid)
			)
			(layer "F.SilkS")
		)
		(fp_line
			(start -0.107 -0.201)
			(end 0.092 -0.001)
			(stroke
				(width 0.1)
				(type solid)
			)
			(layer "F.SilkS")
		)
		(fp_line
			(start 0.092 -0.201)
			(end 0.092 0.198)
			(stroke
				(width 0.1)
				(type solid)
			)
			(layer "F.SilkS")
		)
		(fp_line
			(start -0.271 -0.349)
			(end 0.269 -0.349)
			(stroke
				(width 0.15)
				(type solid)
			)
			(layer "F.SilkS")
		)
		(fp_rect
			(start -1.2192 -0.6096)
			(end 1.27 0.6016)
			(stroke
				(width 0.05)
				(type solid)
			)
			(fill no)
			(layer "F.CrtYd")
		)
		(fp_line
			(start -0.202 0.201)
			(end 0.1 -0.001)
			(stroke
				(width 0.15)
				(type solid)
			)
			(layer "F.Fab")
		)
		(fp_line
			(start 0.198 0.201)
			(end 0.198 -0.101)
			(stroke
				(width 0.15)
				(type solid)
			)
			(layer "F.Fab")
		)
		(fp_line
			(start -0.849 0.025)
			(end -0.442 0.381)
			(stroke
				(width 0.15)
				(type solid)
			)
			(layer "F.Fab")
		)
		(fp_line
			(start -0.6 -0.001)
			(end -0.202 -0.001)
			(stroke
				(width 0.15)
				(type solid)
			)
			(layer "F.Fab")
		)
		(fp_line
			(start -0.202 -0.001)
			(end -0.202 0.201)
			(stroke
				(width 0.15)
				(type solid)
			)
			(layer "F.Fab")
		)
		(fp_line
			(start 0.1 -0.001)
			(end -0.202 -0.201)
			(stroke
				(width 0.15)
				(type solid)
			)
			(layer "F.Fab")
		)
		(fp_line
			(start 0.198 -0.001)
			(end 0.596 -0.001)
			(stroke
				(width 0.15)
				(type solid)
			)
			(layer "F.Fab")
		)
		(fp_line
			(start -0.202 -0.201)
			(end -0.202 -0.001)
			(stroke
				(width 0.15)
				(type solid)
			)
			(layer "F.Fab")
		)
		(fp_line
			(start 0.198 -0.201)
			(end 0.198 -0.101)
			(stroke
				(width 0.15)
				(type solid)
			)
			(layer "F.Fab")
		)
		(fp_rect
			(start -0.849 -0.401)
			(end 0.849 0.401)
			(stroke
				(width 0.15)
				(type solid)
			)
			(fill no)
			(layer "F.Fab")
		)
		(pad "1" smd rect
			(at -0.751 -0.001 90)
			(size 0.8 0.8)
			(layers "F.Cu" "F.Mask" "F.Paste")
			(net 316 "Net-(D11-Pad1)")
			(pinfunction "1")
			(pintype "passive")
		)
		(pad "2" smd rect
			(at 0.749 -0.001 90)
			(size 0.8 0.8)
			(layers "F.Cu" "F.Mask" "F.Paste")
			(net 1 "GND")
			(pinfunction "2")
			(pintype "passive")
		)
	)
	(footprint "antmicro-footprints:R_0402_1005Metric"
		(layer "F.Cu")
		(at 97.9 194.815 90)
		(descr "Resistor SMD 0402")
		(tags "resistor SMD 0402")
		(property "Reference" "R67"
			(at -1.122484 -0.772697 90)
			(layer "F.SilkS")
			(hide yes)
			(effects
				(font
					(size 0.7 0.7)
					(thickness 0.15)
				)
				(justify left bottom)
			)
		)
		(property "Value" "R_330R_0402"
			(at -1.011843 1.772047 90)
			(layer "F.Fab")
			(effects
				(font
					(size 0.7 0.7)
					(thickness 0.15)
				)
				(justify left bottom)
			)
		)
		(property "Datasheet" "https://www.bourns.com/docs/product-datasheets/cr.pdf"
			(at 0 0 90)
			(layer "F.Fab")
			(hide yes)
			(effects
				(font
					(size 1.27 1.27)
					(thickness 0.15)
				)
			)
		)
		(property "Author" "Antmicro"
			(at 292.715 96.915 0)
			(layer "F.Fab")
			(hide yes)
			(effects
				(font
					(size 1 1)
					(thickness 0.15)
				)
			)
		)
		(property "License" "Apache-2.0"
			(at 292.715 96.915 0)
			(layer "F.Fab")
			(hide yes)
			(effects
				(font
					(size 1 1)
					(thickness 0.15)
				)
			)
		)
		(property "MPN" "CR0402-FX-3300GLF"
			(at 292.715 96.915 0)
			(layer "F.Fab")
			(hide yes)
			(effects
				(font
					(size 1 1)
					(thickness 0.15)
				)
			)
		)
		(property "Manufacturer" "Bourns"
			(at 292.715 96.915 0)
			(layer "F.Fab")
			(hide yes)
			(effects
				(font
					(size 1 1)
					(thickness 0.15)
				)
			)
		)
		(property "Tolerance" "1%"
			(at 292.715 96.915 0)
			(layer "F.Fab")
			(hide yes)
			(effects
				(font
					(size 1 1)
					(thickness 0.15)
				)
			)
		)
		(property "Val" "330R"
			(at 292.715 96.915 0)
			(layer "F.Fab")
			(hide yes)
			(effects
				(font
					(size 1 1)
					(thickness 0.15)
				)
			)
		)
		(sheetname "/Debug FTDI/")
		(sheetfile "debug-ftdi.kicad_sch")
		(attr smd)
		(fp_rect
			(start -0.93 -0.47)
			(end 0.93 0.47)
			(stroke
				(width 0.05)
				(type solid)
			)
			(fill no)
			(layer "F.CrtYd")
		)
		(fp_rect
			(start -0.5 -0.25)
			(end 0.5 0.25)
			(stroke
				(width 0.15)
				(type solid)
			)
			(fill no)
			(layer "F.Fab")
		)
		(pad "1" smd roundrect
			(at -0.485 0 90)
			(size 0.59 0.64)
			(layers "F.Cu" "F.Mask" "F.Paste")
			(roundrect_rratio 0.25)
			(net 318 "Net-(D13-Pad1)")
			(pintype "passive")
		)
		(pad "2" smd roundrect
			(at 0.485 0 90)
			(size 0.59 0.64)
			(layers "F.Cu" "F.Mask" "F.Paste")
			(roundrect_rratio 0.25)
			(net 659 "/Debug FTDI/LED_RX1")
			(pintype "passive")
		)
	)
	(footprint "antmicro-footprints:SOT-23-6"
		(layer "F.Cu")
		(at 196.515 146.851 90)
		(property "Reference" "U31"
			(at -1.449 2.785 90)
			(layer "F.SilkS")
			(effects
				(font
					(size 0.7 0.7)
					(thickness 0.15)
				)
				(justify left bottom)
			)
		)
		(property "Value" "LM3880"
			(at -1.75 2.75 90)
			(layer "F.Fab")
			(effects
				(font
					(size 0.7 0.7)
					(thickness 0.15)
				)
				(justify left bottom)
			)
		)
		(property "Datasheet" "http://www.ti.com/lit/ds/symlink/lm3880.pdf"
			(at 0 0 90)
			(layer "F.Fab")
			(hide yes)
			(effects
				(font
					(size 1.27 1.27)
					(thickness 0.15)
				)
			)
		)
		(property "Author" "Antmicro"
			(at 343.366 -49.664 0)
			(layer "F.Fab")
			(hide yes)
			(effects
				(font
					(size 1 1)
					(thickness 0.15)
				)
			)
		)
		(property "License" "Apache-2.0"
			(at 343.366 -49.664 0)
			(layer "F.Fab")
			(hide yes)
			(effects
				(font
					(size 1 1)
					(thickness 0.15)
				)
			)
		)
		(property "MPN" "LM3880MFX-1AA/NOPB"
			(at 343.366 -49.664 0)
			(layer "F.Fab")
			(hide yes)
			(effects
				(font
					(size 1 1)
					(thickness 0.15)
				)
			)
		)
		(property "Manufacturer" "Texas Instruments"
			(at 343.366 -49.664 0)
			(layer "F.Fab")
			(hide yes)
			(effects
				(font
					(size 1 1)
					(thickness 0.15)
				)
			)
		)
		(property ki_fp_filters "SOT?23*")
		(sheetname "/Supply/")
		(sheetfile "supply.kicad_sch")
		(attr smd)
		(fp_line
			(start 1.45 -0.7)
			(end 1.45 -0.4)
			(stroke
				(width 0.12)
				(type solid)
			)
			(layer "F.SilkS")
		)
		(fp_line
			(start 1.3 -0.7)
			(end 1.45 -0.7)
			(stroke
				(width 0.12)
				(type solid)
			)
			(layer "F.SilkS")
		)
		(fp_line
			(start -1.3 -0.7)
			(end -1.45 -0.7)
			(stroke
				(width 0.12)
				(type solid)
			)
			(layer "F.SilkS")
		)
		(fp_line
			(start -1.45 -0.7)
			(end -1.45 -0.4)
			(stroke
				(width 0.12)
				(type solid)
			)
			(layer "F.SilkS")
		)
		(fp_line
			(start 1.45 0.7)
			(end 1.45 0.4)
			(stroke
				(width 0.12)
				(type solid)
			)
			(layer "F.SilkS")
		)
		(fp_line
			(start 1.3 0.7)
			(end 1.45 0.7)
			(stroke
				(width 0.12)
				(type solid)
			)
			(layer "F.SilkS")
		)
		(fp_line
			(start -1.45 0.7)
			(end -1.45 0.4)
			(stroke
				(width 0.12)
				(type solid)
			)
			(layer "F.SilkS")
		)
		(fp_rect
			(start -1.55 -1.85)
			(end 1.55 1.75)
			(stroke
				(width 0.05)
				(type solid)
			)
			(fill no)
			(layer "F.CrtYd")
		)
		(fp_line
			(start 1.5 -0.7)
			(end 1.5 0.7)
			(stroke
				(width 0.1)
				(type solid)
			)
			(layer "F.Fab")
		)
		(fp_line
			(start -1.5 -0.7)
			(end 1.5 -0.7)
			(stroke
				(width 0.1)
				(type solid)
			)
			(layer "F.Fab")
		)
		(fp_line
			(start 1.5 0.7)
			(end -1.5 0.7)
			(stroke
				(width 0.1)
				(type solid)
			)
			(layer "F.Fab")
		)
		(fp_line
			(start -1.5 0.7)
			(end -1.5 -0.7)
			(stroke
				(width 0.1)
				(type solid)
			)
			(layer "F.Fab")
		)
		(fp_text user "."
			(at -1.4 1.2 270)
			(layer "F.SilkS")
			(effects
				(font
					(size 1 1)
					(thickness 0.15)
				)
			)
		)
		(pad "1" smd roundrect
			(at -0.954 1.1 90)
			(size 0.55 1)
			(layers "F.Cu" "F.Mask" "F.Paste")
			(roundrect_rratio 0.15)
			(net 41 "+3V3_AON")
			(pinfunction "VCC")
			(pintype "power_in")
		)
		(pad "2" smd roundrect
			(at -0.003 1.1 90)
			(size 0.55 1)
			(layers "F.Cu" "F.Mask" "F.Paste")
			(roundrect_rratio 0.15)
			(net 1 "GND")
			(pinfunction "GND")
			(pintype "power_in")
		)
		(pad "3" smd roundrect
			(at 0.947 1.1 90)
			(size 0.55 1)
			(layers "F.Cu" "F.Mask" "F.Paste")
			(roundrect_rratio 0.15)
			(net 62 "/Supply/SEQ_EN")
			(pinfunction "EN")
			(pintype "input")
		)
		(pad "4" smd roundrect
			(at 0.947 -1.214 90)
			(size 0.55 1)
			(layers "F.Cu" "F.Mask" "F.Paste")
			(roundrect_rratio 0.15)
			(net 223 "/Supply/EN3")
			(pinfunction "FLAG3")
			(pintype "open_collector")
		)
		(pad "5" smd roundrect
			(at -0.003 -1.214 90)
			(size 0.55 1)
			(layers "F.Cu" "F.Mask" "F.Paste")
			(roundrect_rratio 0.15)
			(net 222 "/Supply/EN2")
			(pinfunction "FLAG2")
			(pintype "open_collector")
		)
		(pad "6" smd roundrect
			(at -0.954 -1.214 90)
			(size 0.55 1)
			(layers "F.Cu" "F.Mask" "F.Paste")
			(roundrect_rratio 0.15)
			(net 221 "/Supply/EN1")
			(pinfunction "FLAG1")
			(pintype "open_collector")
		)
	)
	(footprint "antmicro-footprints:NetTie-2_SMD_Pad0.127mm"
		(layer "F.Cu")
		(at 200.325 177.174)
		(descr "Net tie, 2 pin, 0.127mm  SMD pads")
		(tags "net tie")
		(property "Reference" "NT3"
			(at -0.128 -1.345 0)
			(layer "F.SilkS")
			(hide yes)
			(effects
				(font
					(size 0.7 0.7)
					(thickness 0.15)
				)
				(justify left bottom)
			)
		)
		(property "Value" "Net-Tie_P0.127mm"
			(at 0 1.199 0)
			(layer "F.Fab")
			(effects
				(font
					(size 0.7 0.7)
					(thickness 0.15)
				)
				(justify left bottom)
			)
		)
		(property "Author" "Antmicro"
			(at 0 0 0)
			(layer "F.Fab")
			(hide yes)
			(effects
				(font
					(size 1 1)
					(thickness 0.15)
				)
			)
		)
		(property "License" "Apache-2.0"
			(at 0 0 0)
			(layer "F.Fab")
			(hide yes)
			(effects
				(font
					(size 1 1)
					(thickness 0.15)
				)
			)
		)
		(property "MPN" ""
			(at 0 0 0)
			(layer "F.Fab")
			(hide yes)
			(effects
				(font
					(size 1 1)
					(thickness 0.15)
				)
			)
		)
		(property "Manufacturer" ""
			(at 0 0 0)
			(layer "F.Fab")
			(hide yes)
			(effects
				(font
					(size 1 1)
					(thickness 0.15)
				)
			)
		)
		(property ki_fp_filters "Net*Tie*")
		(sheetname "/Supply/")
		(sheetfile "supply.kicad_sch")
		(attr smd exclude_from_pos_files exclude_from_bom)
		(net_tie_pad_groups "1, 2")
		(fp_poly
			(pts
				(xy -0.0635 -0.0635) (xy 0.0625 -0.0635) (xy 0.0625 0.0635) (xy -0.0635 0.0635)
			)
			(stroke
				(width 0)
				(type solid)
			)
			(fill yes)
			(layer "F.Cu")
		)
		(pad "1" smd roundrect
			(at -0.127 0 180)
			(size 0.127 0.127)
			(layers "F.Cu")
			(roundrect_rratio 0.5)
			(chamfer_ratio 0)
			(chamfer top_left bottom_left)
			(net 232 "/Supply/sp_SEN_+")
			(pinfunction "1")
			(pintype "passive")
		)
		(pad "2" smd roundrect
			(at 0.126 0)
			(size 0.127 0.127)
			(layers "F.Cu")
			(roundrect_rratio 0.5)
			(chamfer_ratio 0)
			(chamfer top_left bottom_left)
			(net 35 "/Supply/spare_local")
			(pinfunction "2")
			(pintype "passive")
		)
	)
	(footprint "antmicro-footprints:VSSOP-8_2.3x2mm_P0.5mm"
		(layer "F.Cu")
		(at 181.65 194.3)
		(property "Reference" "U24"
			(at -1.15 2.1 0)
			(layer "F.SilkS")
			(effects
				(font
					(size 0.7 0.7)
					(thickness 0.15)
				)
				(justify left bottom)
			)
		)
		(property "Value" "TS5A3359_VSSOP"
			(at 0 2.258 0)
			(layer "F.Fab")
			(effects
				(font
					(size 0.7 0.7)
					(thickness 0.15)
				)
				(justify left bottom)
			)
		)
		(property "Datasheet" "https://www.ti.com/general/docs/suppproductinfo.tsp?distId=26&gotoUrl=http%3A%2F%2Fwww.ti.com%2Flit%2Fgpn%2Fts5a3359"
			(at 0 0 0)
			(layer "F.Fab")
			(hide yes)
			(effects
				(font
					(size 1.27 1.27)
					(thickness 0.15)
				)
			)
		)
		(property "Author" "Antmicro"
			(at 0 0 0)
			(layer "F.Fab")
			(hide yes)
			(effects
				(font
					(size 1 1)
					(thickness 0.15)
				)
			)
		)
		(property "License" "Apache-2.0"
			(at 0 0 0)
			(layer "F.Fab")
			(hide yes)
			(effects
				(font
					(size 1 1)
					(thickness 0.15)
				)
			)
		)
		(property "MPN" "TS5A3359DCUR"
			(at 0 0 0)
			(layer "F.Fab")
			(hide yes)
			(effects
				(font
					(size 1 1)
					(thickness 0.15)
				)
			)
		)
		(property "Manufacturer" "Texas Instruments"
			(at 0 0 0)
			(layer "F.Fab")
			(hide yes)
			(effects
				(font
					(size 1 1)
					(thickness 0.15)
				)
			)
		)
		(sheetname "/I^{2}C/")
		(sheetfile "i2c.kicad_sch")
		(attr smd)
		(fp_line
			(start -0.82 -0.992)
			(end 0.825 -0.992)
			(stroke
				(width 0.15)
				(type solid)
			)
			(layer "F.SilkS")
		)
		(fp_line
			(start 0.825 1.007)
			(end -0.82 1.007)
			(stroke
				(width 0.15)
				(type solid)
			)
			(layer "F.SilkS")
		)
		(fp_circle
			(center -1.402 -1.192)
			(end -1.352 -1.192)
			(stroke
				(width 0.15)
				(type solid)
			)
			(fill yes)
			(layer "F.SilkS")
		)
		(fp_rect
			(start 1.8 1.35)
			(end -1.8 -1.35)
			(stroke
				(width 0.05)
				(type solid)
			)
			(fill no)
			(layer "F.CrtYd")
		)
		(fp_line
			(start -0.7 -0.99)
			(end -1.14 -0.55)
			(stroke
				(width 0.15)
				(type solid)
			)
			(layer "F.Fab")
		)
		(fp_rect
			(start -1.147 -0.992)
			(end 1.151 1.007)
			(stroke
				(width 0.15)
				(type solid)
			)
			(fill no)
			(layer "F.Fab")
		)
		(pad "1" smd rect
			(at -1.372 -0.742)
			(size 0.75 0.4)
			(layers "F.Cu" "F.Mask" "F.Paste")
			(net 682 "/FPGA bank 14/FPGA_DDR.SCL")
			(pinfunction "NO1")
			(pintype "passive")
		)
		(pad "2" smd rect
			(at -1.372 -0.244)
			(size 0.75 0.3)
			(layers "F.Cu" "F.Mask" "F.Paste")
			(net 689 "/FPGA bank 14/FPGA_PWR.SCL")
			(pinfunction "NO2")
			(pintype "passive")
		)
		(pad "3" smd rect
			(at -1.372 0.256)
			(size 0.75 0.3)
			(layers "F.Cu" "F.Mask" "F.Paste")
			(net 671 "/Debug FTDI/FTDI.SCL")
			(pinfunction "NO3")
			(pintype "passive")
		)
		(pad "4" smd rect
			(at -1.372 0.757)
			(size 0.75 0.4)
			(layers "F.Cu" "F.Mask" "F.Paste")
			(net 1 "GND")
			(pinfunction "GND")
			(pintype "passive")
		)
		(pad "5" smd rect
			(at 1.377 0.757)
			(size 0.75 0.4)
			(layers "F.Cu" "F.Mask" "F.Paste")
			(net 687 "IN2")
			(pinfunction "IN2")
			(pintype "passive")
		)
		(pad "6" smd rect
			(at 1.377 0.256)
			(size 0.75 0.3)
			(layers "F.Cu" "F.Mask" "F.Paste")
			(net 686 "IN1")
			(pinfunction "IN1")
			(pintype "passive")
		)
		(pad "7" smd rect
			(at 1.377 -0.244)
			(size 0.75 0.3)
			(layers "F.Cu" "F.Mask" "F.Paste")
			(net 691 "/I^{2}C/PWR.SCL")
			(pinfunction "COM")
			(pintype "passive")
		)
		(pad "8" smd rect
			(at 1.377 -0.742)
			(size 0.75 0.4)
			(layers "F.Cu" "F.Mask" "F.Paste")
			(net 41 "+3V3_AON")
			(pinfunction "VCC")
			(pintype "passive")
		)
	)
	(footprint "antmicro-footprints:R_0402_1005Metric"
		(layer "F.Cu")
		(at 115.45 186.6 -90)
		(descr "Resistor SMD 0402")
		(tags "resistor SMD 0402")
		(property "Reference" "R9"
			(at -1.122484 -0.772697 270)
			(layer "F.SilkS")
			(hide yes)
			(effects
				(font
					(size 0.7 0.7)
					(thickness 0.15)
				)
				(justify left bottom)
			)
		)
		(property "Value" "R_22R_0402"
			(at -1.011843 1.772047 270)
			(layer "F.Fab")
			(effects
				(font
					(size 0.7 0.7)
					(thickness 0.15)
				)
				(justify left bottom)
			)
		)
		(property "Datasheet" "https://www.bourns.com/docs/product-datasheets/cr.pdf"
			(at 0 0 270)
			(layer "F.Fab")
			(hide yes)
			(effects
				(font
					(size 1.27 1.27)
					(thickness 0.15)
				)
			)
		)
		(property "Author" "Antmicro"
			(at -71.15 302.05 0)
			(layer "F.Fab")
			(hide yes)
			(effects
				(font
					(size 1 1)
					(thickness 0.15)
				)
			)
		)
		(property "License" "Apache-2.0"
			(at -71.15 302.05 0)
			(layer "F.Fab")
			(hide yes)
			(effects
				(font
					(size 1 1)
					(thickness 0.15)
				)
			)
		)
		(property "MPN" "CR0402-FX-22R0GLF"
			(at -71.15 302.05 0)
			(layer "F.Fab")
			(hide yes)
			(effects
				(font
					(size 1 1)
					(thickness 0.15)
				)
			)
		)
		(property "Manufacturer" "Bourns"
			(at -71.15 302.05 0)
			(layer "F.Fab")
			(hide yes)
			(effects
				(font
					(size 1 1)
					(thickness 0.15)
				)
			)
		)
		(property "Tolerance" "1%"
			(at -71.15 302.05 0)
			(layer "F.Fab")
			(hide yes)
			(effects
				(font
					(size 1 1)
					(thickness 0.15)
				)
			)
		)
		(property "Val" "22R"
			(at -71.15 302.05 0)
			(layer "F.Fab")
			(hide yes)
			(effects
				(font
					(size 1 1)
					(thickness 0.15)
				)
			)
		)
		(sheetname "/HyperRAM + QSPI Flash/")
		(sheetfile "hyperram-flash.kicad_sch")
		(attr smd)
		(fp_rect
			(start -0.93 -0.47)
			(end 0.93 0.47)
			(stroke
				(width 0.05)
				(type solid)
			)
			(fill no)
			(layer "F.CrtYd")
		)
		(fp_rect
			(start -0.5 -0.25)
			(end 0.5 0.25)
			(stroke
				(width 0.15)
				(type solid)
			)
			(fill no)
			(layer "F.Fab")
		)
		(pad "1" smd roundrect
			(at -0.485 0 270)
			(size 0.59 0.64)
			(layers "F.Cu" "F.Mask" "F.Paste")
			(roundrect_rratio 0.25)
			(net 360 "/HyperRAM + QSPI Flash/IO3")
			(pintype "passive")
		)
		(pad "2" smd roundrect
			(at 0.485 0 270)
			(size 0.59 0.64)
			(layers "F.Cu" "F.Mask" "F.Paste")
			(roundrect_rratio 0.25)
			(net 629 "/FPGA Config/FLASH.IO3")
			(pintype "passive")
		)
	)
	(footprint "antmicro-footprints:NetTie-2_SMD_Pad0.127mm"
		(layer "F.Cu")
		(at 187.8305 162.002 180)
		(descr "Net tie, 2 pin, 0.127mm  SMD pads")
		(tags "net tie")
		(property "Reference" "NT14"
			(at -0.128 -1.345 180)
			(layer "F.SilkS")
			(hide yes)
			(effects
				(font
					(size 0.7 0.7)
					(thickness 0.15)
				)
				(justify left bottom)
			)
		)
		(property "Value" "Net-Tie_P0.127mm"
			(at 0 1.199 180)
			(layer "F.Fab")
			(effects
				(font
					(size 0.7 0.7)
					(thickness 0.15)
				)
				(justify left bottom)
			)
		)
		(property "Author" "Antmicro"
			(at 375.661 324.004 0)
			(layer "F.Fab")
			(hide yes)
			(effects
				(font
					(size 1 1)
					(thickness 0.15)
				)
			)
		)
		(property "License" "Apache-2.0"
			(at 375.661 324.004 0)
			(layer "F.Fab")
			(hide yes)
			(effects
				(font
					(size 1 1)
					(thickness 0.15)
				)
			)
		)
		(property "MPN" ""
			(at 375.661 324.004 0)
			(layer "F.Fab")
			(hide yes)
			(effects
				(font
					(size 1 1)
					(thickness 0.15)
				)
			)
		)
		(property "Manufacturer" ""
			(at 375.661 324.004 0)
			(layer "F.Fab")
			(hide yes)
			(effects
				(font
					(size 1 1)
					(thickness 0.15)
				)
			)
		)
		(property ki_fp_filters "Net*Tie*")
		(sheetname "/Supply/")
		(sheetfile "supply.kicad_sch")
		(attr smd exclude_from_pos_files exclude_from_bom)
		(net_tie_pad_groups "1, 2")
		(fp_poly
			(pts
				(xy -0.0635 -0.0635) (xy 0.0625 -0.0635) (xy 0.0625 0.0635) (xy -0.0635 0.0635)
			)
			(stroke
				(width 0)
				(type solid)
			)
			(fill yes)
			(layer "F.Cu")
		)
		(pad "1" smd roundrect
			(at -0.127 0)
			(size 0.127 0.127)
			(layers "F.Cu")
			(roundrect_rratio 0.5)
			(chamfer_ratio 0)
			(chamfer top_left bottom_left)
			(net 146 "/Supply/5V_SEN_-")
			(pinfunction "1")
			(pintype "passive")
		)
		(pad "2" smd roundrect
			(at 0.126 0 180)
			(size 0.127 0.127)
			(layers "F.Cu")
			(roundrect_rratio 0.5)
			(chamfer_ratio 0)
			(chamfer top_left bottom_left)
			(net 201 "+5V")
			(pinfunction "2")
			(pintype "passive")
		)
	)
	(footprint "antmicro-footprints:R_0402_1005Metric"
		(layer "F.Cu")
		(at 106.25 184.8 -90)
		(descr "Resistor SMD 0402")
		(tags "resistor SMD 0402")
		(property "Reference" "R92"
			(at -1.122484 -0.772697 270)
			(layer "F.SilkS")
			(hide yes)
			(effects
				(font
					(size 0.7 0.7)
					(thickness 0.15)
				)
				(justify left bottom)
			)
		)
		(property "Value" "R_0R_0402"
			(at -1.011843 1.772047 270)
			(layer "F.Fab")
			(effects
				(font
					(size 0.7 0.7)
					(thickness 0.15)
				)
				(justify left bottom)
			)
		)
		(property "Datasheet" "https://industrial.panasonic.com/cdbs/www-data/pdf/RDA0000/AOA0000C301.pdf"
			(at 0 0 270)
			(layer "F.Fab")
			(hide yes)
			(effects
				(font
					(size 1.27 1.27)
					(thickness 0.15)
				)
			)
		)
		(property "Author" "Antmicro"
			(at -78.55 291.05 0)
			(layer "F.Fab")
			(hide yes)
			(effects
				(font
					(size 1 1)
					(thickness 0.15)
				)
			)
		)
		(property "Current" "1A"
			(at -78.55 291.05 0)
			(layer "F.Fab")
			(hide yes)
			(effects
				(font
					(size 1 1)
					(thickness 0.15)
				)
			)
		)
		(property "License" "Apache-2.0"
			(at -78.55 291.05 0)
			(layer "F.Fab")
			(hide yes)
			(effects
				(font
					(size 1 1)
					(thickness 0.15)
				)
			)
		)
		(property "MPN" "ERJ2GE0R00X"
			(at -78.55 291.05 0)
			(layer "F.Fab")
			(hide yes)
			(effects
				(font
					(size 1 1)
					(thickness 0.15)
				)
			)
		)
		(property "Manufacturer" "Panasonic"
			(at -78.55 291.05 0)
			(layer "F.Fab")
			(hide yes)
			(effects
				(font
					(size 1 1)
					(thickness 0.15)
				)
			)
		)
		(property "Tolerance" ""
			(at -78.55 291.05 0)
			(layer "F.Fab")
			(hide yes)
			(effects
				(font
					(size 1 1)
					(thickness 0.15)
				)
			)
		)
		(property "Val" "0R"
			(at -78.55 291.05 0)
			(layer "F.Fab")
			(hide yes)
			(effects
				(font
					(size 1 1)
					(thickness 0.15)
				)
			)
		)
		(sheetname "/Debug FTDI/")
		(sheetfile "debug-ftdi.kicad_sch")
		(attr smd)
		(fp_rect
			(start -0.93 -0.47)
			(end 0.93 0.47)
			(stroke
				(width 0.05)
				(type solid)
			)
			(fill no)
			(layer "F.CrtYd")
		)
		(fp_rect
			(start -0.5 -0.25)
			(end 0.5 0.25)
			(stroke
				(width 0.15)
				(type solid)
			)
			(fill no)
			(layer "F.Fab")
		)
		(pad "1" smd roundrect
			(at -0.485 0 270)
			(size 0.59 0.64)
			(layers "F.Cu" "F.Mask" "F.Paste")
			(roundrect_rratio 0.25)
			(net 670 "/Debug FTDI/FTDI_SCL")
			(pintype "passive")
		)
		(pad "2" smd roundrect
			(at 0.485 0 270)
			(size 0.59 0.64)
			(layers "F.Cu" "F.Mask" "F.Paste")
			(roundrect_rratio 0.25)
			(net 671 "/Debug FTDI/FTDI.SCL")
			(pintype "passive")
		)
	)
	(footprint "antmicro-footprints:LED_0603_1608Metric_G"
		(layer "F.Cu")
		(at 89.050501 116.426 -90)
		(descr "LED SMD 0603 Green")
		(tags "LED SMD 0603 Green")
		(property "Reference" "D5"
			(at -0.001 -0.901 270)
			(layer "F.SilkS")
			(hide yes)
			(effects
				(font
					(size 0.7 0.7)
					(thickness 0.15)
				)
				(justify left bottom)
			)
		)
		(property "Value" "LED_G_0603_KP-1608CGCK"
			(at -0.001 1.599 270)
			(layer "F.Fab")
			(effects
				(font
					(size 0.7 0.7)
					(thickness 0.15)
				)
				(justify left bottom)
			)
		)
		(property "Datasheet" "http://www.farnell.com/datasheets/2045956.pdf"
			(at 0 0 270)
			(layer "F.Fab")
			(hide yes)
			(effects
				(font
					(size 1.27 1.27)
					(thickness 0.15)
				)
			)
		)
		(property "Author" "Antmicro"
			(at -27.375499 205.476501 0)
			(layer "F.Fab")
			(hide yes)
			(effects
				(font
					(size 1 1)
					(thickness 0.15)
				)
			)
		)
		(property "License" "Apache-2.0"
			(at -27.375499 205.476501 0)
			(layer "F.Fab")
			(hide yes)
			(effects
				(font
					(size 1 1)
					(thickness 0.15)
				)
			)
		)
		(property "MPN" "KP-1608CGCK"
			(at -27.375499 205.476501 0)
			(layer "F.Fab")
			(hide yes)
			(effects
				(font
					(size 1 1)
					(thickness 0.15)
				)
			)
		)
		(property "Manufacturer" "Kingbright"
			(at -27.375499 205.476501 0)
			(layer "F.Fab")
			(hide yes)
			(effects
				(font
					(size 1 1)
					(thickness 0.15)
				)
			)
		)
		(sheetname "/FPGA bank 14/")
		(sheetfile "fpga-bank-14.kicad_sch")
		(attr smd)
		(fp_line
			(start -0.271 0.348)
			(end 0.269 0.348)
			(stroke
				(width 0.15)
				(type solid)
			)
			(layer "F.SilkS")
		)
		(fp_line
			(start 1.249 0.319)
			(end 1.249 -0.321)
			(stroke
				(width 0.15)
				(type solid)
			)
			(layer "F.SilkS")
		)
		(fp_line
			(start -0.107 -0.001)
			(end -0.291 -0.001)
			(stroke
				(width 0.1)
				(type solid)
			)
			(layer "F.SilkS")
		)
		(fp_line
			(start 0.092 -0.001)
			(end -0.107 0.198)
			(stroke
				(width 0.1)
				(type solid)
			)
			(layer "F.SilkS")
		)
		(fp_line
			(start 0.092 -0.001)
			(end 0.292 -0.001)
			(stroke
				(width 0.1)
				(type solid)
			)
			(layer "F.SilkS")
		)
		(fp_line
			(start -0.107 -0.201)
			(end -0.107 0.198)
			(stroke
				(width 0.1)
				(type solid)
			)
			(layer "F.SilkS")
		)
		(fp_line
			(start -0.107 -0.201)
			(end 0.092 -0.001)
			(stroke
				(width 0.1)
				(type solid)
			)
			(layer "F.SilkS")
		)
		(fp_line
			(start 0.092 -0.201)
			(end 0.092 0.198)
			(stroke
				(width 0.1)
				(type solid)
			)
			(layer "F.SilkS")
		)
		(fp_line
			(start -0.271 -0.349)
			(end 0.269 -0.349)
			(stroke
				(width 0.15)
				(type solid)
			)
			(layer "F.SilkS")
		)
		(fp_rect
			(start -1.2192 -0.6096)
			(end 1.27 0.6016)
			(stroke
				(width 0.05)
				(type solid)
			)
			(fill no)
			(layer "F.CrtYd")
		)
		(fp_line
			(start -0.202 0.201)
			(end 0.1 -0.001)
			(stroke
				(width 0.15)
				(type solid)
			)
			(layer "F.Fab")
		)
		(fp_line
			(start 0.198 0.201)
			(end 0.198 -0.101)
			(stroke
				(width 0.15)
				(type solid)
			)
			(layer "F.Fab")
		)
		(fp_line
			(start -0.849 0.025)
			(end -0.442 0.381)
			(stroke
				(width 0.15)
				(type solid)
			)
			(layer "F.Fab")
		)
		(fp_line
			(start -0.6 -0.001)
			(end -0.202 -0.001)
			(stroke
				(width 0.15)
				(type solid)
			)
			(layer "F.Fab")
		)
		(fp_line
			(start -0.202 -0.001)
			(end -0.202 0.201)
			(stroke
				(width 0.15)
				(type solid)
			)
			(layer "F.Fab")
		)
		(fp_line
			(start 0.1 -0.001)
			(end -0.202 -0.201)
			(stroke
				(width 0.15)
				(type solid)
			)
			(layer "F.Fab")
		)
		(fp_line
			(start 0.198 -0.001)
			(end 0.596 -0.001)
			(stroke
				(width 0.15)
				(type solid)
			)
			(layer "F.Fab")
		)
		(fp_line
			(start -0.202 -0.201)
			(end -0.202 -0.001)
			(stroke
				(width 0.15)
				(type solid)
			)
			(layer "F.Fab")
		)
		(fp_line
			(start 0.198 -0.201)
			(end 0.198 -0.101)
			(stroke
				(width 0.15)
				(type solid)
			)
			(layer "F.Fab")
		)
		(fp_rect
			(start -0.849 -0.401)
			(end 0.849 0.401)
			(stroke
				(width 0.15)
				(type solid)
			)
			(fill no)
			(layer "F.Fab")
		)
		(pad "1" smd rect
			(at -0.751 -0.001 90)
			(size 0.8 0.8)
			(layers "F.Cu" "F.Mask" "F.Paste")
			(net 200 "+3V3")
			(pinfunction "1")
			(pintype "passive")
		)
		(pad "2" smd rect
			(at 0.749 -0.001 90)
			(size 0.8 0.8)
			(layers "F.Cu" "F.Mask" "F.Paste")
			(net 308 "Net-(D5-Pad2)")
			(pinfunction "2")
			(pintype "passive")
		)
	)
	(footprint "antmicro-footprints:Conn_JST_SH_1x4_BM04B-SRSS-TB-LF-SN"
		(layer "F.Cu")
		(at 157.9 173.05)
		(property "Reference" "J8"
			(at 1.9 2.65 0)
			(layer "F.SilkS")
			(effects
				(font
					(size 0.7 0.7)
					(thickness 0.15)
				)
				(justify left bottom)
			)
		)
		(property "Value" "JST_SH_1x4_BM04B-SRSS-TB-LF-SN"
			(at 0 3.1 0)
			(layer "F.Fab")
			(effects
				(font
					(size 0.7 0.7)
					(thickness 0.15)
				)
				(justify left bottom)
			)
		)
		(property "Datasheet" "https://www.jst-mfg.com/product/pdf/eng/eSH.pdf"
			(at 0 0 0)
			(layer "F.Fab")
			(hide yes)
			(effects
				(font
					(size 1.27 1.27)
					(thickness 0.15)
				)
			)
		)
		(property "Author" "Antmicro"
			(at 0 0 0)
			(layer "F.Fab")
			(hide yes)
			(effects
				(font
					(size 1 1)
					(thickness 0.15)
				)
			)
		)
		(property "License" "Apache-2.0"
			(at 0 0 0)
			(layer "F.Fab")
			(hide yes)
			(effects
				(font
					(size 1 1)
					(thickness 0.15)
				)
			)
		)
		(property "MPN" "BM04B-SRSS-TB(LF)(SN) "
			(at 0 0 0)
			(layer "F.Fab")
			(hide yes)
			(effects
				(font
					(size 1 1)
					(thickness 0.15)
				)
			)
		)
		(property "Manufacturer" "JST Automotive Connectors"
			(at 0 0 0)
			(layer "F.Fab")
			(hide yes)
			(effects
				(font
					(size 1 1)
					(thickness 0.15)
				)
			)
		)
		(sheetname "/Supply/")
		(sheetfile "supply.kicad_sch")
		(attr smd)
		(fp_line
			(start -2.999 0.1765)
			(end -2.999 1.0505)
			(stroke
				(width 0.15)
				(type solid)
			)
			(layer "F.SilkS")
		)
		(fp_line
			(start -2.999 1.0505)
			(end -2.201 1.0505)
			(stroke
				(width 0.15)
				(type solid)
			)
			(layer "F.SilkS")
		)
		(fp_line
			(start -1.7005 -1.8495)
			(end 1.7015 -1.8495)
			(stroke
				(width 0.15)
				(type solid)
			)
			(layer "F.SilkS")
		)
		(fp_line
			(start 2.9995 0.1765)
			(end 2.9995 1.0505)
			(stroke
				(width 0.15)
				(type solid)
			)
			(layer "F.SilkS")
		)
		(fp_line
			(start 2.9995 1.0505)
			(end 2.2015 1.0505)
			(stroke
				(width 0.15)
				(type solid)
			)
			(layer "F.SilkS")
		)
		(fp_circle
			(center -2 1.5)
			(end -1.949 1.5)
			(stroke
				(width 0.15)
				(type solid)
			)
			(fill yes)
			(layer "F.SilkS")
		)
		(fp_rect
			(start -3.5 -2.1)
			(end 3.5 2.2)
			(stroke
				(width 0.05)
				(type solid)
			)
			(fill no)
			(layer "F.CrtYd")
		)
		(fp_line
			(start -2.9995 -1.8495)
			(end 2.9995 -1.8495)
			(stroke
				(width 0.15)
				(type solid)
			)
			(layer "F.Fab")
		)
		(fp_line
			(start -2.9995 1.0165)
			(end -2.9995 -1.8495)
			(stroke
				(width 0.15)
				(type solid)
			)
			(layer "F.Fab")
		)
		(fp_line
			(start -1.991 1.7785)
			(end -2.9995 0.9657)
			(stroke
				(width 0.15)
				(type solid)
			)
			(layer "F.Fab")
		)
		(fp_line
			(start 2.9995 -1.8495)
			(end 3.008 1.7785)
			(stroke
				(width 0.15)
				(type solid)
			)
			(layer "F.Fab")
		)
		(fp_line
			(start 3.008 1.7785)
			(end -1.991 1.7785)
			(stroke
				(width 0.15)
				(type solid)
			)
			(layer "F.Fab")
		)
		(pad "1" smd rect
			(at -1.4995 1.3765)
			(size 0.6 1.55)
			(layers "F.Cu" "F.Mask" "F.Paste")
			(net 1 "GND")
			(pinfunction "Pin_1")
			(pintype "passive")
		)
		(pad "2" smd rect
			(at -0.5015 1.3765)
			(size 0.6 1.55)
			(layers "F.Cu" "F.Mask" "F.Paste")
			(net 201 "+5V")
			(pinfunction "Pin_2")
			(pintype "passive")
		)
		(pad "3" smd rect
			(at 0.4995 1.3765)
			(size 0.6 1.55)
			(layers "F.Cu" "F.Mask" "F.Paste")
			(net 331 "unconnected-(J8-Pin_3-Pad3)")
			(pinfunction "Pin_3")
			(pintype "passive+no_connect")
		)
		(pad "4" smd rect
			(at 1.4995 1.3765)
			(size 0.6 1.55)
			(layers "F.Cu" "F.Mask" "F.Paste")
			(net 332 "Net-(J8-Pin_4)")
			(pinfunction "Pin_4")
			(pintype "passive")
		)
		(pad "MP" smd rect
			(at -2.7995 -1.1485)
			(size 1.2 1.8)
			(layers "F.Cu" "F.Mask" "F.Paste")
			(net 1 "GND")
			(pinfunction "MP")
			(pintype "passive")
		)
		(pad "MP" smd rect
			(at 2.8005 -1.1485)
			(size 1.2 1.8)
			(layers "F.Cu" "F.Mask" "F.Paste")
			(net 1 "GND")
			(pinfunction "MP")
			(pintype "passive")
		)
	)
	(footprint "antmicro-footprints:LED_RGY_1.6x1.6mm_APTF1616"
		(layer "F.Cu")
		(at 97.350501 116.426 -90)
		(descr "1.6 x 1.6 mm Full-Color Surface Mount LED")
		(tags "LED")
		(property "Reference" "D9"
			(at 0 -1.2 90)
			(layer "F.SilkS")
			(hide yes)
			(effects
				(font
					(size 0.7 0.7)
					(thickness 0.15)
				)
				(justify left bottom)
			)
		)
		(property "Value" "LED_RGY_0606_APTF1616SURKCGKSYKC"
			(at 0 2 270)
			(layer "F.Fab")
			(effects
				(font
					(size 0.7 0.7)
					(thickness 0.15)
				)
				(justify left bottom)
			)
		)
		(property "Datasheet" "http://www.mouser.com/datasheet/2/216/APTF1616SURKCGKSYKC-1145193.pdf"
			(at 0 0 270)
			(layer "F.Fab")
			(hide yes)
			(effects
				(font
					(size 1.27 1.27)
					(thickness 0.15)
				)
			)
		)
		(property "Description" "Standard LEDs - SMD RGY 1616 SMD"
			(at -19.075499 213.776501 0)
			(layer "F.Fab")
			(hide yes)
			(effects
				(font
					(size 1.27 1.27)
					(thickness 0.15)
				)
			)
		)
		(property "Author" "Antmicro"
			(at -19.075499 213.776501 0)
			(layer "F.Fab")
			(hide yes)
			(effects
				(font
					(size 1 1)
					(thickness 0.15)
				)
			)
		)
		(property "License" "Apache-2.0"
			(at -19.075499 213.776501 0)
			(layer "F.Fab")
			(hide yes)
			(effects
				(font
					(size 1 1)
					(thickness 0.15)
				)
			)
		)
		(property "MPN" "APTF1616SURKCGKSYKC"
			(at -19.075499 213.776501 0)
			(layer "F.Fab")
			(hide yes)
			(effects
				(font
					(size 1 1)
					(thickness 0.15)
				)
			)
		)
		(property "Manufacturer" "Kingbright"
			(at -19.075499 213.776501 0)
			(layer "F.Fab")
			(hide yes)
			(effects
				(font
					(size 1 1)
					(thickness 0.15)
				)
			)
		)
		(sheetname "/DDR5 SODIMM/")
		(sheetfile "ddr5-sodimm.kicad_sch")
		(attr smd)
		(fp_line
			(start -0.35 0.8)
			(end 0.35 0.8)
			(stroke
				(width 0.15)
				(type solid)
			)
			(layer "F.SilkS")
		)
		(fp_line
			(start 0.8 0.148)
			(end 0.8 -0.102)
			(stroke
				(width 0.15)
				(type solid)
			)
			(layer "F.SilkS")
		)
		(fp_line
			(start -0.8 -0.15)
			(end -0.801 0.15)
			(stroke
				(width 0.15)
				(type solid)
			)
			(layer "F.SilkS")
		)
		(fp_line
			(start 0.35 -0.802)
			(end -0.35 -0.802)
			(stroke
				(width 0.15)
				(type solid)
			)
			(layer "F.SilkS")
		)
		(fp_circle
			(center -1.05 -0.95)
			(end -1.101 -0.999)
			(stroke
				(width 0.15)
				(type solid)
			)
			(fill yes)
			(layer "F.SilkS")
		)
		(fp_rect
			(start 1.3 1.1)
			(end -1.3 -1.1)
			(stroke
				(width 0.05)
				(type solid)
			)
			(fill no)
			(layer "F.CrtYd")
		)
		(fp_rect
			(start -0.801 -0.802)
			(end 0.8 0.801)
			(stroke
				(width 0.15)
				(type solid)
			)
			(fill no)
			(layer "F.Fab")
		)
		(pad "1" smd rect
			(at -0.874 -0.499 180)
			(size 0.5 0.85)
			(layers "F.Cu" "F.Mask" "F.Paste")
			(net 200 "+3V3")
			(pinfunction "A")
			(pintype "passive")
		)
		(pad "2" smd rect
			(at 0.874 -0.499 180)
			(size 0.5 0.85)
			(layers "F.Cu" "F.Mask" "F.Paste")
			(net 301 "Net-(D9-C_{R})")
			(pinfunction "C_{R}")
			(pintype "passive")
		)
		(pad "3" smd rect
			(at 0.874 0.498 180)
			(size 0.5 0.85)
			(layers "F.Cu" "F.Mask" "F.Paste")
			(net 302 "Net-(D9-C_{G})")
			(pinfunction "C_{G}")
			(pintype "passive")
		)
		(pad "4" smd rect
			(at -0.874 0.498 180)
			(size 0.5 0.85)
			(layers "F.Cu" "F.Mask" "F.Paste")
			(net 312 "Net-(D9-C_{Y})")
			(pinfunction "C_{Y}")
			(pintype "passive")
		)
	)
	(footprint "antmicro-footprints:C_0603_1608Metric"
		(layer "F.Cu")
		(at 78.149 150.85 90)
		(descr "Capacitor SMD 0603")
		(tags "capacitor 0603")
		(property "Reference" "C109"
			(at -1.42757 -1.000252 90)
			(layer "F.SilkS")
			(hide yes)
			(effects
				(font
					(size 0.7 0.7)
					(thickness 0.15)
				)
				(justify left bottom)
			)
		)
		(property "Value" "C_10u_25V_0603"
			(at -1.42757 1.770288 90)
			(layer "F.Fab")
			(effects
				(font
					(size 0.7 0.7)
					(thickness 0.15)
				)
				(justify left bottom)
			)
		)
		(property "Datasheet" "https://product.tdk.com/en/search/capacitor/ceramic/mlcc/info?part_no=C1608X5R1E106M080AC"
			(at 0 0 90)
			(layer "F.Fab")
			(hide yes)
			(effects
				(font
					(size 1.27 1.27)
					(thickness 0.15)
				)
			)
		)
		(property "Author" "Antmicro"
			(at 228.999 72.701 0)
			(layer "F.Fab")
			(hide yes)
			(effects
				(font
					(size 1 1)
					(thickness 0.15)
				)
			)
		)
		(property "Dielectric" ""
			(at 228.999 72.701 0)
			(layer "F.Fab")
			(hide yes)
			(effects
				(font
					(size 1 1)
					(thickness 0.15)
				)
			)
		)
		(property "License" "Apache-2.0"
			(at 228.999 72.701 0)
			(layer "F.Fab")
			(hide yes)
			(effects
				(font
					(size 1 1)
					(thickness 0.15)
				)
			)
		)
		(property "MPN" "C1608X5R1E106M080AC"
			(at 228.999 72.701 0)
			(layer "F.Fab")
			(hide yes)
			(effects
				(font
					(size 1 1)
					(thickness 0.15)
				)
			)
		)
		(property "Manufacturer" "TDK"
			(at 228.999 72.701 0)
			(layer "F.Fab")
			(hide yes)
			(effects
				(font
					(size 1 1)
					(thickness 0.15)
				)
			)
		)
		(property "Val" "10u/25V"
			(at 228.999 72.701 0)
			(layer "F.Fab")
			(hide yes)
			(effects
				(font
					(size 1 1)
					(thickness 0.15)
				)
			)
		)
		(property "Voltage" ""
			(at 228.999 72.701 0)
			(layer "F.Fab")
			(hide yes)
			(effects
				(font
					(size 1 1)
					(thickness 0.15)
				)
			)
		)
		(sheetname "/Debug FTDI/")
		(sheetfile "debug-ftdi.kicad_sch")
		(attr smd)
		(fp_line
			(start -0.3 -0.3)
			(end 0.3 -0.3)
			(stroke
				(width 0.15)
				(type solid)
			)
			(layer "F.SilkS")
		)
		(fp_line
			(start -0.3 0.3)
			(end 0.3 0.3)
			(stroke
				(width 0.15)
				(type solid)
			)
			(layer "F.SilkS")
		)
		(fp_rect
			(start -1.24 -0.7)
			(end 1.24 0.7)
			(stroke
				(width 0.05)
				(type solid)
			)
			(fill no)
			(layer "F.CrtYd")
		)
		(fp_rect
			(start -0.8 -0.4)
			(end 0.8 0.4)
			(stroke
				(width 0.15)
				(type solid)
			)
			(fill no)
			(layer "F.Fab")
		)
		(pad "1" smd roundrect
			(at -0.7 0 90)
			(size 0.6 0.8)
			(layers "F.Cu" "F.Mask" "F.Paste")
			(roundrect_rratio 0.2)
			(net 1 "GND")
			(pintype "passive")
		)
		(pad "2" smd roundrect
			(at 0.7 0 90)
			(size 0.6 0.8)
			(layers "F.Cu" "F.Mask" "F.Paste")
			(roundrect_rratio 0.2)
			(net 2 "/Debug FTDI/VBUS")
			(pintype "passive")
		)
	)
	(footprint "antmicro-footprints:C_0402_1005Metric"
		(layer "F.Cu")
		(at 181.566 154.05)
		(descr "Capacitor SMD 0402")
		(tags "capacitor SMD 0402")
		(property "Reference" "C218"
			(at 0 -0.699 0)
			(layer "F.SilkS")
			(hide yes)
			(effects
				(font
					(size 0.7 0.7)
					(thickness 0.15)
				)
				(justify left bottom)
			)
		)
		(property "Value" "C_10u_6.3V_0402"
			(at -1.022927 2.155213 0)
			(layer "F.Fab")
			(effects
				(font
					(size 0.7 0.7)
					(thickness 0.15)
				)
				(justify left bottom)
			)
		)
		(property "Datasheet" "https://www.murata.com/products/productdetail?partno=GRM155R60J106ME15%23"
			(at 0 0 0)
			(layer "F.Fab")
			(hide yes)
			(effects
				(font
					(size 1.27 1.27)
					(thickness 0.15)
				)
			)
		)
		(property "Author" "Antmicro"
			(at 0 0 0)
			(layer "F.Fab")
			(hide yes)
			(effects
				(font
					(size 1 1)
					(thickness 0.15)
				)
			)
		)
		(property "Dielectric" "X5R"
			(at 0 0 0)
			(layer "F.Fab")
			(hide yes)
			(effects
				(font
					(size 1 1)
					(thickness 0.15)
				)
			)
		)
		(property "License" "Apache-2.0"
			(at 0 0 0)
			(layer "F.Fab")
			(hide yes)
			(effects
				(font
					(size 1 1)
					(thickness 0.15)
				)
			)
		)
		(property "MPN" "GRM155R60J106ME15D"
			(at 0 0 0)
			(layer "F.Fab")
			(hide yes)
			(effects
				(font
					(size 1 1)
					(thickness 0.15)
				)
			)
		)
		(property "Manufacturer" "Murata"
			(at 0 0 0)
			(layer "F.Fab")
			(hide yes)
			(effects
				(font
					(size 1 1)
					(thickness 0.15)
				)
			)
		)
		(property "Val" "10u"
			(at 0 0 0)
			(layer "F.Fab")
			(hide yes)
			(effects
				(font
					(size 1 1)
					(thickness 0.15)
				)
			)
		)
		(property "Voltage" "6.3V"
			(at 0 0 0)
			(layer "F.Fab")
			(hide yes)
			(effects
				(font
					(size 1 1)
					(thickness 0.15)
				)
			)
		)
		(sheetname "/Supply/")
		(sheetfile "supply.kicad_sch")
		(attr smd)
		(fp_rect
			(start -0.9659 -0.481258)
			(end 0.9649 0.458742)
			(stroke
				(width 0.05)
				(type solid)
			)
			(fill no)
			(layer "F.CrtYd")
		)
		(fp_line
			(start -0.499 -0.25)
			(end 0.499 -0.25)
			(stroke
				(width 0.15)
				(type solid)
			)
			(layer "F.Fab")
		)
		(fp_line
			(start -0.499 0.248)
			(end -0.499 -0.25)
			(stroke
				(width 0.15)
				(type solid)
			)
			(layer "F.Fab")
		)
		(fp_line
			(start 0.499 -0.25)
			(end 0.499 0.248)
			(stroke
				(width 0.15)
				(type solid)
			)
			(layer "F.Fab")
		)
		(fp_line
			(start 0.499 0.248)
			(end -0.499 0.248)
			(stroke
				(width 0.15)
				(type solid)
			)
			(layer "F.Fab")
		)
		(pad "1" smd roundrect
			(at -0.484 0)
			(size 0.59 0.64)
			(layers "F.Cu" "F.Mask" "F.Paste")
			(roundrect_rratio 0.25)
			(net 1 "GND")
			(pintype "passive")
		)
		(pad "2" smd roundrect
			(at 0.484 0)
			(size 0.59 0.64)
			(layers "F.Cu" "F.Mask" "F.Paste")
			(roundrect_rratio 0.25)
			(net 206 "+1V1")
			(pintype "passive")
		)
	)
	(footprint "antmicro-footprints:C_Pol_EIA-D"
		(layer "F.Cu")
		(at 125.000501 193.976 -90)
		(property "Reference" "C12"
			(at 0 -2.6 90)
			(layer "F.SilkS")
			(hide yes)
			(effects
				(font
					(size 0.7 0.7)
					(thickness 0.15)
				)
				(justify right bottom)
			)
		)
		(property "Value" "C_Pol_1m_2.5V_KEMET-T520-D"
			(at 0 3.4 90)
			(layer "F.Fab")
			(effects
				(font
					(size 0.7 0.7)
					(thickness 0.15)
				)
				(justify right bottom)
			)
		)
		(property "Datasheet" "https://content.kemet.com/datasheets/KEM_T2076_T52X-530.pdf"
			(at 0 0 270)
			(layer "F.Fab")
			(hide yes)
			(effects
				(font
					(size 1.27 1.27)
					(thickness 0.15)
				)
			)
		)
		(property "Author" "Antmicro"
			(at -68.975499 318.976501 0)
			(layer "F.Fab")
			(hide yes)
			(effects
				(font
					(size 1 1)
					(thickness 0.15)
				)
			)
		)
		(property "License" "Apache-2.0"
			(at -68.975499 318.976501 0)
			(layer "F.Fab")
			(hide yes)
			(effects
				(font
					(size 1 1)
					(thickness 0.15)
				)
			)
		)
		(property "MPN" "T520D108M2R5ATE030"
			(at -68.975499 318.976501 0)
			(layer "F.Fab")
			(hide yes)
			(effects
				(font
					(size 1 1)
					(thickness 0.15)
				)
			)
		)
		(property "Manufacturer" "KEMET"
			(at -68.975499 318.976501 0)
			(layer "F.Fab")
			(hide yes)
			(effects
				(font
					(size 1 1)
					(thickness 0.15)
				)
			)
		)
		(property "Val" "1000u/2.5V"
			(at -68.975499 318.976501 0)
			(layer "F.Fab")
			(hide yes)
			(effects
				(font
					(size 1 1)
					(thickness 0.15)
				)
			)
		)
		(property "Voltage" "2.5V"
			(at -68.975499 318.976501 0)
			(layer "F.Fab")
			(hide yes)
			(effects
				(font
					(size 1 1)
					(thickness 0.15)
				)
			)
		)
		(sheetname "/FPGA power/")
		(sheetfile "fpga-power.kicad_sch")
		(zone_connect 2)
		(attr smd)
		(fp_line
			(start -3.58 2.2)
			(end -3.58 1.6)
			(stroke
				(width 0.15)
				(type solid)
			)
			(layer "F.SilkS")
		)
		(fp_line
			(start 3.6 2.2)
			(end -3.58 2.2)
			(stroke
				(width 0.15)
				(type solid)
			)
			(layer "F.SilkS")
		)
		(fp_line
			(start 3.6 1.6)
			(end 3.6 2.2)
			(stroke
				(width 0.15)
				(type solid)
			)
			(layer "F.SilkS")
		)
		(fp_line
			(start -3.58 -1.6)
			(end -3.58 -2.2)
			(stroke
				(width 0.15)
				(type solid)
			)
			(layer "F.SilkS")
		)
		(fp_line
			(start -4.3 -1.825)
			(end -3.9 -1.825)
			(stroke
				(width 0.12)
				(type solid)
			)
			(layer "F.SilkS")
		)
		(fp_line
			(start -4.1 -2.025)
			(end -4.1 -1.625)
			(stroke
				(width 0.12)
				(type solid)
			)
			(layer "F.SilkS")
		)
		(fp_line
			(start -3.58 -2.2)
			(end 3.6 -2.2)
			(stroke
				(width 0.15)
				(type solid)
			)
			(layer "F.SilkS")
		)
		(fp_line
			(start 3.6 -2.2)
			(end 3.6 -1.6)
			(stroke
				(width 0.15)
				(type solid)
			)
			(layer "F.SilkS")
		)
		(fp_line
			(start -3.77 2.4)
			(end -3.77 1.51)
			(stroke
				(width 0.05)
				(type solid)
			)
			(layer "F.CrtYd")
		)
		(fp_line
			(start 3.77 2.4)
			(end -3.77 2.4)
			(stroke
				(width 0.05)
				(type solid)
			)
			(layer "F.CrtYd")
		)
		(fp_line
			(start -4.505 1.51)
			(end -4.505 -1.5)
			(stroke
				(width 0.05)
				(type solid)
			)
			(layer "F.CrtYd")
		)
		(fp_line
			(start -3.77 1.51)
			(end -4.505 1.51)
			(stroke
				(width 0.05)
				(type solid)
			)
			(layer "F.CrtYd")
		)
		(fp_line
			(start 3.77 1.51)
			(end 3.77 2.4)
			(stroke
				(width 0.05)
				(type solid)
			)
			(layer "F.CrtYd")
		)
		(fp_line
			(start 4.505 1.51)
			(end 3.77 1.51)
			(stroke
				(width 0.05)
				(type solid)
			)
			(layer "F.CrtYd")
		)
		(fp_line
			(start -3.775 -1.5)
			(end -4.505 -1.5)
			(stroke
				(width 0.05)
				(type solid)
			)
			(layer "F.CrtYd")
		)
		(fp_line
			(start 3.77 -1.51)
			(end 4.505 -1.51)
			(stroke
				(width 0.05)
				(type solid)
			)
			(layer "F.CrtYd")
		)
		(fp_line
			(start 4.505 -1.51)
			(end 4.505 1.5)
			(stroke
				(width 0.05)
				(type solid)
			)
			(layer "F.CrtYd")
		)
		(fp_line
			(start -3.775 -2.4)
			(end -3.775 -1.5)
			(stroke
				(width 0.05)
				(type solid)
			)
			(layer "F.CrtYd")
		)
		(fp_line
			(start -3.775 -2.4)
			(end 3.77 -2.4)
			(stroke
				(width 0.05)
				(type solid)
			)
			(layer "F.CrtYd")
		)
		(fp_line
			(start 3.77 -2.4)
			(end 3.77 -1.51)
			(stroke
				(width 0.05)
				(type solid)
			)
			(layer "F.CrtYd")
		)
		(fp_rect
			(start -3.65 -2.15)
			(end 3.65 2.15)
			(stroke
				(width 0.15)
				(type solid)
			)
			(fill no)
			(layer "F.Fab")
		)
		(pad "1" smd roundrect
			(at -3.1 0 270)
			(size 2.31 2.52)
			(layers "F.Cu" "F.Mask" "F.Paste")
			(roundrect_rratio 0.1)
			(net 227 "+1V0")
			(pintype "passive")
		)
		(pad "2" smd roundrect
			(at 3.1 0 270)
			(size 2.31 2.52)
			(layers "F.Cu" "F.Mask" "F.Paste")
			(roundrect_rratio 0.1)
			(net 1 "GND")
			(pintype "passive")
		)
	)
	(footprint "antmicro-footprints:R_0402_1005Metric"
		(layer "F.Cu")
		(at 176.080501 197.776 90)
		(descr "Resistor SMD 0402")
		(tags "resistor SMD 0402")
		(property "Reference" "R185"
			(at -3.624 0.299499 90)
			(layer "F.SilkS")
			(effects
				(font
					(size 0.7 0.7)
					(thickness 0.15)
				)
				(justify left bottom)
			)
		)
		(property "Value" "R_80k6_0402"
			(at -1.011843 1.772047 90)
			(layer "F.Fab")
			(effects
				(font
					(size 0.7 0.7)
					(thickness 0.15)
				)
				(justify left bottom)
			)
		)
		(property "Datasheet" "https://www.bourns.com/docs/product-datasheets/cr.pdf"
			(at 0 0 90)
			(layer "F.Fab")
			(hide yes)
			(effects
				(font
					(size 1.27 1.27)
					(thickness 0.15)
				)
			)
		)
		(property "Author" "Antmicro"
			(at 373.856501 21.695499 0)
			(layer "F.Fab")
			(hide yes)
			(effects
				(font
					(size 1 1)
					(thickness 0.15)
				)
			)
		)
		(property "License" "Apache-2.0"
			(at 373.856501 21.695499 0)
			(layer "F.Fab")
			(hide yes)
			(effects
				(font
					(size 1 1)
					(thickness 0.15)
				)
			)
		)
		(property "MPN" "CR0402-FX-8062GLF"
			(at 373.856501 21.695499 0)
			(layer "F.Fab")
			(hide yes)
			(effects
				(font
					(size 1 1)
					(thickness 0.15)
				)
			)
		)
		(property "Manufacturer" "Bourns"
			(at 373.856501 21.695499 0)
			(layer "F.Fab")
			(hide yes)
			(effects
				(font
					(size 1 1)
					(thickness 0.15)
				)
			)
		)
		(property "Tolerance" "1%"
			(at 373.856501 21.695499 0)
			(layer "F.Fab")
			(hide yes)
			(effects
				(font
					(size 1 1)
					(thickness 0.15)
				)
			)
		)
		(property "Val" "80k6"
			(at 373.856501 21.695499 0)
			(layer "F.Fab")
			(hide yes)
			(effects
				(font
					(size 1 1)
					(thickness 0.15)
				)
			)
		)
		(sheetname "/Supply/")
		(sheetfile "supply.kicad_sch")
		(attr smd)
		(fp_rect
			(start -0.93 -0.47)
			(end 0.93 0.47)
			(stroke
				(width 0.05)
				(type solid)
			)
			(fill no)
			(layer "F.CrtYd")
		)
		(fp_rect
			(start -0.5 -0.25)
			(end 0.5 0.25)
			(stroke
				(width 0.15)
				(type solid)
			)
			(fill no)
			(layer "F.Fab")
		)
		(pad "1" smd roundrect
			(at -0.485 0 90)
			(size 0.59 0.64)
			(layers "F.Cu" "F.Mask" "F.Paste")
			(roundrect_rratio 0.25)
			(net 303 "Net-(C221-Pad1)")
			(pintype "passive")
		)
		(pad "2" smd roundrect
			(at 0.485 0 90)
			(size 0.59 0.64)
			(layers "F.Cu" "F.Mask" "F.Paste")
			(roundrect_rratio 0.25)
			(net 78 "/Supply/1V0_REG")
			(pintype "passive")
		)
	)
	(footprint "antmicro-footprints:SW_KMR211NGLFS_SMD"
		(layer "F.Cu")
		(at 182.25 124.146)
		(property "Reference" "SW3"
			(at 2.75 1.054 0)
			(layer "F.SilkS")
			(effects
				(font
					(size 0.7 0.7)
					(thickness 0.15)
				)
				(justify left bottom)
			)
		)
		(property "Value" "SW_KMR211NGLFS_SMD"
			(at 0 2.8 0)
			(layer "F.Fab")
			(effects
				(font
					(size 0.7 0.7)
					(thickness 0.15)
				)
				(justify left bottom)
			)
		)
		(property "Datasheet" "http://www.farnell.com/datasheets/2631211.pdf"
			(at 0 0 0)
			(layer "F.Fab")
			(hide yes)
			(effects
				(font
					(size 1.27 1.27)
					(thickness 0.15)
				)
			)
		)
		(property "Author" "Antmicro"
			(at 0 0 0)
			(layer "F.Fab")
			(hide yes)
			(effects
				(font
					(size 1 1)
					(thickness 0.15)
				)
			)
		)
		(property "License" "Apache-2.0"
			(at 0 0 0)
			(layer "F.Fab")
			(hide yes)
			(effects
				(font
					(size 1 1)
					(thickness 0.15)
				)
			)
		)
		(property "MPN" "KMR211NGLFS"
			(at 0 0 0)
			(layer "F.Fab")
			(hide yes)
			(effects
				(font
					(size 1 1)
					(thickness 0.15)
				)
			)
		)
		(property "Manufacturer" "C&K"
			(at 0 0 0)
			(layer "F.Fab")
			(hide yes)
			(effects
				(font
					(size 1 1)
					(thickness 0.15)
				)
			)
		)
		(sheetname "/DDR5 SODIMM/")
		(sheetfile "ddr5-sodimm.kicad_sch")
		(attr smd)
		(fp_line
			(start -2.1 -1.6)
			(end -2.1 -1.499)
			(stroke
				(width 0.15)
				(type solid)
			)
			(layer "F.SilkS")
		)
		(fp_line
			(start -2.1 1.601)
			(end -2.1 1.48)
			(stroke
				(width 0.15)
				(type solid)
			)
			(layer "F.SilkS")
		)
		(fp_line
			(start 2.101 -1.6)
			(end -2.1 -1.6)
			(stroke
				(width 0.15)
				(type solid)
			)
			(layer "F.SilkS")
		)
		(fp_line
			(start 2.101 -1.58)
			(end 2.101 -1.459)
			(stroke
				(width 0.15)
				(type solid)
			)
			(layer "F.SilkS")
		)
		(fp_line
			(start 2.101 1.601)
			(end -2.1 1.601)
			(stroke
				(width 0.15)
				(type solid)
			)
			(layer "F.SilkS")
		)
		(fp_line
			(start 2.101 1.601)
			(end 2.101 1.48)
			(stroke
				(width 0.15)
				(type solid)
			)
			(layer "F.SilkS")
		)
		(fp_rect
			(start 2.751 1.75)
			(end -2.748 -1.749)
			(stroke
				(width 0.05)
				(type solid)
			)
			(fill no)
			(layer "F.CrtYd")
		)
		(fp_line
			(start -2.1 -1.6)
			(end -2.1 1.601)
			(stroke
				(width 0.15)
				(type solid)
			)
			(layer "F.Fab")
		)
		(fp_line
			(start -2.1 1.601)
			(end 2.101 1.601)
			(stroke
				(width 0.15)
				(type solid)
			)
			(layer "F.Fab")
		)
		(fp_line
			(start -0.248 -0.8)
			(end 0.25 -0.8)
			(stroke
				(width 0.15)
				(type solid)
			)
			(layer "F.Fab")
		)
		(fp_line
			(start 0.25 0.802)
			(end -0.248 0.802)
			(stroke
				(width 0.15)
				(type solid)
			)
			(layer "F.Fab")
		)
		(fp_line
			(start 2.101 -1.6)
			(end -2.1 -1.6)
			(stroke
				(width 0.15)
				(type solid)
			)
			(layer "F.Fab")
		)
		(fp_line
			(start 2.101 1.601)
			(end 2.101 -1.6)
			(stroke
				(width 0.15)
				(type solid)
			)
			(layer "F.Fab")
		)
		(fp_arc
			(start -0.248 0.802)
			(mid -1.050001 0.001)
			(end -0.248 -0.8)
			(stroke
				(width 0.15)
				(type solid)
			)
			(layer "F.Fab")
		)
		(fp_arc
			(start 0.25 -0.8)
			(mid 1.051001 0.001)
			(end 0.25 0.802)
			(stroke
				(width 0.15)
				(type solid)
			)
			(layer "F.Fab")
		)
		(pad "1" smd rect
			(at -2.048 -0.8 180)
			(size 0.9 1)
			(layers "F.Cu" "F.Mask" "F.Paste")
			(net 1 "GND")
			(pinfunction "1")
			(pintype "passive")
		)
		(pad "2" smd rect
			(at 2.05 -0.8 180)
			(size 0.9 1)
			(layers "F.Cu" "F.Mask" "F.Paste")
			(net 1 "GND")
			(pinfunction "2")
			(pintype "passive")
		)
		(pad "3" smd rect
			(at -2.048 0.802 180)
			(size 0.9 1)
			(layers "F.Cu" "F.Mask" "F.Paste")
			(net 106 "HOT_SWAP_BUTTON")
			(pinfunction "3")
			(pintype "passive")
		)
		(pad "4" smd rect
			(at 2.05 0.802 180)
			(size 0.9 1)
			(layers "F.Cu" "F.Mask" "F.Paste")
			(net 106 "HOT_SWAP_BUTTON")
			(pinfunction "4")
			(pintype "passive")
		)
	)
	(footprint "antmicro-footprints:SC70-3"
		(layer "F.Cu")
		(at 83.650501 122.926 90)
		(property "Reference" "Q4"
			(at 0 -1.6 90)
			(layer "F.SilkS")
			(hide yes)
			(effects
				(font
					(size 0.7 0.7)
					(thickness 0.15)
				)
				(justify left bottom)
			)
		)
		(property "Value" "BSS138PW,115"
			(at 0 2.3 90)
			(layer "F.Fab")
			(effects
				(font
					(size 0.7 0.7)
					(thickness 0.15)
				)
				(justify left bottom)
			)
		)
		(property "Datasheet" "https://assets.nexperia.com/documents/data-sheet/BSS138PW.pdf"
			(at 0 0 90)
			(layer "F.Fab")
			(hide yes)
			(effects
				(font
					(size 1.27 1.27)
					(thickness 0.15)
				)
			)
		)
		(property "Description" "Power MOSFET, N Channel, 60 V, 320 mA, 0.9 ohm, SOT-323, Surface Mount"
			(at 0 0 90)
			(layer "F.Fab")
			(hide yes)
			(effects
				(font
					(size 1.27 1.27)
					(thickness 0.15)
				)
			)
		)
		(property "Author" "Antmicro"
			(at 206.576501 39.275499 0)
			(layer "F.Fab")
			(hide yes)
			(effects
				(font
					(size 1 1)
					(thickness 0.15)
				)
			)
		)
		(property "License" "Apache-2.0"
			(at 206.576501 39.275499 0)
			(layer "F.Fab")
			(hide yes)
			(effects
				(font
					(size 1 1)
					(thickness 0.15)
				)
			)
		)
		(property "MPN" "BSS138PW,115"
			(at 206.576501 39.275499 0)
			(layer "F.Fab")
			(hide yes)
			(effects
				(font
					(size 1 1)
					(thickness 0.15)
				)
			)
		)
		(property "Manufacturer" "Nexperia"
			(at 206.576501 39.275499 0)
			(layer "F.Fab")
			(hide yes)
			(effects
				(font
					(size 1 1)
					(thickness 0.15)
				)
			)
		)
		(sheetname "/FPGA bank 14/")
		(sheetfile "fpga-bank-14.kicad_sch")
		(attr smd)
		(fp_line
			(start -0.3 -1)
			(end 0.627 -0.999)
			(stroke
				(width 0.15)
				(type solid)
			)
			(layer "F.SilkS")
		)
		(fp_line
			(start 0.627 -0.6)
			(end 0.627 -0.999)
			(stroke
				(width 0.15)
				(type solid)
			)
			(layer "F.SilkS")
		)
		(fp_line
			(start 0.627 0.6)
			(end 0.627 1.001)
			(stroke
				(width 0.15)
				(type solid)
			)
			(layer "F.SilkS")
		)
		(fp_line
			(start -0.3 1)
			(end 0.627 1.001)
			(stroke
				(width 0.15)
				(type solid)
			)
			(layer "F.SilkS")
		)
		(fp_line
			(start 0.9 -1.3)
			(end 0.9 -0.4)
			(stroke
				(width 0.05)
				(type solid)
			)
			(layer "F.CrtYd")
		)
		(fp_line
			(start -0.9 -1.3)
			(end 0.9 -1.3)
			(stroke
				(width 0.05)
				(type solid)
			)
			(layer "F.CrtYd")
		)
		(fp_line
			(start -0.9 -1.3)
			(end -0.9 -1)
			(stroke
				(width 0.05)
				(type solid)
			)
			(layer "F.CrtYd")
		)
		(fp_line
			(start -0.9 -1)
			(end -1.4 -1)
			(stroke
				(width 0.05)
				(type solid)
			)
			(layer "F.CrtYd")
		)
		(fp_line
			(start 1.4 -0.4)
			(end 1.4 0.4)
			(stroke
				(width 0.05)
				(type solid)
			)
			(layer "F.CrtYd")
		)
		(fp_line
			(start 0.9 -0.4)
			(end 1.4 -0.4)
			(stroke
				(width 0.05)
				(type solid)
			)
			(layer "F.CrtYd")
		)
		(fp_line
			(start 1.4 0.4)
			(end 0.9 0.4)
			(stroke
				(width 0.05)
				(type solid)
			)
			(layer "F.CrtYd")
		)
		(fp_line
			(start 0.9 0.4)
			(end 0.9 1.3)
			(stroke
				(width 0.05)
				(type solid)
			)
			(layer "F.CrtYd")
		)
		(fp_line
			(start -0.9 1)
			(end -1.4 1)
			(stroke
				(width 0.05)
				(type solid)
			)
			(layer "F.CrtYd")
		)
		(fp_line
			(start -1.4 1)
			(end -1.4 -1)
			(stroke
				(width 0.05)
				(type solid)
			)
			(layer "F.CrtYd")
		)
		(fp_line
			(start 0.9 1.3)
			(end -0.9 1.3)
			(stroke
				(width 0.05)
				(type solid)
			)
			(layer "F.CrtYd")
		)
		(fp_line
			(start -0.9 1.3)
			(end -0.9 1)
			(stroke
				(width 0.05)
				(type solid)
			)
			(layer "F.CrtYd")
		)
		(fp_rect
			(start -0.623 -0.999)
			(end 0.627 1.001)
			(stroke
				(width 0.15)
				(type solid)
			)
			(fill no)
			(layer "F.Fab")
		)
		(pad "1" smd rect
			(at -1.051 -0.65 180)
			(size 0.6 0.6)
			(layers "F.Cu" "F.Mask" "F.Paste")
			(net 615 "/FPGA bank 14/USR_LED1")
			(pinfunction "G")
			(pintype "input")
		)
		(pad "2" smd rect
			(at -1.051 0.65 180)
			(size 0.6 0.6)
			(layers "F.Cu" "F.Mask" "F.Paste")
			(net 1 "GND")
			(pinfunction "S")
			(pintype "passive")
		)
		(pad "3" smd rect
			(at 1.05 0 180)
			(size 0.6 0.6)
			(layers "F.Cu" "F.Mask" "F.Paste")
			(net 353 "Net-(Q4-D)")
			(pinfunction "D")
			(pintype "passive")
		)
	)
	(footprint "antmicro-footprints:R_0402_1005Metric"
		(layer "F.Cu")
		(at 77.7 153.2 180)
		(descr "Resistor SMD 0402")
		(tags "resistor SMD 0402")
		(property "Reference" "R68"
			(at -1.122484 -0.772697 180)
			(layer "F.SilkS")
			(hide yes)
			(effects
				(font
					(size 0.7 0.7)
					(thickness 0.15)
				)
				(justify left bottom)
			)
		)
		(property "Value" "R_5k11_0402"
			(at -1.011843 1.772047 180)
			(layer "F.Fab")
			(effects
				(font
					(size 0.7 0.7)
					(thickness 0.15)
				)
				(justify left bottom)
			)
		)
		(property "Datasheet" "https://www.bourns.com/docs/product-datasheets/cr.pdf"
			(at 0 0 180)
			(layer "F.Fab")
			(hide yes)
			(effects
				(font
					(size 1.27 1.27)
					(thickness 0.15)
				)
			)
		)
		(property "Author" "Antmicro"
			(at 155.4 306.4 0)
			(layer "F.Fab")
			(hide yes)
			(effects
				(font
					(size 1 1)
					(thickness 0.15)
				)
			)
		)
		(property "License" "Apache-2.0"
			(at 155.4 306.4 0)
			(layer "F.Fab")
			(hide yes)
			(effects
				(font
					(size 1 1)
					(thickness 0.15)
				)
			)
		)
		(property "MPN" "CR0402-FX-5111GLF"
			(at 155.4 306.4 0)
			(layer "F.Fab")
			(hide yes)
			(effects
				(font
					(size 1 1)
					(thickness 0.15)
				)
			)
		)
		(property "Manufacturer" "Bourns"
			(at 155.4 306.4 0)
			(layer "F.Fab")
			(hide yes)
			(effects
				(font
					(size 1 1)
					(thickness 0.15)
				)
			)
		)
		(property "Tolerance" "1%"
			(at 155.4 306.4 0)
			(layer "F.Fab")
			(hide yes)
			(effects
				(font
					(size 1 1)
					(thickness 0.15)
				)
			)
		)
		(property "Val" "5k11"
			(at 155.4 306.4 0)
			(layer "F.Fab")
			(hide yes)
			(effects
				(font
					(size 1 1)
					(thickness 0.15)
				)
			)
		)
		(sheetname "/Debug FTDI/")
		(sheetfile "debug-ftdi.kicad_sch")
		(attr smd)
		(fp_rect
			(start -0.93 -0.47)
			(end 0.93 0.47)
			(stroke
				(width 0.05)
				(type solid)
			)
			(fill no)
			(layer "F.CrtYd")
		)
		(fp_rect
			(start -0.5 -0.25)
			(end 0.5 0.25)
			(stroke
				(width 0.15)
				(type solid)
			)
			(fill no)
			(layer "F.Fab")
		)
		(pad "1" smd roundrect
			(at -0.485 0 180)
			(size 0.59 0.64)
			(layers "F.Cu" "F.Mask" "F.Paste")
			(roundrect_rratio 0.25)
			(net 1 "GND")
			(pintype "passive")
		)
		(pad "2" smd roundrect
			(at 0.485 0 180)
			(size 0.59 0.64)
			(layers "F.Cu" "F.Mask" "F.Paste")
			(roundrect_rratio 0.25)
			(net 321 "Net-(J3-CC_{1})")
			(pintype "passive")
		)
	)
	(footprint "antmicro-footprints:SC70-3"
		(layer "F.Cu")
		(at 91.750501 129.249 90)
		(property "Reference" "Q3"
			(at 0 -1.6 90)
			(layer "F.SilkS")
			(hide yes)
			(effects
				(font
					(size 0.7 0.7)
					(thickness 0.15)
				)
				(justify left bottom)
			)
		)
		(property "Value" "BSS138PW,115"
			(at 0 2.3 90)
			(layer "F.Fab")
			(effects
				(font
					(size 0.7 0.7)
					(thickness 0.15)
				)
				(justify left bottom)
			)
		)
		(property "Datasheet" "https://assets.nexperia.com/documents/data-sheet/BSS138PW.pdf"
			(at 0 0 90)
			(layer "F.Fab")
			(hide yes)
			(effects
				(font
					(size 1.27 1.27)
					(thickness 0.15)
				)
			)
		)
		(property "Description" "Power MOSFET, N Channel, 60 V, 320 mA, 0.9 ohm, SOT-323, Surface Mount"
			(at 0 0 90)
			(layer "F.Fab")
			(hide yes)
			(effects
				(font
					(size 1.27 1.27)
					(thickness 0.15)
				)
			)
		)
		(property "Author" "Antmicro"
			(at 220.999501 37.498499 0)
			(layer "F.Fab")
			(hide yes)
			(effects
				(font
					(size 1 1)
					(thickness 0.15)
				)
			)
		)
		(property "License" "Apache-2.0"
			(at 220.999501 37.498499 0)
			(layer "F.Fab")
			(hide yes)
			(effects
				(font
					(size 1 1)
					(thickness 0.15)
				)
			)
		)
		(property "MPN" "BSS138PW,115"
			(at 220.999501 37.498499 0)
			(layer "F.Fab")
			(hide yes)
			(effects
				(font
					(size 1 1)
					(thickness 0.15)
				)
			)
		)
		(property "Manufacturer" "Nexperia"
			(at 220.999501 37.498499 0)
			(layer "F.Fab")
			(hide yes)
			(effects
				(font
					(size 1 1)
					(thickness 0.15)
				)
			)
		)
		(sheetname "/FPGA Config/")
		(sheetfile "fpga-config.kicad_sch")
		(attr smd)
		(fp_line
			(start -0.3 -1)
			(end 0.627 -0.999)
			(stroke
				(width 0.15)
				(type solid)
			)
			(layer "F.SilkS")
		)
		(fp_line
			(start 0.627 -0.6)
			(end 0.627 -0.999)
			(stroke
				(width 0.15)
				(type solid)
			)
			(layer "F.SilkS")
		)
		(fp_line
			(start 0.627 0.6)
			(end 0.627 1.001)
			(stroke
				(width 0.15)
				(type solid)
			)
			(layer "F.SilkS")
		)
		(fp_line
			(start -0.3 1)
			(end 0.627 1.001)
			(stroke
				(width 0.15)
				(type solid)
			)
			(layer "F.SilkS")
		)
		(fp_line
			(start 0.9 -1.3)
			(end 0.9 -0.4)
			(stroke
				(width 0.05)
				(type solid)
			)
			(layer "F.CrtYd")
		)
		(fp_line
			(start -0.9 -1.3)
			(end 0.9 -1.3)
			(stroke
				(width 0.05)
				(type solid)
			)
			(layer "F.CrtYd")
		)
		(fp_line
			(start -0.9 -1.3)
			(end -0.9 -1)
			(stroke
				(width 0.05)
				(type solid)
			)
			(layer "F.CrtYd")
		)
		(fp_line
			(start -0.9 -1)
			(end -1.4 -1)
			(stroke
				(width 0.05)
				(type solid)
			)
			(layer "F.CrtYd")
		)
		(fp_line
			(start 1.4 -0.4)
			(end 1.4 0.4)
			(stroke
				(width 0.05)
				(type solid)
			)
			(layer "F.CrtYd")
		)
		(fp_line
			(start 0.9 -0.4)
			(end 1.4 -0.4)
			(stroke
				(width 0.05)
				(type solid)
			)
			(layer "F.CrtYd")
		)
		(fp_line
			(start 1.4 0.4)
			(end 0.9 0.4)
			(stroke
				(width 0.05)
				(type solid)
			)
			(layer "F.CrtYd")
		)
		(fp_line
			(start 0.9 0.4)
			(end 0.9 1.3)
			(stroke
				(width 0.05)
				(type solid)
			)
			(layer "F.CrtYd")
		)
		(fp_line
			(start -0.9 1)
			(end -1.4 1)
			(stroke
				(width 0.05)
				(type solid)
			)
			(layer "F.CrtYd")
		)
		(fp_line
			(start -1.4 1)
			(end -1.4 -1)
			(stroke
				(width 0.05)
				(type solid)
			)
			(layer "F.CrtYd")
		)
		(fp_line
			(start 0.9 1.3)
			(end -0.9 1.3)
			(stroke
				(width 0.05)
				(type solid)
			)
			(layer "F.CrtYd")
		)
		(fp_line
			(start -0.9 1.3)
			(end -0.9 1)
			(stroke
				(width 0.05)
				(type solid)
			)
			(layer "F.CrtYd")
		)
		(fp_rect
			(start -0.623 -0.999)
			(end 0.627 1.001)
			(stroke
				(width 0.15)
				(type solid)
			)
			(fill no)
			(layer "F.Fab")
		)
		(pad "1" smd rect
			(at -1.051 -0.65 180)
			(size 0.6 0.6)
			(layers "F.Cu" "F.Mask" "F.Paste")
			(net 614 "/FPGA Config/INIT_B")
			(pinfunction "G")
			(pintype "input")
		)
		(pad "2" smd rect
			(at -1.051 0.65 180)
			(size 0.6 0.6)
			(layers "F.Cu" "F.Mask" "F.Paste")
			(net 1 "GND")
			(pinfunction "S")
			(pintype "passive")
		)
		(pad "3" smd rect
			(at 1.05 0 180)
			(size 0.6 0.6)
			(layers "F.Cu" "F.Mask" "F.Paste")
			(net 352 "Net-(Q3-D)")
			(pinfunction "D")
			(pintype "passive")
		)
	)
	(footprint "antmicro-footprints:C_0402_1005Metric"
		(layer "F.Cu")
		(at 176.619502 196.214503 180)
		(descr "Capacitor SMD 0402")
		(tags "capacitor SMD 0402")
		(property "Reference" "C221"
			(at 0.969502 0.614503 180)
			(layer "F.SilkS")
			(hide yes)
			(effects
				(font
					(size 0.7 0.7)
					(thickness 0.15)
				)
				(justify left bottom)
			)
		)
		(property "Value" "C_22p_0402"
			(at -1.022927 2.155213 180)
			(layer "F.Fab")
			(effects
				(font
					(size 0.7 0.7)
					(thickness 0.15)
				)
				(justify left bottom)
			)
		)
		(property "Datasheet" "https://www.yageo.com/en/Chart/Download/pdf/CC0402JRNPO9BN220"
			(at 0 0 180)
			(layer "F.Fab")
			(hide yes)
			(effects
				(font
					(size 1.27 1.27)
					(thickness 0.15)
				)
			)
		)
		(property "Author" "Antmicro"
			(at 353.239004 392.429006 0)
			(layer "F.Fab")
			(hide yes)
			(effects
				(font
					(size 1 1)
					(thickness 0.15)
				)
			)
		)
		(property "Dielectric" ""
			(at 353.239004 392.429006 0)
			(layer "F.Fab")
			(hide yes)
			(effects
				(font
					(size 1 1)
					(thickness 0.15)
				)
			)
		)
		(property "License" "Apache-2.0"
			(at 353.239004 392.429006 0)
			(layer "F.Fab")
			(hide yes)
			(effects
				(font
					(size 1 1)
					(thickness 0.15)
				)
			)
		)
		(property "MPN" "CC0402JRNPO9BN220"
			(at 353.239004 392.429006 0)
			(layer "F.Fab")
			(hide yes)
			(effects
				(font
					(size 1 1)
					(thickness 0.15)
				)
			)
		)
		(property "Manufacturer" "YAGEO"
			(at 353.239004 392.429006 0)
			(layer "F.Fab")
			(hide yes)
			(effects
				(font
					(size 1 1)
					(thickness 0.15)
				)
			)
		)
		(property "Val" "22p"
			(at 353.239004 392.429006 0)
			(layer "F.Fab")
			(hide yes)
			(effects
				(font
					(size 1 1)
					(thickness 0.15)
				)
			)
		)
		(property "Voltage" ""
			(at 353.239004 392.429006 0)
			(layer "F.Fab")
			(hide yes)
			(effects
				(font
					(size 1 1)
					(thickness 0.15)
				)
			)
		)
		(sheetname "/Supply/")
		(sheetfile "supply.kicad_sch")
		(attr smd)
		(fp_rect
			(start -0.9659 -0.481258)
			(end 0.9649 0.458742)
			(stroke
				(width 0.05)
				(type solid)
			)
			(fill no)
			(layer "F.CrtYd")
		)
		(fp_line
			(start 0.499 0.248)
			(end -0.499 0.248)
			(stroke
				(width 0.15)
				(type solid)
			)
			(layer "F.Fab")
		)
		(fp_line
			(start 0.499 -0.25)
			(end 0.499 0.248)
			(stroke
				(width 0.15)
				(type solid)
			)
			(layer "F.Fab")
		)
		(fp_line
			(start -0.499 0.248)
			(end -0.499 -0.25)
			(stroke
				(width 0.15)
				(type solid)
			)
			(layer "F.Fab")
		)
		(fp_line
			(start -0.499 -0.25)
			(end 0.499 -0.25)
			(stroke
				(width 0.15)
				(type solid)
			)
			(layer "F.Fab")
		)
		(pad "1" smd roundrect
			(at -0.484 0 180)
			(size 0.59 0.64)
			(layers "F.Cu" "F.Mask" "F.Paste")
			(roundrect_rratio 0.25)
			(net 303 "Net-(C221-Pad1)")
			(pintype "passive")
		)
		(pad "2" smd roundrect
			(at 0.484 0 180)
			(size 0.59 0.64)
			(layers "F.Cu" "F.Mask" "F.Paste")
			(roundrect_rratio 0.25)
			(net 78 "/Supply/1V0_REG")
			(pintype "passive")
		)
	)
	(footprint "antmicro-footprints:TP_SMD_1mm"
		(layer "F.Cu")
		(at 165.25 199.15)
		(property "Reference" "TP10"
			(at 0 -0.731898 0)
			(layer "F.SilkS")
			(hide yes)
			(effects
				(font
					(size 0.7 0.7)
					(thickness 0.15)
				)
				(justify left bottom)
			)
		)
		(property "Value" "TP_1mm_SMD"
			(at 0 1.4 0)
			(layer "F.Fab")
			(effects
				(font
					(size 0.7 0.7)
					(thickness 0.15)
				)
				(justify left bottom)
			)
		)
		(property "Author" "Antmicro"
			(at 0 0 0)
			(layer "F.Fab")
			(hide yes)
			(effects
				(font
					(size 1 1)
					(thickness 0.15)
				)
			)
		)
		(property "License" "Apache-2.0"
			(at 0 0 0)
			(layer "F.Fab")
			(hide yes)
			(effects
				(font
					(size 1 1)
					(thickness 0.15)
				)
			)
		)
		(property "MPN" ""
			(at 0 0 0)
			(layer "F.Fab")
			(hide yes)
			(effects
				(font
					(size 1 1)
					(thickness 0.15)
				)
			)
		)
		(property "Manufacturer" ""
			(at 0 0 0)
			(layer "F.Fab")
			(hide yes)
			(effects
				(font
					(size 1 1)
					(thickness 0.15)
				)
			)
		)
		(sheetname "/Supply/")
		(sheetfile "supply.kicad_sch")
		(attr exclude_from_pos_files)
		(pad "1" smd circle
			(at 0 0)
			(size 1 1)
			(layers "F.Cu" "F.Mask")
			(net 227 "+1V0")
			(pinfunction "1")
			(pintype "passive")
		)
	)
	(footprint "antmicro-footprints:C_0402_1005Metric"
		(layer "F.Cu")
		(at 105.175001 148.9025 180)
		(descr "Capacitor SMD 0402")
		(tags "capacitor SMD 0402")
		(property "Reference" "C7"
			(at 0 -0.699 180)
			(layer "F.SilkS")
			(hide yes)
			(effects
				(font
					(size 0.7 0.7)
					(thickness 0.15)
				)
				(justify left bottom)
			)
		)
		(property "Value" "C_4u7_0402"
			(at -1.022927 2.155213 180)
			(layer "F.Fab")
			(effects
				(font
					(size 0.7 0.7)
					(thickness 0.15)
				)
				(justify left bottom)
			)
		)
		(property "Datasheet" "https://www.murata.com/products/productdetail?partno=GRM155R61A475MEAA%23"
			(at 0 0 180)
			(layer "F.Fab")
			(hide yes)
			(effects
				(font
					(size 1.27 1.27)
					(thickness 0.15)
				)
			)
		)
		(property "Author" "Antmicro"
			(at 210.350002 297.805 0)
			(layer "F.Fab")
			(hide yes)
			(effects
				(font
					(size 1 1)
					(thickness 0.15)
				)
			)
		)
		(property "Dielectric" ""
			(at 210.350002 297.805 0)
			(layer "F.Fab")
			(hide yes)
			(effects
				(font
					(size 1 1)
					(thickness 0.15)
				)
			)
		)
		(property "License" "Apache-2.0"
			(at 210.350002 297.805 0)
			(layer "F.Fab")
			(hide yes)
			(effects
				(font
					(size 1 1)
					(thickness 0.15)
				)
			)
		)
		(property "MPN" "GRM155R61A475MEAAD"
			(at 210.350002 297.805 0)
			(layer "F.Fab")
			(hide yes)
			(effects
				(font
					(size 1 1)
					(thickness 0.15)
				)
			)
		)
		(property "Manufacturer" "Murata"
			(at 210.350002 297.805 0)
			(layer "F.Fab")
			(hide yes)
			(effects
				(font
					(size 1 1)
					(thickness 0.15)
				)
			)
		)
		(property "Val" "4u7"
			(at 210.350002 297.805 0)
			(layer "F.Fab")
			(hide yes)
			(effects
				(font
					(size 1 1)
					(thickness 0.15)
				)
			)
		)
		(property "Voltage" ""
			(at 210.350002 297.805 0)
			(layer "F.Fab")
			(hide yes)
			(effects
				(font
					(size 1 1)
					(thickness 0.15)
				)
			)
		)
		(sheetname "/DDR5 SODIMM/")
		(sheetfile "ddr5-sodimm.kicad_sch")
		(attr smd)
		(fp_rect
			(start -0.9659 -0.481258)
			(end 0.9649 0.458742)
			(stroke
				(width 0.05)
				(type solid)
			)
			(fill no)
			(layer "F.CrtYd")
		)
		(fp_line
			(start 0.499 0.248)
			(end -0.499 0.248)
			(stroke
				(width 0.15)
				(type solid)
			)
			(layer "F.Fab")
		)
		(fp_line
			(start 0.499 -0.25)
			(end 0.499 0.248)
			(stroke
				(width 0.15)
				(type solid)
			)
			(layer "F.Fab")
		)
		(fp_line
			(start -0.499 0.248)
			(end -0.499 -0.25)
			(stroke
				(width 0.15)
				(type solid)
			)
			(layer "F.Fab")
		)
		(fp_line
			(start -0.499 -0.25)
			(end 0.499 -0.25)
			(stroke
				(width 0.15)
				(type solid)
			)
			(layer "F.Fab")
		)
		(pad "1" smd roundrect
			(at -0.484 0 180)
			(size 0.59 0.64)
			(layers "F.Cu" "F.Mask" "F.Paste")
			(roundrect_rratio 0.25)
			(net 201 "+5V")
			(pintype "passive")
		)
		(pad "2" smd roundrect
			(at 0.484 0 180)
			(size 0.59 0.64)
			(layers "F.Cu" "F.Mask" "F.Paste")
			(roundrect_rratio 0.25)
			(net 1 "GND")
			(pintype "passive")
		)
	)
	(footprint "antmicro-footprints:C_0402_1005Metric"
		(layer "F.Cu")
		(at 176.119502 192.714502 -90)
		(descr "Capacitor SMD 0402")
		(tags "capacitor SMD 0402")
		(property "Reference" "C201"
			(at 0 -0.699 270)
			(layer "F.SilkS")
			(hide yes)
			(effects
				(font
					(size 0.7 0.7)
					(thickness 0.15)
				)
				(justify left bottom)
			)
		)
		(property "Value" "C_470n_0402"
			(at -1.022927 2.155213 270)
			(layer "F.Fab")
			(effects
				(font
					(size 0.7 0.7)
					(thickness 0.15)
				)
				(justify left bottom)
			)
		)
		(property "Datasheet" "https://product.tdk.com/en/search/capacitor/ceramic/mlcc/info?part_no=C1005X5R1E474M050BB"
			(at 0 0 270)
			(layer "F.Fab")
			(hide yes)
			(effects
				(font
					(size 1.27 1.27)
					(thickness 0.15)
				)
			)
		)
		(property "Author" "Antmicro"
			(at -16.595 368.834004 0)
			(layer "F.Fab")
			(hide yes)
			(effects
				(font
					(size 1 1)
					(thickness 0.15)
				)
			)
		)
		(property "Dielectric" ""
			(at -16.595 368.834004 0)
			(layer "F.Fab")
			(hide yes)
			(effects
				(font
					(size 1 1)
					(thickness 0.15)
				)
			)
		)
		(property "License" "Apache-2.0"
			(at -16.595 368.834004 0)
			(layer "F.Fab")
			(hide yes)
			(effects
				(font
					(size 1 1)
					(thickness 0.15)
				)
			)
		)
		(property "MPN" "C1005X5R1E474M050BB"
			(at -16.595 368.834004 0)
			(layer "F.Fab")
			(hide yes)
			(effects
				(font
					(size 1 1)
					(thickness 0.15)
				)
			)
		)
		(property "Manufacturer" "TDK"
			(at -16.595 368.834004 0)
			(layer "F.Fab")
			(hide yes)
			(effects
				(font
					(size 1 1)
					(thickness 0.15)
				)
			)
		)
		(property "Val" "470n"
			(at -16.595 368.834004 0)
			(layer "F.Fab")
			(hide yes)
			(effects
				(font
					(size 1 1)
					(thickness 0.15)
				)
			)
		)
		(property "Voltage" ""
			(at -16.595 368.834004 0)
			(layer "F.Fab")
			(hide yes)
			(effects
				(font
					(size 1 1)
					(thickness 0.15)
				)
			)
		)
		(sheetname "/Supply/")
		(sheetfile "supply.kicad_sch")
		(attr smd)
		(fp_rect
			(start -0.9659 -0.481258)
			(end 0.9649 0.458742)
			(stroke
				(width 0.05)
				(type solid)
			)
			(fill no)
			(layer "F.CrtYd")
		)
		(fp_line
			(start -0.499 0.248)
			(end -0.499 -0.25)
			(stroke
				(width 0.15)
				(type solid)
			)
			(layer "F.Fab")
		)
		(fp_line
			(start 0.499 0.248)
			(end -0.499 0.248)
			(stroke
				(width 0.15)
				(type solid)
			)
			(layer "F.Fab")
		)
		(fp_line
			(start -0.499 -0.25)
			(end 0.499 -0.25)
			(stroke
				(width 0.15)
				(type solid)
			)
			(layer "F.Fab")
		)
		(fp_line
			(start 0.499 -0.25)
			(end 0.499 0.248)
			(stroke
				(width 0.15)
				(type solid)
			)
			(layer "F.Fab")
		)
		(pad "1" smd roundrect
			(at -0.484 0 270)
			(size 0.59 0.64)
			(layers "F.Cu" "F.Mask" "F.Paste")
			(roundrect_rratio 0.25)
			(net 1 "GND")
			(pintype "passive")
		)
		(pad "2" smd roundrect
			(at 0.484 0 270)
			(size 0.59 0.64)
			(layers "F.Cu" "F.Mask" "F.Paste")
			(roundrect_rratio 0.25)
			(net 63 "/Supply/1V0_VCC")
			(pintype "passive")
		)
	)
	(footprint "antmicro-footprints:MicroSD_Wurth_693071020811"
		(layer "F.Cu")
		(at 74.470501 172.416 -90)
		(descr "SMT MICRO SD CARD CONNECTOR")
		(property "Reference" "J5"
			(at 9.784 5.270501 0)
			(layer "F.SilkS")
			(effects
				(font
					(size 0.7 0.7)
					(thickness 0.15)
				)
				(justify left bottom)
			)
		)
		(property "Value" "MicroSD_693071020811"
			(at 0 8.9 270)
			(layer "F.Fab")
			(effects
				(font
					(size 0.7 0.7)
					(thickness 0.15)
				)
				(justify left bottom)
			)
		)
		(property "Datasheet" "https://www.we-online.com/catalog/datasheet/693071020811.pdf"
			(at 0 0 270)
			(layer "F.Fab")
			(hide yes)
			(effects
				(font
					(size 1.27 1.27)
					(thickness 0.15)
				)
			)
		)
		(property "Author" "Antmicro"
			(at -97.945499 246.886501 0)
			(layer "F.Fab")
			(hide yes)
			(effects
				(font
					(size 1 1)
					(thickness 0.15)
				)
			)
		)
		(property "License" "Apache-2.0"
			(at -97.945499 246.886501 0)
			(layer "F.Fab")
			(hide yes)
			(effects
				(font
					(size 1 1)
					(thickness 0.15)
				)
			)
		)
		(property "MPN" "693071020811"
			(at -97.945499 246.886501 0)
			(layer "F.Fab")
			(hide yes)
			(effects
				(font
					(size 1 1)
					(thickness 0.15)
				)
			)
		)
		(property "Manufacturer" "Würth Elektronik"
			(at -97.945499 246.886501 0)
			(layer "F.Fab")
			(hide yes)
			(effects
				(font
					(size 1 1)
					(thickness 0.15)
				)
			)
		)
		(sheetname "/HDMI + SD Card/")
		(sheetfile "hdmi-sd-card.kicad_sch")
		(attr smd)
		(fp_line
			(start -7.35 1.432)
			(end -7.35 -5.267)
			(stroke
				(width 0.15)
				(type solid)
			)
			(layer "F.SilkS")
		)
		(fp_line
			(start 7.35 1.432)
			(end 7.35 -5.267)
			(stroke
				(width 0.15)
				(type solid)
			)
			(layer "F.SilkS")
		)
		(fp_line
			(start 6.201 -7.148)
			(end 2.801 -7.148)
			(stroke
				(width 0.15)
				(type solid)
			)
			(layer "F.SilkS")
		)
		(fp_circle
			(center 2.85 -7.9)
			(end 2.9 -7.9)
			(stroke
				(width 0.15)
				(type solid)
			)
			(fill yes)
			(layer "F.SilkS")
		)
		(fp_line
			(start -7.55 7.7)
			(end -7.55 4.55)
			(stroke
				(width 0.05)
				(type solid)
			)
			(layer "F.CrtYd")
		)
		(fp_line
			(start 7.5 7.7)
			(end -7.55 7.7)
			(stroke
				(width 0.05)
				(type solid)
			)
			(layer "F.CrtYd")
		)
		(fp_line
			(start 7.5 7.7)
			(end 7.5 4.55)
			(stroke
				(width 0.05)
				(type solid)
			)
			(layer "F.CrtYd")
		)
		(fp_line
			(start -8.7 4.55)
			(end -7.55 4.55)
			(stroke
				(width 0.05)
				(type solid)
			)
			(layer "F.CrtYd")
		)
		(fp_line
			(start -8.7 4.55)
			(end -8.7 1.6)
			(stroke
				(width 0.05)
				(type solid)
			)
			(layer "F.CrtYd")
		)
		(fp_line
			(start 8.7 4.55)
			(end 7.5 4.55)
			(stroke
				(width 0.05)
				(type solid)
			)
			(layer "F.CrtYd")
		)
		(fp_line
			(start 8.7 4.55)
			(end 8.7 1.6)
			(stroke
				(width 0.05)
				(type solid)
			)
			(layer "F.CrtYd")
		)
		(fp_line
			(start -7.55 1.6)
			(end -8.7 1.6)
			(stroke
				(width 0.05)
				(type solid)
			)
			(layer "F.CrtYd")
		)
		(fp_line
			(start 7.5 1.6)
			(end 8.7 1.6)
			(stroke
				(width 0.05)
				(type solid)
			)
			(layer "F.CrtYd")
		)
		(fp_line
			(start 7.5 1.6)
			(end 7.5 -5.45)
			(stroke
				(width 0.05)
				(type solid)
			)
			(layer "F.CrtYd")
		)
		(fp_line
			(start -7.55 -5.45)
			(end -7.55 1.6)
			(stroke
				(width 0.05)
				(type solid)
			)
			(layer "F.CrtYd")
		)
		(fp_line
			(start -7.55 -5.45)
			(end -9.1 -5.45)
			(stroke
				(width 0.05)
				(type solid)
			)
			(layer "F.CrtYd")
		)
		(fp_line
			(start 7.5 -5.45)
			(end 8.4 -5.45)
			(stroke
				(width 0.05)
				(type solid)
			)
			(layer "F.CrtYd")
		)
		(fp_line
			(start -9.1 -7.6)
			(end -9.1 -5.45)
			(stroke
				(width 0.05)
				(type solid)
			)
			(layer "F.CrtYd")
		)
		(fp_line
			(start -9.1 -7.6)
			(end -7.05 -7.6)
			(stroke
				(width 0.05)
				(type solid)
			)
			(layer "F.CrtYd")
		)
		(fp_line
			(start 2.75 -7.6)
			(end 2.75 -8.7)
			(stroke
				(width 0.05)
				(type solid)
			)
			(layer "F.CrtYd")
		)
		(fp_line
			(start 8.4 -7.6)
			(end 8.4 -5.45)
			(stroke
				(width 0.05)
				(type solid)
			)
			(layer "F.CrtYd")
		)
		(fp_line
			(start 8.4 -7.6)
			(end 2.75 -7.6)
			(stroke
				(width 0.05)
				(type solid)
			)
			(layer "F.CrtYd")
		)
		(fp_line
			(start -7.05 -8.7)
			(end -7.05 -7.6)
			(stroke
				(width 0.05)
				(type solid)
			)
			(layer "F.CrtYd")
		)
		(fp_line
			(start -7.05 -8.7)
			(end 2.75 -8.7)
			(stroke
				(width 0.05)
				(type solid)
			)
			(layer "F.CrtYd")
		)
		(fp_line
			(start -7.35 7.502)
			(end 7.35 7.502)
			(stroke
				(width 0.15)
				(type solid)
			)
			(layer "F.Fab")
		)
		(fp_line
			(start 7.35 7.353)
			(end 7.35 -7.148)
			(stroke
				(width 0.15)
				(type solid)
			)
			(layer "F.Fab")
		)
		(fp_line
			(start -7.35 -7.148)
			(end -7.35 7.353)
			(stroke
				(width 0.15)
				(type solid)
			)
			(layer "F.Fab")
		)
		(fp_line
			(start 7.35 -7.148)
			(end -7.35 -7.148)
			(stroke
				(width 0.15)
				(type solid)
			)
			(layer "F.Fab")
		)
		(pad "" np_thru_hole circle
			(at -4.95 3.485 270)
			(size 1 1)
			(drill 1)
			(layers "*.Cu" "*.Mask")
		)
		(pad "" np_thru_hole oval
			(at 3.05 3.485 270)
			(size 1.7 1)
			(drill oval 1.7 1)
			(layers "*.Cu" "*.Mask")
		)
		(pad "1" smd rect
			(at 2.25 -7.57 270)
			(size 0.7 1.9)
			(layers "F.Cu" "F.Mask" "F.Paste")
			(net 350 "/FPGA bank 16/SD.DAT2")
			(pinfunction "DAT2")
			(pintype "bidirectional")
		)
		(pad "2" smd rect
			(at 1.15 -7.57 270)
			(size 0.7 1.9)
			(layers "F.Cu" "F.Mask" "F.Paste")
			(net 371 "/FPGA bank 16/SD.DAT3")
			(pinfunction "DAT3/CD")
			(pintype "bidirectional")
		)
		(pad "3" smd rect
			(at 0.05 -7.57 270)
			(size 0.7 1.9)
			(layers "F.Cu" "F.Mask" "F.Paste")
			(net 372 "/FPGA bank 16/SD.CMD")
			(pinfunction "CMD")
			(pintype "input")
		)
		(pad "4" smd rect
			(at -1.05 -7.57 270)
			(size 0.7 1.9)
			(layers "F.Cu" "F.Mask" "F.Paste")
			(net 200 "+3V3")
			(pinfunction "VDD")
			(pintype "power_in")
		)
		(pad "5" smd rect
			(at -2.15 -7.57 270)
			(size 0.7 1.9)
			(layers "F.Cu" "F.Mask" "F.Paste")
			(net 373 "/FPGA bank 16/SD.CLK")
			(pinfunction "CLK")
			(pintype "input")
		)
		(pad "6" smd rect
			(at -3.25 -7.57 270)
			(size 0.7 1.9)
			(layers "F.Cu" "F.Mask" "F.Paste")
			(net 1 "GND")
			(pinfunction "VSS")
			(pintype "passive")
		)
		(pad "7" smd rect
			(at -4.35 -7.57 270)
			(size 0.7 1.9)
			(layers "F.Cu" "F.Mask" "F.Paste")
			(net 374 "/FPGA bank 16/SD.DAT0")
			(pinfunction "DAT0")
			(pintype "input")
		)
		(pad "8" smd rect
			(at -5.45 -7.57 270)
			(size 0.7 1.9)
			(layers "F.Cu" "F.Mask" "F.Paste")
			(net 594 "/FPGA bank 16/SD.DAT1")
			(pinfunction "DAT1")
			(pintype "input")
		)
		(pad "9" smd rect
			(at -6.55 -7.57 270)
			(size 0.7 1.9)
			(layers "F.Cu" "F.Mask" "F.Paste")
			(net 330 "Net-(J5-CD_SW1)")
			(pinfunction "CD_SW1")
			(pintype "passive")
		)
		(pad "SH" smd rect
			(at -8.1 -6.515 270)
			(size 1.7 1.8)
			(layers "F.Cu" "F.Mask" "F.Paste")
			(net 1 "GND")
			(pinfunction "SH")
			(pintype "passive")
		)
		(pad "SH" smd rect
			(at -7.85 3.08 270)
			(size 1.4 2.6)
			(layers "F.Cu" "F.Mask" "F.Paste")
			(net 1 "GND")
			(pinfunction "SH")
			(pintype "passive")
		)
		(pad "SH" smd rect
			(at 7.4 -6.515 270)
			(size 1.7 1.8)
			(layers "F.Cu" "F.Mask" "F.Paste")
			(net 1 "GND")
			(pinfunction "SH")
			(pintype "passive")
		)
		(pad "SH" smd rect
			(at 7.85 3.08 270)
			(size 1.4 2.6)
			(layers "F.Cu" "F.Mask" "F.Paste")
			(net 1 "GND")
			(pinfunction "SH")
			(pintype "passive")
		)
	)
	(footprint "antmicro-footprints:C_0402_1005Metric"
		(layer "F.Cu")
		(at 181.566 155.074999)
		(descr "Capacitor SMD 0402")
		(tags "capacitor SMD 0402")
		(property "Reference" "C216"
			(at 0 -0.699 0)
			(layer "F.SilkS")
			(hide yes)
			(effects
				(font
					(size 0.7 0.7)
					(thickness 0.15)
				)
				(justify left bottom)
			)
		)
		(property "Value" "C_100n_0402"
			(at -1.022927 2.155213 0)
			(layer "F.Fab")
			(effects
				(font
					(size 0.7 0.7)
					(thickness 0.15)
				)
				(justify left bottom)
			)
		)
		(property "Datasheet" "https://www.murata.com/products/productdetail?partno=GRM155R61H104KE14%23"
			(at 0 0 0)
			(layer "F.Fab")
			(hide yes)
			(effects
				(font
					(size 1.27 1.27)
					(thickness 0.15)
				)
			)
		)
		(property "Author" "Antmicro"
			(at 0 0 0)
			(layer "F.Fab")
			(hide yes)
			(effects
				(font
					(size 1 1)
					(thickness 0.15)
				)
			)
		)
		(property "Dielectric" "X5R"
			(at 0 0 0)
			(layer "F.Fab")
			(hide yes)
			(effects
				(font
					(size 1 1)
					(thickness 0.15)
				)
			)
		)
		(property "License" "Apache-2.0"
			(at 0 0 0)
			(layer "F.Fab")
			(hide yes)
			(effects
				(font
					(size 1 1)
					(thickness 0.15)
				)
			)
		)
		(property "MPN" "GRM155R61H104KE14D"
			(at 0 0 0)
			(layer "F.Fab")
			(hide yes)
			(effects
				(font
					(size 1 1)
					(thickness 0.15)
				)
			)
		)
		(property "Manufacturer" "Murata"
			(at 0 0 0)
			(layer "F.Fab")
			(hide yes)
			(effects
				(font
					(size 1 1)
					(thickness 0.15)
				)
			)
		)
		(property "Val" "100n"
			(at 0 0 0)
			(layer "F.Fab")
			(hide yes)
			(effects
				(font
					(size 1 1)
					(thickness 0.15)
				)
			)
		)
		(property "Voltage" "50V"
			(at 0 0 0)
			(layer "F.Fab")
			(hide yes)
			(effects
				(font
					(size 1 1)
					(thickness 0.15)
				)
			)
		)
		(sheetname "/Supply/")
		(sheetfile "supply.kicad_sch")
		(attr smd)
		(fp_rect
			(start -0.9659 -0.481258)
			(end 0.9649 0.458742)
			(stroke
				(width 0.05)
				(type solid)
			)
			(fill no)
			(layer "F.CrtYd")
		)
		(fp_line
			(start -0.499 -0.25)
			(end 0.499 -0.25)
			(stroke
				(width 0.15)
				(type solid)
			)
			(layer "F.Fab")
		)
		(fp_line
			(start -0.499 0.248)
			(end -0.499 -0.25)
			(stroke
				(width 0.15)
				(type solid)
			)
			(layer "F.Fab")
		)
		(fp_line
			(start 0.499 -0.25)
			(end 0.499 0.248)
			(stroke
				(width 0.15)
				(type solid)
			)
			(layer "F.Fab")
		)
		(fp_line
			(start 0.499 0.248)
			(end -0.499 0.248)
			(stroke
				(width 0.15)
				(type solid)
			)
			(layer "F.Fab")
		)
		(pad "1" smd roundrect
			(at -0.484 0)
			(size 0.59 0.64)
			(layers "F.Cu" "F.Mask" "F.Paste")
			(roundrect_rratio 0.25)
			(net 1 "GND")
			(pintype "passive")
		)
		(pad "2" smd roundrect
			(at 0.484 0)
			(size 0.59 0.64)
			(layers "F.Cu" "F.Mask" "F.Paste")
			(roundrect_rratio 0.25)
			(net 206 "+1V1")
			(pintype "passive")
		)
	)
	(footprint "antmicro-footprints:R_1206_3216Metric"
		(layer "F.Cu")
		(at 188.675 179.499 180)
		(property "Reference" "R142"
			(at 0.475 -1.951 180)
			(layer "F.SilkS")
			(effects
				(font
					(size 0.7 0.7)
					(thickness 0.15)
				)
				(justify left bottom)
			)
		)
		(property "Value" "R_0R01_1206"
			(at -2.422356 2.103591 180)
			(layer "F.Fab")
			(effects
				(font
					(size 0.7 0.7)
					(thickness 0.15)
				)
				(justify left bottom)
			)
		)
		(property "Datasheet" "https://www.yageo.com/upload/media/product/productsearch/datasheet/rchip/PYu-RL_Group_521_RoHS_L_2.pdf"
			(at 0 0 180)
			(layer "F.Fab")
			(hide yes)
			(effects
				(font
					(size 1.27 1.27)
					(thickness 0.15)
				)
			)
		)
		(property "Author" "Antmicro"
			(at 377.35 358.998 0)
			(layer "F.Fab")
			(hide yes)
			(effects
				(font
					(size 1 1)
					(thickness 0.15)
				)
			)
		)
		(property "License" "Apache-2.0"
			(at 377.35 358.998 0)
			(layer "F.Fab")
			(hide yes)
			(effects
				(font
					(size 1 1)
					(thickness 0.15)
				)
			)
		)
		(property "MPN" "RL1206FR-7W0R01L"
			(at 377.35 358.998 0)
			(layer "F.Fab")
			(hide yes)
			(effects
				(font
					(size 1 1)
					(thickness 0.15)
				)
			)
		)
		(property "Manufacturer" "YAGEO"
			(at 377.35 358.998 0)
			(layer "F.Fab")
			(hide yes)
			(effects
				(font
					(size 1 1)
					(thickness 0.15)
				)
			)
		)
		(property "Tolerance" "1%"
			(at 377.35 358.998 0)
			(layer "F.Fab")
			(hide yes)
			(effects
				(font
					(size 1 1)
					(thickness 0.15)
				)
			)
		)
		(property "Val" "0R01"
			(at 377.35 358.998 0)
			(layer "F.Fab")
			(hide yes)
			(effects
				(font
					(size 1 1)
					(thickness 0.15)
				)
			)
		)
		(sheetname "/Supply/")
		(sheetfile "supply.kicad_sch")
		(attr smd)
		(fp_line
			(start 0 0.9)
			(end 0.498 0.9)
			(stroke
				(width 0.15)
				(type solid)
			)
			(layer "F.SilkS")
		)
		(fp_line
			(start 0 0.9)
			(end -0.5 0.9)
			(stroke
				(width 0.15)
				(type solid)
			)
			(layer "F.SilkS")
		)
		(fp_line
			(start 0 -0.902)
			(end 0.498 -0.902)
			(stroke
				(width 0.15)
				(type solid)
			)
			(layer "F.SilkS")
		)
		(fp_line
			(start 0 -0.902)
			(end -0.5 -0.902)
			(stroke
				(width 0.15)
				(type solid)
			)
			(layer "F.SilkS")
		)
		(fp_rect
			(start -2.25 -1.05)
			(end 2.25 1.05)
			(stroke
				(width 0.05)
				(type solid)
			)
			(fill no)
			(layer "F.CrtYd")
		)
		(fp_line
			(start 1.6 -0.802)
			(end 1.6 0.8)
			(stroke
				(width 0.15)
				(type solid)
			)
			(layer "F.Fab")
		)
		(fp_line
			(start -1.601 0.8)
			(end 1.6 0.8)
			(stroke
				(width 0.15)
				(type solid)
			)
			(layer "F.Fab")
		)
		(fp_line
			(start -1.601 -0.802)
			(end 1.6 -0.802)
			(stroke
				(width 0.15)
				(type solid)
			)
			(layer "F.Fab")
		)
		(fp_line
			(start -1.601 -0.802)
			(end -1.601 0.8)
			(stroke
				(width 0.15)
				(type solid)
			)
			(layer "F.Fab")
		)
		(pad "1" smd roundrect
			(at -1.5 0 180)
			(size 1.2 1.8)
			(layers "F.Cu" "F.Mask" "F.Paste")
			(roundrect_rratio 0.15)
			(net 51 "/Supply/1V8_local")
			(pintype "passive")
		)
		(pad "2" smd roundrect
			(at 1.499 0 180)
			(size 1.2 1.8)
			(layers "F.Cu" "F.Mask" "F.Paste")
			(roundrect_rratio 0.15)
			(net 188 "+1V8")
			(pintype "passive")
		)
	)
	(footprint "antmicro-footprints:R_0402_1005Metric"
		(layer "F.Cu")
		(at 94.748501 126.719 -90)
		(descr "Resistor SMD 0402")
		(tags "resistor SMD 0402")
		(property "Reference" "R12"
			(at -1.122484 -0.772697 270)
			(layer "F.SilkS")
			(hide yes)
			(effects
				(font
					(size 0.7 0.7)
					(thickness 0.15)
				)
				(justify left bottom)
			)
		)
		(property "Value" "R_330R_0402"
			(at -1.011843 1.772047 270)
			(layer "F.Fab")
			(effects
				(font
					(size 0.7 0.7)
					(thickness 0.15)
				)
				(justify left bottom)
			)
		)
		(property "Datasheet" "https://www.bourns.com/docs/product-datasheets/cr.pdf"
			(at 0 0 270)
			(layer "F.Fab")
			(hide yes)
			(effects
				(font
					(size 1.27 1.27)
					(thickness 0.15)
				)
			)
		)
		(property "Author" "Antmicro"
			(at -31.970499 221.467501 0)
			(layer "F.Fab")
			(hide yes)
			(effects
				(font
					(size 1 1)
					(thickness 0.15)
				)
			)
		)
		(property "License" "Apache-2.0"
			(at -31.970499 221.467501 0)
			(layer "F.Fab")
			(hide yes)
			(effects
				(font
					(size 1 1)
					(thickness 0.15)
				)
			)
		)
		(property "MPN" "CR0402-FX-3300GLF"
			(at -31.970499 221.467501 0)
			(layer "F.Fab")
			(hide yes)
			(effects
				(font
					(size 1 1)
					(thickness 0.15)
				)
			)
		)
		(property "Manufacturer" "Bourns"
			(at -31.970499 221.467501 0)
			(layer "F.Fab")
			(hide yes)
			(effects
				(font
					(size 1 1)
					(thickness 0.15)
				)
			)
		)
		(property "Tolerance" "1%"
			(at -31.970499 221.467501 0)
			(layer "F.Fab")
			(hide yes)
			(effects
				(font
					(size 1 1)
					(thickness 0.15)
				)
			)
		)
		(property "Val" "330R"
			(at -31.970499 221.467501 0)
			(layer "F.Fab")
			(hide yes)
			(effects
				(font
					(size 1 1)
					(thickness 0.15)
				)
			)
		)
		(sheetname "/FPGA Config/")
		(sheetfile "fpga-config.kicad_sch")
		(attr smd)
		(fp_rect
			(start -0.93 -0.47)
			(end 0.93 0.47)
			(stroke
				(width 0.05)
				(type solid)
			)
			(fill no)
			(layer "F.CrtYd")
		)
		(fp_rect
			(start -0.5 -0.25)
			(end 0.5 0.25)
			(stroke
				(width 0.15)
				(type solid)
			)
			(fill no)
			(layer "F.Fab")
		)
		(pad "1" smd roundrect
			(at -0.485 0 270)
			(size 0.59 0.64)
			(layers "F.Cu" "F.Mask" "F.Paste")
			(roundrect_rratio 0.25)
			(net 305 "Net-(D2-Pad2)")
			(pintype "passive")
		)
		(pad "2" smd roundrect
			(at 0.485 0 270)
			(size 0.59 0.64)
			(layers "F.Cu" "F.Mask" "F.Paste")
			(roundrect_rratio 0.25)
			(net 351 "Net-(Q2-D)")
			(pintype "passive")
		)
	)
	(footprint "antmicro-footprints:NetTie-2_SMD_Pad0.127mm"
		(layer "F.Cu")
		(at 199.876501 159.699)
		(descr "Net tie, 2 pin, 0.127mm  SMD pads")
		(tags "net tie")
		(property "Reference" "NT7"
			(at -0.128 -1.345 0)
			(layer "F.SilkS")
			(hide yes)
			(effects
				(font
					(size 0.7 0.7)
					(thickness 0.15)
				)
				(justify left bottom)
			)
		)
		(property "Value" "Net-Tie_P0.127mm"
			(at 0 1.199 0)
			(layer "F.Fab")
			(effects
				(font
					(size 0.7 0.7)
					(thickness 0.15)
				)
				(justify left bottom)
			)
		)
		(property "Author" "Antmicro"
			(at 0 0 0)
			(layer "F.Fab")
			(hide yes)
			(effects
				(font
					(size 1 1)
					(thickness 0.15)
				)
			)
		)
		(property "License" "Apache-2.0"
			(at 0 0 0)
			(layer "F.Fab")
			(hide yes)
			(effects
				(font
					(size 1 1)
					(thickness 0.15)
				)
			)
		)
		(property "MPN" ""
			(at 0 0 0)
			(layer "F.Fab")
			(hide yes)
			(effects
				(font
					(size 1 1)
					(thickness 0.15)
				)
			)
		)
		(property "Manufacturer" ""
			(at 0 0 0)
			(layer "F.Fab")
			(hide yes)
			(effects
				(font
					(size 1 1)
					(thickness 0.15)
				)
			)
		)
		(property ki_fp_filters "Net*Tie*")
		(sheetname "/Supply/")
		(sheetfile "supply.kicad_sch")
		(attr smd exclude_from_pos_files exclude_from_bom)
		(net_tie_pad_groups "1, 2")
		(fp_poly
			(pts
				(xy -0.0635 -0.0635) (xy 0.0625 -0.0635) (xy 0.0625 0.0635) (xy -0.0635 0.0635)
			)
			(stroke
				(width 0)
				(type solid)
			)
			(fill yes)
			(layer "F.Cu")
		)
		(pad "1" smd roundrect
			(at -0.127 0 180)
			(size 0.127 0.127)
			(layers "F.Cu")
			(roundrect_rratio 0.5)
			(chamfer_ratio 0)
			(chamfer top_left bottom_left)
			(net 142 "/Supply/1V1_SEN_+")
			(pinfunction "1")
			(pintype "passive")
		)
		(pad "2" smd roundrect
			(at 0.126 0)
			(size 0.127 0.127)
			(layers "F.Cu")
			(roundrect_rratio 0.5)
			(chamfer_ratio 0)
			(chamfer top_left bottom_left)
			(net 53 "/Supply/1V1_local")
			(pinfunction "2")
			(pintype "passive")
		)
	)
	(footprint "antmicro-footprints:R_0603_1608Metric"
		(layer "F.Cu")
		(at 166.100501 197.114501 180)
		(descr "Resistor SMD 0603")
		(tags "resistor SMD 0603")
		(property "Reference" "R188"
			(at 1.550501 0.9 180)
			(layer "F.SilkS")
			(effects
				(font
					(size 0.7 0.7)
					(thickness 0.15)
				)
				(justify left bottom)
			)
		)
		(property "Value" "R_0R_22.4A_0603"
			(at 0 1.6 180)
			(layer "F.Fab")
			(effects
				(font
					(size 0.7 0.7)
					(thickness 0.15)
				)
				(justify left bottom)
			)
		)
		(property "Datasheet" "https://fscdn.rohm.com/en/products/databook/datasheet/passive/resistor/chip_resistor/pmr-jpw-e.pdf"
			(at 0 0 180)
			(layer "F.Fab")
			(hide yes)
			(effects
				(font
					(size 1.27 1.27)
					(thickness 0.15)
				)
			)
		)
		(property "Author" "Antmicro"
			(at 332.201002 394.229002 0)
			(layer "F.Fab")
			(hide yes)
			(effects
				(font
					(size 1 1)
					(thickness 0.15)
				)
			)
		)
		(property "License" "Apache-2.0"
			(at 332.201002 394.229002 0)
			(layer "F.Fab")
			(hide yes)
			(effects
				(font
					(size 1 1)
					(thickness 0.15)
				)
			)
		)
		(property "MPN" "PMR03EZPJ000"
			(at 332.201002 394.229002 0)
			(layer "F.Fab")
			(hide yes)
			(effects
				(font
					(size 1 1)
					(thickness 0.15)
				)
			)
		)
		(property "Manufacturer" "ROHM Semiconductor"
			(at 332.201002 394.229002 0)
			(layer "F.Fab")
			(hide yes)
			(effects
				(font
					(size 1 1)
					(thickness 0.15)
				)
			)
		)
		(property "Max. Curr." "22.4A"
			(at 332.201002 394.229002 0)
			(layer "F.Fab")
			(hide yes)
			(effects
				(font
					(size 1 1)
					(thickness 0.15)
				)
			)
		)
		(property "Val" "0R"
			(at 332.201002 394.229002 0)
			(layer "F.Fab")
			(hide yes)
			(effects
				(font
					(size 1 1)
					(thickness 0.15)
				)
			)
		)
		(sheetname "/Supply/")
		(sheetfile "supply.kicad_sch")
		(attr smd)
		(fp_line
			(start -0.3 0.3)
			(end 0.3 0.3)
			(stroke
				(width 0.15)
				(type solid)
			)
			(layer "F.SilkS")
		)
		(fp_line
			(start -0.3 -0.3)
			(end 0.3 -0.3)
			(stroke
				(width 0.15)
				(type solid)
			)
			(layer "F.SilkS")
		)
		(fp_rect
			(start -1.25 -0.7)
			(end 1.25 0.7)
			(stroke
				(width 0.05)
				(type solid)
			)
			(fill no)
			(layer "F.CrtYd")
		)
		(fp_rect
			(start -0.8 -0.4)
			(end 0.8 0.4)
			(stroke
				(width 0.15)
				(type solid)
			)
			(fill no)
			(layer "F.Fab")
		)
		(pad "1" smd roundrect
			(at -0.7 0 180)
			(size 0.6 0.8)
			(layers "F.Cu" "F.Mask" "F.Paste")
			(roundrect_rratio 0.2)
			(net 78 "/Supply/1V0_REG")
			(pintype "passive")
		)
		(pad "2" smd roundrect
			(at 0.7 0 180)
			(size 0.6 0.8)
			(layers "F.Cu" "F.Mask" "F.Paste")
			(roundrect_rratio 0.2)
			(net 227 "+1V0")
			(pintype "passive")
		)
	)
	(footprint "antmicro-footprints:C_0402_1005Metric"
		(layer "F.Cu")
		(at 83.649 150.634 90)
		(descr "Capacitor SMD 0402")
		(tags "capacitor SMD 0402")
		(property "Reference" "C113"
			(at 0 -0.699 90)
			(layer "F.SilkS")
			(hide yes)
			(effects
				(font
					(size 0.7 0.7)
					(thickness 0.15)
				)
				(justify left bottom)
			)
		)
		(property "Value" "C_10u_6.3V_0402"
			(at -1.022927 2.155213 90)
			(layer "F.Fab")
			(effects
				(font
					(size 0.7 0.7)
					(thickness 0.15)
				)
				(justify left bottom)
			)
		)
		(property "Datasheet" "https://www.murata.com/products/productdetail?partno=GRM155R60J106ME15%23"
			(at 0 0 90)
			(layer "F.Fab")
			(hide yes)
			(effects
				(font
					(size 1.27 1.27)
					(thickness 0.15)
				)
			)
		)
		(property "Author" "Antmicro"
			(at 234.283 66.985 0)
			(layer "F.Fab")
			(hide yes)
			(effects
				(font
					(size 1 1)
					(thickness 0.15)
				)
			)
		)
		(property "Dielectric" "X5R"
			(at 234.283 66.985 0)
			(layer "F.Fab")
			(hide yes)
			(effects
				(font
					(size 1 1)
					(thickness 0.15)
				)
			)
		)
		(property "License" "Apache-2.0"
			(at 234.283 66.985 0)
			(layer "F.Fab")
			(hide yes)
			(effects
				(font
					(size 1 1)
					(thickness 0.15)
				)
			)
		)
		(property "MPN" "GRM155R60J106ME15D"
			(at 234.283 66.985 0)
			(layer "F.Fab")
			(hide yes)
			(effects
				(font
					(size 1 1)
					(thickness 0.15)
				)
			)
		)
		(property "Manufacturer" "Murata"
			(at 234.283 66.985 0)
			(layer "F.Fab")
			(hide yes)
			(effects
				(font
					(size 1 1)
					(thickness 0.15)
				)
			)
		)
		(property "Val" "10u"
			(at 234.283 66.985 0)
			(layer "F.Fab")
			(hide yes)
			(effects
				(font
					(size 1 1)
					(thickness 0.15)
				)
			)
		)
		(property "Voltage" "6.3V"
			(at 234.283 66.985 0)
			(layer "F.Fab")
			(hide yes)
			(effects
				(font
					(size 1 1)
					(thickness 0.15)
				)
			)
		)
		(sheetname "/Debug FTDI/")
		(sheetfile "debug-ftdi.kicad_sch")
		(attr smd)
		(fp_rect
			(start -0.9659 -0.481258)
			(end 0.9649 0.458742)
			(stroke
				(width 0.05)
				(type solid)
			)
			(fill no)
			(layer "F.CrtYd")
		)
		(fp_line
			(start 0.499 -0.25)
			(end 0.499 0.248)
			(stroke
				(width 0.15)
				(type solid)
			)
			(layer "F.Fab")
		)
		(fp_line
			(start -0.499 -0.25)
			(end 0.499 -0.25)
			(stroke
				(width 0.15)
				(type solid)
			)
			(layer "F.Fab")
		)
		(fp_line
			(start 0.499 0.248)
			(end -0.499 0.248)
			(stroke
				(width 0.15)
				(type solid)
			)
			(layer "F.Fab")
		)
		(fp_line
			(start -0.499 0.248)
			(end -0.499 -0.25)
			(stroke
				(width 0.15)
				(type solid)
			)
			(layer "F.Fab")
		)
		(pad "1" smd roundrect
			(at -0.484 0 90)
			(size 0.59 0.64)
			(layers "F.Cu" "F.Mask" "F.Paste")
			(roundrect_rratio 0.25)
			(net 1 "GND")
			(pintype "passive")
		)
		(pad "2" smd roundrect
			(at 0.484 0 90)
			(size 0.59 0.64)
			(layers "F.Cu" "F.Mask" "F.Paste")
			(roundrect_rratio 0.25)
			(net 6 "/Debug FTDI/FTDI_3V3")
			(pintype "passive")
		)
	)
	(footprint "antmicro-footprints:R_0402_1005Metric"
		(layer "F.Cu")
		(at 202.881001 170.222 -90)
		(descr "Resistor SMD 0402")
		(tags "resistor SMD 0402")
		(property "Reference" "R168"
			(at 3.778 -0.368999 270)
			(layer "F.SilkS")
			(effects
				(font
					(size 0.7 0.7)
					(thickness 0.15)
				)
				(justify left bottom)
			)
		)
		(property "Value" "R_0R_0402"
			(at -1.011843 1.772047 270)
			(layer "F.Fab")
			(effects
				(font
					(size 0.7 0.7)
					(thickness 0.15)
				)
				(justify left bottom)
			)
		)
		(property "Datasheet" "https://industrial.panasonic.com/cdbs/www-data/pdf/RDA0000/AOA0000C301.pdf"
			(at 0 0 270)
			(layer "F.Fab")
			(hide yes)
			(effects
				(font
					(size 1.27 1.27)
					(thickness 0.15)
				)
			)
		)
		(property "Author" "Antmicro"
			(at 32.659001 373.103001 0)
			(layer "F.Fab")
			(hide yes)
			(effects
				(font
					(size 1 1)
					(thickness 0.15)
				)
			)
		)
		(property "Current" "1A"
			(at 32.659001 373.103001 0)
			(layer "F.Fab")
			(hide yes)
			(effects
				(font
					(size 1 1)
					(thickness 0.15)
				)
			)
		)
		(property "License" "Apache-2.0"
			(at 32.659001 373.103001 0)
			(layer "F.Fab")
			(hide yes)
			(effects
				(font
					(size 1 1)
					(thickness 0.15)
				)
			)
		)
		(property "MPN" "ERJ2GE0R00X"
			(at 32.659001 373.103001 0)
			(layer "F.Fab")
			(hide yes)
			(effects
				(font
					(size 1 1)
					(thickness 0.15)
				)
			)
		)
		(property "Manufacturer" "Panasonic"
			(at 32.659001 373.103001 0)
			(layer "F.Fab")
			(hide yes)
			(effects
				(font
					(size 1 1)
					(thickness 0.15)
				)
			)
		)
		(property "Tolerance" ""
			(at 32.659001 373.103001 0)
			(layer "F.Fab")
			(hide yes)
			(effects
				(font
					(size 1 1)
					(thickness 0.15)
				)
			)
		)
		(property "Val" "0R"
			(at 32.659001 373.103001 0)
			(layer "F.Fab")
			(hide yes)
			(effects
				(font
					(size 1 1)
					(thickness 0.15)
				)
			)
		)
		(sheetname "/Supply/")
		(sheetfile "supply.kicad_sch")
		(attr smd)
		(fp_rect
			(start -0.93 -0.47)
			(end 0.93 0.47)
			(stroke
				(width 0.05)
				(type solid)
			)
			(fill no)
			(layer "F.CrtYd")
		)
		(fp_rect
			(start -0.5 -0.25)
			(end 0.5 0.25)
			(stroke
				(width 0.15)
				(type solid)
			)
			(fill no)
			(layer "F.Fab")
		)
		(pad "1" smd roundrect
			(at -0.485 0 270)
			(size 0.59 0.64)
			(layers "F.Cu" "F.Mask" "F.Paste")
			(roundrect_rratio 0.25)
			(net 218 "/Supply/FB8")
			(pintype "passive")
		)
		(pad "2" smd roundrect
			(at 0.485 0 270)
			(size 0.59 0.64)
			(layers "F.Cu" "F.Mask" "F.Paste")
			(roundrect_rratio 0.25)
			(net 56 "/Supply/1V2_local")
			(pintype "passive")
		)
	)
	(footprint "antmicro-footprints:FB_0603_1608Metric"
		(layer "F.Cu")
		(at 86.577001 187.4505)
		(property "Reference" "FB3"
			(at 0 -0.8 0)
			(layer "F.SilkS")
			(hide yes)
			(effects
				(font
					(size 0.7 0.7)
					(thickness 0.15)
				)
				(justify left bottom)
			)
		)
		(property "Value" "FB_120Z_2A_Murata-BLM18PG_0603"
			(at 0 1.5 0)
			(layer "F.Fab")
			(effects
				(font
					(size 0.7 0.7)
					(thickness 0.15)
				)
				(justify left bottom)
			)
		)
		(property "Datasheet" "https://www.murata.com/en-us/products/productdata/8796738650142/ENFA0003.pdf"
			(at 0 0 0)
			(layer "F.Fab")
			(hide yes)
			(effects
				(font
					(size 1.27 1.27)
					(thickness 0.15)
				)
			)
		)
		(property "Author" "Antmicro"
			(at 0 0 0)
			(layer "F.Fab")
			(hide yes)
			(effects
				(font
					(size 1 1)
					(thickness 0.15)
				)
			)
		)
		(property "License" "Apache-2.0"
			(at 0 0 0)
			(layer "F.Fab")
			(hide yes)
			(effects
				(font
					(size 1 1)
					(thickness 0.15)
				)
			)
		)
		(property "MPN" "BLM18PG121SN1D"
			(at 0 0 0)
			(layer "F.Fab")
			(hide yes)
			(effects
				(font
					(size 1 1)
					(thickness 0.15)
				)
			)
		)
		(property "Manufacturer" "Murata"
			(at 0 0 0)
			(layer "F.Fab")
			(hide yes)
			(effects
				(font
					(size 1 1)
					(thickness 0.15)
				)
			)
		)
		(property "Val" "120Z/2A"
			(at 0 0 0)
			(layer "F.Fab")
			(hide yes)
			(effects
				(font
					(size 1 1)
					(thickness 0.15)
				)
			)
		)
		(sheetname "/HDMI + SD Card/")
		(sheetfile "hdmi-sd-card.kicad_sch")
		(attr smd)
		(fp_line
			(start -0.196 -0.408)
			(end 0.193 -0.408)
			(stroke
				(width 0.15)
				(type solid)
			)
			(layer "F.SilkS")
		)
		(fp_line
			(start -0.196 0.406)
			(end 0.193 0.406)
			(stroke
				(width 0.15)
				(type solid)
			)
			(layer "F.SilkS")
		)
		(fp_rect
			(start -1.3 -0.6)
			(end 1.3 0.6)
			(stroke
				(width 0.05)
				(type solid)
			)
			(fill no)
			(layer "F.CrtYd")
		)
		(fp_line
			(start -0.803 0.406)
			(end -0.803 -0.408)
			(stroke
				(width 0.15)
				(type solid)
			)
			(layer "F.Fab")
		)
		(fp_line
			(start 0.8 -0.408)
			(end -0.803 -0.408)
			(stroke
				(width 0.15)
				(type solid)
			)
			(layer "F.Fab")
		)
		(fp_line
			(start 0.8 -0.408)
			(end 0.8 0.406)
			(stroke
				(width 0.15)
				(type solid)
			)
			(layer "F.Fab")
		)
		(fp_line
			(start 0.8 0.406)
			(end -0.803 0.406)
			(stroke
				(width 0.15)
				(type solid)
			)
			(layer "F.Fab")
		)
		(pad "1" smd roundrect
			(at -0.891 0)
			(size 0.762 1.09)
			(layers "F.Cu" "F.Mask" "F.Paste")
			(roundrect_rratio 0.15)
			(net 201 "+5V")
			(pintype "passive")
		)
		(pad "2" smd roundrect
			(at 0.888 0)
			(size 0.762 1.09)
			(layers "F.Cu" "F.Mask" "F.Paste")
			(roundrect_rratio 0.15)
			(net 34 "/HDMI + SD Card/HDMI_5V")
			(pintype "passive")
		)
	)
	(footprint "antmicro-footprints:R_0402_1005Metric"
		(layer "F.Cu")
		(at 185 183.115 -90)
		(descr "Resistor SMD 0402")
		(tags "resistor SMD 0402")
		(property "Reference" "R173"
			(at -1.122484 -0.772697 270)
			(layer "F.SilkS")
			(hide yes)
			(effects
				(font
					(size 0.7 0.7)
					(thickness 0.15)
				)
				(justify left bottom)
			)
		)
		(property "Value" "R_10k_0402"
			(at -1.011843 1.772047 270)
			(layer "F.Fab")
			(effects
				(font
					(size 0.7 0.7)
					(thickness 0.15)
				)
				(justify left bottom)
			)
		)
		(property "Datasheet" "https://www.bourns.com/docs/product-datasheets/cr.pdf"
			(at 0 0 270)
			(layer "F.Fab")
			(hide yes)
			(effects
				(font
					(size 1.27 1.27)
					(thickness 0.15)
				)
			)
		)
		(property "Author" "Antmicro"
			(at 1.885 368.115 0)
			(layer "F.Fab")
			(hide yes)
			(effects
				(font
					(size 1 1)
					(thickness 0.15)
				)
			)
		)
		(property "License" "Apache-2.0"
			(at 1.885 368.115 0)
			(layer "F.Fab")
			(hide yes)
			(effects
				(font
					(size 1 1)
					(thickness 0.15)
				)
			)
		)
		(property "MPN" "CR0402-FX-1002GLF"
			(at 1.885 368.115 0)
			(layer "F.Fab")
			(hide yes)
			(effects
				(font
					(size 1 1)
					(thickness 0.15)
				)
			)
		)
		(property "Manufacturer" "Bourns"
			(at 1.885 368.115 0)
			(layer "F.Fab")
			(hide yes)
			(effects
				(font
					(size 1 1)
					(thickness 0.15)
				)
			)
		)
		(property "Tolerance" "1%"
			(at 1.885 368.115 0)
			(layer "F.Fab")
			(hide yes)
			(effects
				(font
					(size 1 1)
					(thickness 0.15)
				)
			)
		)
		(property "Val" "10k"
			(at 1.885 368.115 0)
			(layer "F.Fab")
			(hide yes)
			(effects
				(font
					(size 1 1)
					(thickness 0.15)
				)
			)
		)
		(sheetname "/Supply/")
		(sheetfile "supply.kicad_sch")
		(attr smd)
		(fp_rect
			(start -0.93 -0.47)
			(end 0.93 0.47)
			(stroke
				(width 0.05)
				(type solid)
			)
			(fill no)
			(layer "F.CrtYd")
		)
		(fp_rect
			(start -0.5 -0.25)
			(end 0.5 0.25)
			(stroke
				(width 0.15)
				(type solid)
			)
			(fill no)
			(layer "F.Fab")
		)
		(pad "1" smd roundrect
			(at -0.485 0 270)
			(size 0.59 0.64)
			(layers "F.Cu" "F.Mask" "F.Paste")
			(roundrect_rratio 0.25)
			(net 200 "+3V3")
			(pintype "passive")
		)
		(pad "2" smd roundrect
			(at 0.485 0 270)
			(size 0.59 0.64)
			(layers "F.Cu" "F.Mask" "F.Paste")
			(roundrect_rratio 0.25)
			(net 385 "Net-(U25-~{PWRDN})")
			(pintype "passive")
		)
	)
	(footprint "antmicro-footprints:NetTie-2_SMD_Pad0.127mm"
		(layer "F.Cu")
		(at 189.4805 162.002)
		(descr "Net tie, 2 pin, 0.127mm  SMD pads")
		(tags "net tie")
		(property "Reference" "NT6"
			(at -0.128 -1.345 0)
			(layer "F.SilkS")
			(hide yes)
			(effects
				(font
					(size 0.7 0.7)
					(thickness 0.15)
				)
				(justify left bottom)
			)
		)
		(property "Value" "Net-Tie_P0.127mm"
			(at 0 1.199 0)
			(layer "F.Fab")
			(effects
				(font
					(size 0.7 0.7)
					(thickness 0.15)
				)
				(justify left bottom)
			)
		)
		(property "Author" "Antmicro"
			(at 0 0 0)
			(layer "F.Fab")
			(hide yes)
			(effects
				(font
					(size 1 1)
					(thickness 0.15)
				)
			)
		)
		(property "License" "Apache-2.0"
			(at 0 0 0)
			(layer "F.Fab")
			(hide yes)
			(effects
				(font
					(size 1 1)
					(thickness 0.15)
				)
			)
		)
		(property "MPN" ""
			(at 0 0 0)
			(layer "F.Fab")
			(hide yes)
			(effects
				(font
					(size 1 1)
					(thickness 0.15)
				)
			)
		)
		(property "Manufacturer" ""
			(at 0 0 0)
			(layer "F.Fab")
			(hide yes)
			(effects
				(font
					(size 1 1)
					(thickness 0.15)
				)
			)
		)
		(property ki_fp_filters "Net*Tie*")
		(sheetname "/Supply/")
		(sheetfile "supply.kicad_sch")
		(attr smd exclude_from_pos_files exclude_from_bom)
		(net_tie_pad_groups "1, 2")
		(fp_poly
			(pts
				(xy -0.0635 -0.0635) (xy 0.0625 -0.0635) (xy 0.0625 0.0635) (xy -0.0635 0.0635)
			)
			(stroke
				(width 0)
				(type solid)
			)
			(fill yes)
			(layer "F.Cu")
		)
		(pad "1" smd roundrect
			(at -0.127 0 180)
			(size 0.127 0.127)
			(layers "F.Cu")
			(roundrect_rratio 0.5)
			(chamfer_ratio 0)
			(chamfer top_left bottom_left)
			(net 141 "/Supply/5V_SEN_+")
			(pinfunction "1")
			(pintype "passive")
		)
		(pad "2" smd roundrect
			(at 0.126 0)
			(size 0.127 0.127)
			(layers "F.Cu")
			(roundrect_rratio 0.5)
			(chamfer_ratio 0)
			(chamfer top_left bottom_left)
			(net 60 "/Supply/5V_local")
			(pinfunction "2")
			(pintype "passive")
		)
	)
	(footprint "antmicro-footprints:R_0402_1005Metric"
		(layer "F.Cu")
		(at 97.75 136.06 -90)
		(descr "Resistor SMD 0402")
		(tags "resistor SMD 0402")
		(property "Reference" "R128"
			(at -1.122484 -0.772697 270)
			(layer "F.SilkS")
			(hide yes)
			(effects
				(font
					(size 0.7 0.7)
					(thickness 0.15)
				)
				(justify left bottom)
			)
		)
		(property "Value" "R_10k_0402"
			(at -1.011843 1.772047 270)
			(layer "F.Fab")
			(effects
				(font
					(size 0.7 0.7)
					(thickness 0.15)
				)
				(justify left bottom)
			)
		)
		(property "Datasheet" "https://www.bourns.com/docs/product-datasheets/cr.pdf"
			(at 0 0 270)
			(layer "F.Fab")
			(hide yes)
			(effects
				(font
					(size 1.27 1.27)
					(thickness 0.15)
				)
			)
		)
		(property "Author" "Antmicro"
			(at -38.31 233.81 0)
			(layer "F.Fab")
			(hide yes)
			(effects
				(font
					(size 1 1)
					(thickness 0.15)
				)
			)
		)
		(property "License" "Apache-2.0"
			(at -38.31 233.81 0)
			(layer "F.Fab")
			(hide yes)
			(effects
				(font
					(size 1 1)
					(thickness 0.15)
				)
			)
		)
		(property "MPN" "CR0402-FX-1002GLF"
			(at -38.31 233.81 0)
			(layer "F.Fab")
			(hide yes)
			(effects
				(font
					(size 1 1)
					(thickness 0.15)
				)
			)
		)
		(property "Manufacturer" "Bourns"
			(at -38.31 233.81 0)
			(layer "F.Fab")
			(hide yes)
			(effects
				(font
					(size 1 1)
					(thickness 0.15)
				)
			)
		)
		(property "Tolerance" "1%"
			(at -38.31 233.81 0)
			(layer "F.Fab")
			(hide yes)
			(effects
				(font
					(size 1 1)
					(thickness 0.15)
				)
			)
		)
		(property "Val" "10k"
			(at -38.31 233.81 0)
			(layer "F.Fab")
			(hide yes)
			(effects
				(font
					(size 1 1)
					(thickness 0.15)
				)
			)
		)
		(sheetname "/DDR5 SODIMM/")
		(sheetfile "ddr5-sodimm.kicad_sch")
		(attr smd)
		(fp_rect
			(start -0.93 -0.47)
			(end 0.93 0.47)
			(stroke
				(width 0.05)
				(type solid)
			)
			(fill no)
			(layer "F.CrtYd")
		)
		(fp_rect
			(start -0.5 -0.25)
			(end 0.5 0.25)
			(stroke
				(width 0.15)
				(type solid)
			)
			(fill no)
			(layer "F.Fab")
		)
		(pad "1" smd roundrect
			(at -0.485 0 270)
			(size 0.59 0.64)
			(layers "F.Cu" "F.Mask" "F.Paste")
			(roundrect_rratio 0.25)
			(net 1 "GND")
			(pintype "passive")
		)
		(pad "2" smd roundrect
			(at 0.485 0 270)
			(size 0.59 0.64)
			(layers "F.Cu" "F.Mask" "F.Paste")
			(roundrect_rratio 0.25)
			(net 49 "/DDR5 SODIMM/HSA")
			(pintype "passive")
		)
	)
	(footprint "antmicro-footprints:SOD-523"
		(layer "F.Cu")
		(at 177.449 189.35 180)
		(property "Reference" "D17"
			(at -1.051 2.7 0)
			(layer "F.SilkS")
			(effects
				(font
					(size 0.7 0.7)
					(thickness 0.15)
				)
				(justify right top)
			)
		)
		(property "Value" "BAT54-02V-G3-08"
			(at 0 1.499 0)
			(layer "F.Fab")
			(effects
				(font
					(size 0.7 0.7)
					(thickness 0.15)
				)
				(justify right top)
			)
		)
		(property "Datasheet" "https://www.vishay.com/docs/85633/bat5402v.pdf"
			(at 0 0 0)
			(layer "F.Fab")
			(hide yes)
			(effects
				(font
					(size 1.27 1.27)
					(thickness 0.15)
				)
			)
		)
		(property "Description" "Small Signal Schottky Diode, Single, 30 V, 200 mA, 800 mV, 600 mA, 125 °C"
			(at 0 0 0)
			(layer "F.Fab")
			(hide yes)
			(effects
				(font
					(size 1.27 1.27)
					(thickness 0.15)
				)
			)
		)
		(property "MPN" "BAT54-02V-G3-08"
			(at 0 0 180)
			(unlocked yes)
			(layer "F.Fab")
			(hide yes)
			(effects
				(font
					(size 1 1)
					(thickness 0.15)
				)
			)
		)
		(property "Manufacturer" "Vishay"
			(at 0 0 180)
			(unlocked yes)
			(layer "F.Fab")
			(hide yes)
			(effects
				(font
					(size 1 1)
					(thickness 0.15)
				)
			)
		)
		(property "Author" "Antmicro"
			(at 0 0 180)
			(unlocked yes)
			(layer "F.Fab")
			(hide yes)
			(effects
				(font
					(size 1 1)
					(thickness 0.15)
				)
			)
		)
		(property "License" "Apache-2.0"
			(at 0 0 180)
			(unlocked yes)
			(layer "F.Fab")
			(hide yes)
			(effects
				(font
					(size 1 1)
					(thickness 0.15)
				)
			)
		)
		(sheetname "/I^{2}C/")
		(sheetfile "i2c.kicad_sch")
		(attr smd)
		(fp_line
			(start -0.35 -0.5)
			(end -0.35 0.5)
			(stroke
				(width 0.15)
				(type solid)
			)
			(layer "F.SilkS")
		)
		(fp_poly
			(pts
				(xy -1 -0.6) (xy 1 -0.6) (xy 1 0.6) (xy -1 0.6)
			)
			(stroke
				(width 0.05)
				(type solid)
			)
			(fill no)
			(layer "F.CrtYd")
		)
		(fp_line
			(start 0.65 -0.425)
			(end 0.65 0.423)
			(stroke
				(width 0.15)
				(type solid)
			)
			(layer "F.Fab")
		)
		(fp_line
			(start -0.35 -0.4)
			(end -0.35 0.4)
			(stroke
				(width 0.15)
				(type solid)
			)
			(layer "F.Fab")
		)
		(fp_line
			(start -0.652 0.423)
			(end 0.65 0.423)
			(stroke
				(width 0.15)
				(type solid)
			)
			(layer "F.Fab")
		)
		(fp_line
			(start -0.652 0.423)
			(end -0.652 -0.425)
			(stroke
				(width 0.15)
				(type solid)
			)
			(layer "F.Fab")
		)
		(fp_line
			(start -0.652 -0.425)
			(end 0.65 -0.425)
			(stroke
				(width 0.15)
				(type solid)
			)
			(layer "F.Fab")
		)
		(fp_text user "License: Apache-2.0"
			(at -1.276 5.9 0)
			(layer "F.Fab")
			(effects
				(font
					(size 0.7 0.7)
					(thickness 0.15)
				)
				(justify right top)
			)
		)
		(fp_text user "${REFERENCE}"
			(at -1.276 3.499 0)
			(layer "F.Fab")
			(effects
				(font
					(size 0.7 0.7)
					(thickness 0.15)
				)
				(justify right top)
			)
		)
		(fp_text user "Author: Antmicro"
			(at -1.276 4.7 0)
			(layer "F.Fab")
			(effects
				(font
					(size 0.7 0.7)
					(thickness 0.15)
				)
				(justify right top)
			)
		)
		(pad "1" smd roundrect
			(at -0.701 0 180)
			(size 0.5 0.6)
			(layers "F.Cu" "F.Mask" "F.Paste")
			(roundrect_rratio 0.25)
			(net 759 "Net-(D17-C)")
			(pinfunction "C")
			(pintype "passive")
		)
		(pad "2" smd roundrect
			(at 0.699001 0 180)
			(size 0.5 0.6)
			(layers "F.Cu" "F.Mask" "F.Paste")
			(roundrect_rratio 0.25)
			(net 200 "+3V3")
			(pinfunction "A")
			(pintype "passive")
		)
	)
	(footprint "antmicro-footprints:TP_SMD_1mm"
		(layer "F.Cu")
		(at 186.4 184.85)
		(property "Reference" "TP8"
			(at 0 -0.731898 0)
			(layer "F.SilkS")
			(hide yes)
			(effects
				(font
					(size 0.7 0.7)
					(thickness 0.15)
				)
				(justify left bottom)
			)
		)
		(property "Value" "TP_1mm_SMD"
			(at 0 1.4 0)
			(layer "F.Fab")
			(effects
				(font
					(size 0.7 0.7)
					(thickness 0.15)
				)
				(justify left bottom)
			)
		)
		(property "Author" "Antmicro"
			(at 0 0 0)
			(layer "F.Fab")
			(hide yes)
			(effects
				(font
					(size 1 1)
					(thickness 0.15)
				)
			)
		)
		(property "License" "Apache-2.0"
			(at 0 0 0)
			(layer "F.Fab")
			(hide yes)
			(effects
				(font
					(size 1 1)
					(thickness 0.15)
				)
			)
		)
		(property "MPN" ""
			(at 0 0 0)
			(layer "F.Fab")
			(hide yes)
			(effects
				(font
					(size 1 1)
					(thickness 0.15)
				)
			)
		)
		(property "Manufacturer" ""
			(at 0 0 0)
			(layer "F.Fab")
			(hide yes)
			(effects
				(font
					(size 1 1)
					(thickness 0.15)
				)
			)
		)
		(sheetname "/Supply/")
		(sheetfile "supply.kicad_sch")
		(attr exclude_from_pos_files)
		(pad "1" smd circle
			(at 0 0)
			(size 1 1)
			(layers "F.Cu" "F.Mask")
			(net 187 "+1V0_MGTAVCC")
			(pinfunction "1")
			(pintype "passive")
		)
	)
	(footprint "antmicro-footprints:R_0402_1005Metric"
		(layer "F.Cu")
		(at 121.799499 186.6 -90)
		(descr "Resistor SMD 0402")
		(tags "resistor SMD 0402")
		(property "Reference" "R7"
			(at -1.122484 -0.772697 270)
			(layer "F.SilkS")
			(hide yes)
			(effects
				(font
					(size 0.7 0.7)
					(thickness 0.15)
				)
				(justify left bottom)
			)
		)
		(property "Value" "R_22R_0402"
			(at -1.011843 1.772047 270)
			(layer "F.Fab")
			(effects
				(font
					(size 0.7 0.7)
					(thickness 0.15)
				)
				(justify left bottom)
			)
		)
		(property "Datasheet" "https://www.bourns.com/docs/product-datasheets/cr.pdf"
			(at 0 0 270)
			(layer "F.Fab")
			(hide yes)
			(effects
				(font
					(size 1.27 1.27)
					(thickness 0.15)
				)
			)
		)
		(property "Author" "Antmicro"
			(at -64.800501 308.399499 0)
			(layer "F.Fab")
			(hide yes)
			(effects
				(font
					(size 1 1)
					(thickness 0.15)
				)
			)
		)
		(property "License" "Apache-2.0"
			(at -64.800501 308.399499 0)
			(layer "F.Fab")
			(hide yes)
			(effects
				(font
					(size 1 1)
					(thickness 0.15)
				)
			)
		)
		(property "MPN" "CR0402-FX-22R0GLF"
			(at -64.800501 308.399499 0)
			(layer "F.Fab")
			(hide yes)
			(effects
				(font
					(size 1 1)
					(thickness 0.15)
				)
			)
		)
		(property "Manufacturer" "Bourns"
			(at -64.800501 308.399499 0)
			(layer "F.Fab")
			(hide yes)
			(effects
				(font
					(size 1 1)
					(thickness 0.15)
				)
			)
		)
		(property "Tolerance" "1%"
			(at -64.800501 308.399499 0)
			(layer "F.Fab")
			(hide yes)
			(effects
				(font
					(size 1 1)
					(thickness 0.15)
				)
			)
		)
		(property "Val" "22R"
			(at -64.800501 308.399499 0)
			(layer "F.Fab")
			(hide yes)
			(effects
				(font
					(size 1 1)
					(thickness 0.15)
				)
			)
		)
		(sheetname "/HyperRAM + QSPI Flash/")
		(sheetfile "hyperram-flash.kicad_sch")
		(attr smd)
		(fp_rect
			(start -0.93 -0.47)
			(end 0.93 0.47)
			(stroke
				(width 0.05)
				(type solid)
			)
			(fill no)
			(layer "F.CrtYd")
		)
		(fp_rect
			(start -0.5 -0.25)
			(end 0.5 0.25)
			(stroke
				(width 0.15)
				(type solid)
			)
			(fill no)
			(layer "F.Fab")
		)
		(pad "1" smd roundrect
			(at -0.485 0 270)
			(size 0.59 0.64)
			(layers "F.Cu" "F.Mask" "F.Paste")
			(roundrect_rratio 0.25)
			(net 363 "/HyperRAM + QSPI Flash/IO1")
			(pintype "passive")
		)
		(pad "2" smd roundrect
			(at 0.485 0 270)
			(size 0.59 0.64)
			(layers "F.Cu" "F.Mask" "F.Paste")
			(roundrect_rratio 0.25)
			(net 627 "/FPGA Config/FLASH.IO1")
			(pintype "passive")
		)
	)
	(footprint "antmicro-footprints:FBGA-25-24_6x8mm_Layout5x5_P1mm"
		(layer "F.Cu")
		(at 118.650501 174.926 -90)
		(property "Reference" "U1"
			(at 3.249 -4.299499 0)
			(layer "F.SilkS")
			(effects
				(font
					(size 0.7 0.7)
					(thickness 0.15)
				)
				(justify left bottom)
			)
		)
		(property "Value" "IS66WVH16M8DBLL-100B1LI"
			(at 0.1 5.3 270)
			(layer "F.Fab")
			(effects
				(font
					(size 0.7 0.7)
					(thickness 0.15)
				)
				(justify left bottom)
			)
		)
		(property "Datasheet" "https://eu.mouser.com/datasheet/2/198/issi_s_a0011529618_1-2271553.pdf"
			(at 0 0 270)
			(layer "F.Fab")
			(hide yes)
			(effects
				(font
					(size 1.27 1.27)
					(thickness 0.15)
				)
			)
		)
		(property "Author" "Antmicro"
			(at -56.275499 293.576501 0)
			(layer "F.Fab")
			(hide yes)
			(effects
				(font
					(size 1 1)
					(thickness 0.15)
				)
			)
		)
		(property "License" "Apache-2.0"
			(at -56.275499 293.576501 0)
			(layer "F.Fab")
			(hide yes)
			(effects
				(font
					(size 1 1)
					(thickness 0.15)
				)
			)
		)
		(property "MPN" "IS66WVH16M8DBLL-100B1LI"
			(at -56.275499 293.576501 0)
			(layer "F.Fab")
			(hide yes)
			(effects
				(font
					(size 1 1)
					(thickness 0.15)
				)
			)
		)
		(property "Manufacturer" "ISSI"
			(at -56.275499 293.576501 0)
			(layer "F.Fab")
			(hide yes)
			(effects
				(font
					(size 1 1)
					(thickness 0.15)
				)
			)
		)
		(sheetname "/HyperRAM + QSPI Flash/")
		(sheetfile "hyperram-flash.kicad_sch")
		(attr smd)
		(fp_line
			(start -3.121 4.12)
			(end -3.121 2.12)
			(stroke
				(width 0.15)
				(type solid)
			)
			(layer "F.SilkS")
		)
		(fp_line
			(start -1.621 4.12)
			(end -3.121 4.12)
			(stroke
				(width 0.15)
				(type solid)
			)
			(layer "F.SilkS")
		)
		(fp_line
			(start 1.62 4.12)
			(end 3.12 4.12)
			(stroke
				(width 0.15)
				(type solid)
			)
			(layer "F.SilkS")
		)
		(fp_line
			(start 3.12 4.12)
			(end 3.12 2.12)
			(stroke
				(width 0.15)
				(type solid)
			)
			(layer "F.SilkS")
		)
		(fp_line
			(start -3.121 -3)
			(end -3.121 -2.121)
			(stroke
				(width 0.15)
				(type solid)
			)
			(layer "F.SilkS")
		)
		(fp_line
			(start -2 -4.121)
			(end -3.121 -3)
			(stroke
				(width 0.15)
				(type solid)
			)
			(layer "F.SilkS")
		)
		(fp_line
			(start -1.621 -4.121)
			(end -2 -4.121)
			(stroke
				(width 0.15)
				(type solid)
			)
			(layer "F.SilkS")
		)
		(fp_line
			(start 1.62 -4.121)
			(end 3.12 -4.121)
			(stroke
				(width 0.15)
				(type solid)
			)
			(layer "F.SilkS")
		)
		(fp_line
			(start 1.62 -4.121)
			(end 3.12 -4.121)
			(stroke
				(width 0.15)
				(type solid)
			)
			(layer "F.SilkS")
		)
		(fp_line
			(start 1.62 -4.121)
			(end 3.12 -4.121)
			(stroke
				(width 0.15)
				(type solid)
			)
			(layer "F.SilkS")
		)
		(fp_line
			(start 3.12 -4.121)
			(end 3.12 -2.121)
			(stroke
				(width 0.15)
				(type solid)
			)
			(layer "F.SilkS")
		)
		(fp_line
			(start 3.12 -4.121)
			(end 3.12 -2.121)
			(stroke
				(width 0.15)
				(type solid)
			)
			(layer "F.SilkS")
		)
		(fp_line
			(start 3.12 -4.121)
			(end 3.12 -2.121)
			(stroke
				(width 0.15)
				(type solid)
			)
			(layer "F.SilkS")
		)
		(fp_circle
			(center -3.6 -3.9)
			(end -3.5 -3.9)
			(stroke
				(width 0.15)
				(type solid)
			)
			(fill yes)
			(layer "F.SilkS")
		)
		(fp_line
			(start -3.25 4.24)
			(end -3.25 -4.25)
			(stroke
				(width 0.05)
				(type solid)
			)
			(layer "F.CrtYd")
		)
		(fp_line
			(start 3.24 4.24)
			(end -3.25 4.24)
			(stroke
				(width 0.05)
				(type solid)
			)
			(layer "F.CrtYd")
		)
		(fp_line
			(start -3.25 -4.25)
			(end 3.24 -4.25)
			(stroke
				(width 0.05)
				(type solid)
			)
			(layer "F.CrtYd")
		)
		(fp_line
			(start 3.24 -4.25)
			(end 3.24 4.24)
			(stroke
				(width 0.05)
				(type solid)
			)
			(layer "F.CrtYd")
		)
		(fp_line
			(start -3 4)
			(end 3 4)
			(stroke
				(width 0.15)
				(type solid)
			)
			(layer "F.Fab")
		)
		(fp_line
			(start 3 4)
			(end 3 -4)
			(stroke
				(width 0.15)
				(type solid)
			)
			(layer "F.Fab")
		)
		(fp_line
			(start -3 -3)
			(end -3 4)
			(stroke
				(width 0.15)
				(type solid)
			)
			(layer "F.Fab")
		)
		(fp_line
			(start -2 -4)
			(end -3 -3)
			(stroke
				(width 0.15)
				(type solid)
			)
			(layer "F.Fab")
		)
		(fp_line
			(start 3 -4)
			(end -2 -4)
			(stroke
				(width 0.15)
				(type solid)
			)
			(layer "F.Fab")
		)
		(pad "A2" smd circle
			(at -1 -2 270)
			(size 0.4 0.4)
			(layers "F.Cu" "F.Mask" "F.Paste")
			(net 388 "unconnected-(U1-NC-PadA2)")
			(pinfunction "NC")
			(pintype "no_connect")
		)
		(pad "A3" smd circle
			(at 0 -2 270)
			(size 0.4 0.4)
			(layers "F.Cu" "F.Mask" "F.Paste")
			(net 624 "/FPGA bank 12/HyperRAM.~{CS}")
			(pinfunction "~{CS}")
			(pintype "input")
		)
		(pad "A4" smd circle
			(at 1 -2 270)
			(size 0.4 0.4)
			(layers "F.Cu" "F.Mask" "F.Paste")
			(net 623 "/FPGA bank 12/HyperRAM.~{RESET}")
			(pinfunction "~{RESET}")
			(pintype "input")
		)
		(pad "A5" smd circle
			(at 2 -2 270)
			(size 0.4 0.4)
			(layers "F.Cu" "F.Mask" "F.Paste")
			(net 389 "unconnected-(U1-NC-PadA5)")
			(pinfunction "NC")
			(pintype "no_connect")
		)
		(pad "B1" smd circle
			(at -2 -1 270)
			(size 0.4 0.4)
			(layers "F.Cu" "F.Mask" "F.Paste")
			(net 693 "/FPGA bank 12/HyperRAM.CK_N")
			(pinfunction "CK-")
			(pintype "input")
		)
		(pad "B2" smd circle
			(at -1 -1 270)
			(size 0.4 0.4)
			(layers "F.Cu" "F.Mask" "F.Paste")
			(net 694 "/FPGA bank 12/HyperRAM.CK_P")
			(pinfunction "CK+")
			(pintype "input")
		)
		(pad "B3" smd circle
			(at 0 -1 270)
			(size 0.4 0.4)
			(layers "F.Cu" "F.Mask" "F.Paste")
			(net 1 "GND")
			(pinfunction "VSS")
			(pintype "power_in")
		)
		(pad "B4" smd circle
			(at 1 -1 270)
			(size 0.4 0.4)
			(layers "F.Cu" "F.Mask" "F.Paste")
			(net 200 "+3V3")
			(pinfunction "VCC")
			(pintype "power_in")
		)
		(pad "B5" smd circle
			(at 2 -1 270)
			(size 0.4 0.4)
			(layers "F.Cu" "F.Mask" "F.Paste")
			(net 390 "unconnected-(U1-NC-PadB5)")
			(pinfunction "NC")
			(pintype "no_connect")
		)
		(pad "C1" smd circle
			(at -2 0 270)
			(size 0.4 0.4)
			(layers "F.Cu" "F.Mask" "F.Paste")
			(net 1 "GND")
			(pinfunction "VSSQ")
			(pintype "power_in")
		)
		(pad "C2" smd circle
			(at -1 0 270)
			(size 0.4 0.4)
			(layers "F.Cu" "F.Mask" "F.Paste")
			(net 391 "unconnected-(U1-NC-PadC2)")
			(pinfunction "NC")
			(pintype "no_connect")
		)
		(pad "C3" smd circle
			(at 0 0 270)
			(size 0.4 0.4)
			(layers "F.Cu" "F.Mask" "F.Paste")
			(net 695 "/FPGA bank 12/HyperRAM.RWDS")
			(pinfunction "RWDS")
			(pintype "bidirectional")
		)
		(pad "C4" smd circle
			(at 1 0 270)
			(size 0.4 0.4)
			(layers "F.Cu" "F.Mask" "F.Paste")
			(net 696 "/FPGA bank 12/HyperRAM.DQ2")
			(pinfunction "DQ2")
			(pintype "bidirectional")
		)
		(pad "C5" smd circle
			(at 2 0 270)
			(size 0.4 0.4)
			(layers "F.Cu" "F.Mask" "F.Paste")
			(net 392 "unconnected-(U1-NC-PadC5)")
			(pinfunction "NC")
			(pintype "no_connect")
		)
		(pad "D1" smd circle
			(at -2 1 270)
			(size 0.4 0.4)
			(layers "F.Cu" "F.Mask" "F.Paste")
			(net 200 "+3V3")
			(pinfunction "VCCQ")
			(pintype "power_in")
		)
		(pad "D2" smd circle
			(at -1 1 270)
			(size 0.4 0.4)
			(layers "F.Cu" "F.Mask" "F.Paste")
			(net 697 "/FPGA bank 12/HyperRAM.DQ1")
			(pinfunction "DQ1")
			(pintype "bidirectional")
		)
		(pad "D3" smd circle
			(at 0 1 270)
			(size 0.4 0.4)
			(layers "F.Cu" "F.Mask" "F.Paste")
			(net 698 "/FPGA bank 12/HyperRAM.DQ0")
			(pinfunction "DQ0")
			(pintype "bidirectional")
		)
		(pad "D4" smd circle
			(at 1 1 270)
			(size 0.4 0.4)
			(layers "F.Cu" "F.Mask" "F.Paste")
			(net 699 "/FPGA bank 12/HyperRAM.DQ3")
			(pinfunction "DQ3")
			(pintype "bidirectional")
		)
		(pad "D5" smd circle
			(at 2 1 270)
			(size 0.4 0.4)
			(layers "F.Cu" "F.Mask" "F.Paste")
			(net 700 "/FPGA bank 12/HyperRAM.DQ4")
			(pinfunction "DQ4")
			(pintype "bidirectional")
		)
		(pad "E1" smd circle
			(at -2 2 270)
			(size 0.4 0.4)
			(layers "F.Cu" "F.Mask" "F.Paste")
			(net 701 "/FPGA bank 12/HyperRAM.DQ7")
			(pinfunction "DQ7")
			(pintype "bidirectional")
		)
		(pad "E2" smd circle
			(at -1 2 270)
			(size 0.4 0.4)
			(layers "F.Cu" "F.Mask" "F.Paste")
			(net 702 "/FPGA bank 12/HyperRAM.DQ6")
			(pinfunction "DQ6")
			(pintype "bidirectional")
		)
		(pad "E3" smd circle
			(at 0 2 270)
			(size 0.4 0.4)
			(layers "F.Cu" "F.Mask" "F.Paste")
			(net 703 "/FPGA bank 12/HyperRAM.DQ5")
			(pinfunction "DQ5")
			(pintype "bidirectional")
		)
		(pad "E4" smd circle
			(at 1 2 270)
			(size 0.4 0.4)
			(layers "F.Cu" "F.Mask" "F.Paste")
			(net 200 "+3V3")
			(pinfunction "VCCQ")
			(pintype "passive")
		)
		(pad "E5" smd circle
			(at 2 2 270)
			(size 0.4 0.4)
			(layers "F.Cu" "F.Mask" "F.Paste")
			(net 1 "GND")
			(pinfunction "VSSQ")
			(pintype "passive")
		)
	)
	(footprint "antmicro-footprints:SOD-523"
		(layer "F.Cu")
		(at 177.449 190.65 180)
		(property "Reference" "D18"
			(at 1.149 2.1 180)
			(layer "F.SilkS")
			(effects
				(font
					(size 0.7 0.7)
					(thickness 0.15)
				)
				(justify left bottom)
			)
		)
		(property "Value" "BAT54-02V-G3-08"
			(at 0 1.499 180)
			(layer "F.Fab")
			(effects
				(font
					(size 0.7 0.7)
					(thickness 0.15)
				)
				(justify left bottom)
			)
		)
		(property "Datasheet" "https://www.vishay.com/docs/85633/bat5402v.pdf"
			(at 0 0 180)
			(layer "F.Fab")
			(hide yes)
			(effects
				(font
					(size 1.27 1.27)
					(thickness 0.15)
				)
			)
		)
		(property "Description" "Small Signal Schottky Diode, Single, 30 V, 200 mA, 800 mV, 600 mA, 125 °C"
			(at 0 0 180)
			(layer "F.Fab")
			(hide yes)
			(effects
				(font
					(size 1.27 1.27)
					(thickness 0.15)
				)
			)
		)
		(property "MPN" "BAT54-02V-G3-08"
			(at 0 0 180)
			(unlocked yes)
			(layer "F.Fab")
			(hide yes)
			(effects
				(font
					(size 1 1)
					(thickness 0.15)
				)
			)
		)
		(property "Manufacturer" "Vishay"
			(at 0 0 180)
			(unlocked yes)
			(layer "F.Fab")
			(hide yes)
			(effects
				(font
					(size 1 1)
					(thickness 0.15)
				)
			)
		)
		(property "Author" "Antmicro"
			(at 0 0 180)
			(unlocked yes)
			(layer "F.Fab")
			(hide yes)
			(effects
				(font
					(size 1 1)
					(thickness 0.15)
				)
			)
		)
		(property "License" "Apache-2.0"
			(at 0 0 180)
			(unlocked yes)
			(layer "F.Fab")
			(hide yes)
			(effects
				(font
					(size 1 1)
					(thickness 0.15)
				)
			)
		)
		(sheetname "/I^{2}C/")
		(sheetfile "i2c.kicad_sch")
		(attr smd)
		(fp_line
			(start -0.35 -0.5)
			(end -0.35 0.5)
			(stroke
				(width 0.15)
				(type solid)
			)
			(layer "F.SilkS")
		)
		(fp_rect
			(start -1 -0.6)
			(end 1 0.6)
			(stroke
				(width 0.05)
				(type solid)
			)
			(fill no)
			(layer "F.CrtYd")
		)
		(fp_line
			(start 0.65 -0.425)
			(end 0.65 0.423)
			(stroke
				(width 0.15)
				(type solid)
			)
			(layer "F.Fab")
		)
		(fp_line
			(start -0.35 -0.4)
			(end -0.35 0.4)
			(stroke
				(width 0.15)
				(type solid)
			)
			(layer "F.Fab")
		)
		(fp_line
			(start -0.652 0.423)
			(end 0.65 0.423)
			(stroke
				(width 0.15)
				(type solid)
			)
			(layer "F.Fab")
		)
		(fp_line
			(start -0.652 0.423)
			(end -0.652 -0.425)
			(stroke
				(width 0.15)
				(type solid)
			)
			(layer "F.Fab")
		)
		(fp_line
			(start -0.652 -0.425)
			(end 0.65 -0.425)
			(stroke
				(width 0.15)
				(type solid)
			)
			(layer "F.Fab")
		)
		(fp_text user "License: Apache-2.0"
			(at -1.276 5.9 180)
			(layer "F.Fab")
			(effects
				(font
					(size 0.7 0.7)
					(thickness 0.15)
				)
				(justify left bottom)
			)
		)
		(fp_text user "Author: Antmicro"
			(at -1.276 4.7 180)
			(layer "F.Fab")
			(effects
				(font
					(size 0.7 0.7)
					(thickness 0.15)
				)
				(justify left bottom)
			)
		)
		(fp_text user "${REFERENCE}"
			(at -1.276 3.499 180)
			(layer "F.Fab")
			(effects
				(font
					(size 0.7 0.7)
					(thickness 0.15)
				)
				(justify left bottom)
			)
		)
		(pad "1" smd roundrect
			(at -0.701 0 180)
			(size 0.5 0.6)
			(layers "F.Cu" "F.Mask" "F.Paste")
			(roundrect_rratio 0.25)
			(net 759 "Net-(D17-C)")
			(pinfunction "C")
			(pintype "passive")
		)
		(pad "2" smd roundrect
			(at 0.699 0 180)
			(size 0.5 0.6)
			(layers "F.Cu" "F.Mask" "F.Paste")
			(roundrect_rratio 0.25)
			(net 760 "Net-(D18-A)")
			(pinfunction "A")
			(pintype "passive")
		)
	)
	(footprint "antmicro-footprints:TP_SMD_1mm"
		(layer "F.Cu")
		(at 186.4 193.15)
		(property "Reference" "TP17"
			(at 0 -0.731898 0)
			(layer "F.SilkS")
			(hide yes)
			(effects
				(font
					(size 0.7 0.7)
					(thickness 0.15)
				)
				(justify left bottom)
			)
		)
		(property "Value" "TP_1mm_SMD"
			(at 0 1.4 0)
			(layer "F.Fab")
			(effects
				(font
					(size 0.7 0.7)
					(thickness 0.15)
				)
				(justify left bottom)
			)
		)
		(property "Author" "Antmicro"
			(at 0 0 0)
			(layer "F.Fab")
			(hide yes)
			(effects
				(font
					(size 1 1)
					(thickness 0.15)
				)
			)
		)
		(property "License" "Apache-2.0"
			(at 0 0 0)
			(layer "F.Fab")
			(hide yes)
			(effects
				(font
					(size 1 1)
					(thickness 0.15)
				)
			)
		)
		(property "MPN" ""
			(at 0 0 0)
			(layer "F.Fab")
			(hide yes)
			(effects
				(font
					(size 1 1)
					(thickness 0.15)
				)
			)
		)
		(property "Manufacturer" ""
			(at 0 0 0)
			(layer "F.Fab")
			(hide yes)
			(effects
				(font
					(size 1 1)
					(thickness 0.15)
				)
			)
		)
		(sheetname "/Supply/")
		(sheetfile "supply.kicad_sch")
		(attr exclude_from_pos_files)
		(pad "1" smd circle
			(at 0 0)
			(size 1 1)
			(layers "F.Cu" "F.Mask")
			(net 226 "+1V2_MGTAVTT")
			(pinfunction "1")
			(pintype "passive")
		)
	)
	(footprint "antmicro-footprints:R_0402_1005Metric"
		(layer "F.Cu")
		(at 101.65 181.45 -90)
		(descr "Resistor SMD 0402")
		(tags "resistor SMD 0402")
		(property "Reference" "R91"
			(at -1.122484 -0.772697 270)
			(layer "F.SilkS")
			(hide yes)
			(effects
				(font
					(size 0.7 0.7)
					(thickness 0.15)
				)
				(justify left bottom)
			)
		)
		(property "Value" "R_0R_0402"
			(at -1.011843 1.772047 270)
			(layer "F.Fab")
			(effects
				(font
					(size 0.7 0.7)
					(thickness 0.15)
				)
				(justify left bottom)
			)
		)
		(property "Datasheet" "https://industrial.panasonic.com/cdbs/www-data/pdf/RDA0000/AOA0000C301.pdf"
			(at 0 0 270)
			(layer "F.Fab")
			(hide yes)
			(effects
				(font
					(size 1.27 1.27)
					(thickness 0.15)
				)
			)
		)
		(property "Author" "Antmicro"
			(at -79.8 283.1 0)
			(layer "F.Fab")
			(hide yes)
			(effects
				(font
					(size 1 1)
					(thickness 0.15)
				)
			)
		)
		(property "Current" "1A"
			(at -79.8 283.1 0)
			(layer "F.Fab")
			(hide yes)
			(effects
				(font
					(size 1 1)
					(thickness 0.15)
				)
			)
		)
		(property "License" "Apache-2.0"
			(at -79.8 283.1 0)
			(layer "F.Fab")
			(hide yes)
			(effects
				(font
					(size 1 1)
					(thickness 0.15)
				)
			)
		)
		(property "MPN" "ERJ2GE0R00X"
			(at -79.8 283.1 0)
			(layer "F.Fab")
			(hide yes)
			(effects
				(font
					(size 1 1)
					(thickness 0.15)
				)
			)
		)
		(property "Manufacturer" "Panasonic"
			(at -79.8 283.1 0)
			(layer "F.Fab")
			(hide yes)
			(effects
				(font
					(size 1 1)
					(thickness 0.15)
				)
			)
		)
		(property "Tolerance" ""
			(at -79.8 283.1 0)
			(layer "F.Fab")
			(hide yes)
			(effects
				(font
					(size 1 1)
					(thickness 0.15)
				)
			)
		)
		(property "Val" "0R"
			(at -79.8 283.1 0)
			(layer "F.Fab")
			(hide yes)
			(effects
				(font
					(size 1 1)
					(thickness 0.15)
				)
			)
		)
		(sheetname "/Debug FTDI/")
		(sheetfile "debug-ftdi.kicad_sch")
		(attr exclude_from_pos_files exclude_from_bom dnp)
		(fp_rect
			(start -0.93 -0.47)
			(end 0.93 0.47)
			(stroke
				(width 0.05)
				(type solid)
			)
			(fill no)
			(layer "F.CrtYd")
		)
		(fp_rect
			(start -0.5 -0.25)
			(end 0.5 0.25)
			(stroke
				(width 0.15)
				(type solid)
			)
			(fill no)
			(layer "F.Fab")
		)
		(pad "1" smd roundrect
			(at -0.485 0 270)
			(size 0.59 0.64)
			(layers "F.Cu" "F.Mask" "F.Paste")
			(roundrect_rratio 0.25)
			(net 654 "/Debug FTDI/I2C_EN")
			(pintype "passive")
		)
		(pad "2" smd roundrect
			(at 0.485 0 270)
			(size 0.59 0.64)
			(layers "F.Cu" "F.Mask" "F.Paste")
			(roundrect_rratio 0.25)
			(net 383 "Net-(U13-OE)")
			(pintype "passive")
		)
	)
	(footprint "antmicro-footprints:C_0402_1005Metric"
		(layer "F.Cu")
		(at 183.120107 181.815)
		(descr "Capacitor SMD 0402")
		(tags "capacitor SMD 0402")
		(property "Reference" "C199"
			(at 0 -0.699 0)
			(layer "F.SilkS")
			(hide yes)
			(effects
				(font
					(size 0.7 0.7)
					(thickness 0.15)
				)
				(justify left bottom)
			)
		)
		(property "Value" "C_100n_0402"
			(at -1.022927 2.155213 0)
			(layer "F.Fab")
			(effects
				(font
					(size 0.7 0.7)
					(thickness 0.15)
				)
				(justify left bottom)
			)
		)
		(property "Datasheet" "https://www.murata.com/products/productdetail?partno=GRM155R61H104KE14%23"
			(at 0 0 0)
			(layer "F.Fab")
			(hide yes)
			(effects
				(font
					(size 1.27 1.27)
					(thickness 0.15)
				)
			)
		)
		(property "Author" "Antmicro"
			(at 0 0 0)
			(layer "F.Fab")
			(hide yes)
			(effects
				(font
					(size 1 1)
					(thickness 0.15)
				)
			)
		)
		(property "Dielectric" "X5R"
			(at 0 0 0)
			(layer "F.Fab")
			(hide yes)
			(effects
				(font
					(size 1 1)
					(thickness 0.15)
				)
			)
		)
		(property "License" "Apache-2.0"
			(at 0 0 0)
			(layer "F.Fab")
			(hide yes)
			(effects
				(font
					(size 1 1)
					(thickness 0.15)
				)
			)
		)
		(property "MPN" "GRM155R61H104KE14D"
			(at 0 0 0)
			(layer "F.Fab")
			(hide yes)
			(effects
				(font
					(size 1 1)
					(thickness 0.15)
				)
			)
		)
		(property "Manufacturer" "Murata"
			(at 0 0 0)
			(layer "F.Fab")
			(hide yes)
			(effects
				(font
					(size 1 1)
					(thickness 0.15)
				)
			)
		)
		(property "Val" "100n"
			(at 0 0 0)
			(layer "F.Fab")
			(hide yes)
			(effects
				(font
					(size 1 1)
					(thickness 0.15)
				)
			)
		)
		(property "Voltage" "50V"
			(at 0 0 0)
			(layer "F.Fab")
			(hide yes)
			(effects
				(font
					(size 1 1)
					(thickness 0.15)
				)
			)
		)
		(sheetname "/Supply/")
		(sheetfile "supply.kicad_sch")
		(attr smd)
		(fp_rect
			(start -0.9659 -0.481258)
			(end 0.9649 0.458742)
			(stroke
				(width 0.05)
				(type solid)
			)
			(fill no)
			(layer "F.CrtYd")
		)
		(fp_line
			(start -0.499 -0.25)
			(end 0.499 -0.25)
			(stroke
				(width 0.15)
				(type solid)
			)
			(layer "F.Fab")
		)
		(fp_line
			(start -0.499 0.248)
			(end -0.499 -0.25)
			(stroke
				(width 0.15)
				(type solid)
			)
			(layer "F.Fab")
		)
		(fp_line
			(start 0.499 -0.25)
			(end 0.499 0.248)
			(stroke
				(width 0.15)
				(type solid)
			)
			(layer "F.Fab")
		)
		(fp_line
			(start 0.499 0.248)
			(end -0.499 0.248)
			(stroke
				(width 0.15)
				(type solid)
			)
			(layer "F.Fab")
		)
		(pad "1" smd roundrect
			(at -0.484 0)
			(size 0.59 0.64)
			(layers "F.Cu" "F.Mask" "F.Paste")
			(roundrect_rratio 0.25)
			(net 200 "+3V3")
			(pintype "passive")
		)
		(pad "2" smd roundrect
			(at 0.484 0)
			(size 0.59 0.64)
			(layers "F.Cu" "F.Mask" "F.Paste")
			(roundrect_rratio 0.25)
			(net 1 "GND")
			(pintype "passive")
		)
	)
	(footprint "antmicro-footprints:MP_NPTH_Drill3mm"
		(layer "F.Cu")
		(at 202.878201 115.5)
		(property "Reference" "MP4"
			(at -10.06 1.28 0)
			(layer "F.SilkS")
			(hide yes)
			(effects
				(font
					(size 0.7 0.7)
					(thickness 0.15)
				)
				(justify left bottom)
			)
		)
		(property "Value" "MP_NPTH_Drill3mm"
			(at -13.52 6.2 0)
			(layer "F.Fab")
			(effects
				(font
					(size 0.7 0.7)
					(thickness 0.15)
				)
				(justify left bottom)
			)
		)
		(property "Author" "Antmicro"
			(at 0 0 0)
			(layer "F.Fab")
			(hide yes)
			(effects
				(font
					(size 1 1)
					(thickness 0.15)
				)
			)
		)
		(property "License" "Apache-2.0"
			(at 0 0 0)
			(layer "F.Fab")
			(hide yes)
			(effects
				(font
					(size 1 1)
					(thickness 0.15)
				)
			)
		)
		(sheetfile "sodimm-ddr5-tester.kicad_sch")
		(attr board_only exclude_from_pos_files exclude_from_bom)
		(pad "" np_thru_hole circle
			(at 0 0)
			(size 3 3)
			(drill 3)
			(layers "*.Cu" "*.Mask")
		)
	)
	(footprint "antmicro-footprints:SC70-3"
		(layer "F.Cu")
		(at 91.750501 122.926 90)
		(property "Reference" "Q7"
			(at 0 -1.6 90)
			(layer "F.SilkS")
			(hide yes)
			(effects
				(font
					(size 0.7 0.7)
					(thickness 0.15)
				)
				(justify left bottom)
			)
		)
		(property "Value" "BSS138PW,115"
			(at 0 2.3 90)
			(layer "F.Fab")
			(effects
				(font
					(size 0.7 0.7)
					(thickness 0.15)
				)
				(justify left bottom)
			)
		)
		(property "Datasheet" "https://assets.nexperia.com/documents/data-sheet/BSS138PW.pdf"
			(at 0 0 90)
			(layer "F.Fab")
			(hide yes)
			(effects
				(font
					(size 1.27 1.27)
					(thickness 0.15)
				)
			)
		)
		(property "Description" "Power MOSFET, N Channel, 60 V, 320 mA, 0.9 ohm, SOT-323, Surface Mount"
			(at 0 0 90)
			(layer "F.Fab")
			(hide yes)
			(effects
				(font
					(size 1.27 1.27)
					(thickness 0.15)
				)
			)
		)
		(property "Author" "Antmicro"
			(at 214.676501 31.175499 0)
			(layer "F.Fab")
			(hide yes)
			(effects
				(font
					(size 1 1)
					(thickness 0.15)
				)
			)
		)
		(property "License" "Apache-2.0"
			(at 214.676501 31.175499 0)
			(layer "F.Fab")
			(hide yes)
			(effects
				(font
					(size 1 1)
					(thickness 0.15)
				)
			)
		)
		(property "MPN" "BSS138PW,115"
			(at 214.676501 31.175499 0)
			(layer "F.Fab")
			(hide yes)
			(effects
				(font
					(size 1 1)
					(thickness 0.15)
				)
			)
		)
		(property "Manufacturer" "Nexperia"
			(at 214.676501 31.175499 0)
			(layer "F.Fab")
			(hide yes)
			(effects
				(font
					(size 1 1)
					(thickness 0.15)
				)
			)
		)
		(sheetname "/FPGA bank 14/")
		(sheetfile "fpga-bank-14.kicad_sch")
		(attr smd)
		(fp_line
			(start -0.3 -1)
			(end 0.627 -0.999)
			(stroke
				(width 0.15)
				(type solid)
			)
			(layer "F.SilkS")
		)
		(fp_line
			(start 0.627 -0.6)
			(end 0.627 -0.999)
			(stroke
				(width 0.15)
				(type solid)
			)
			(layer "F.SilkS")
		)
		(fp_line
			(start 0.627 0.6)
			(end 0.627 1.001)
			(stroke
				(width 0.15)
				(type solid)
			)
			(layer "F.SilkS")
		)
		(fp_line
			(start -0.3 1)
			(end 0.627 1.001)
			(stroke
				(width 0.15)
				(type solid)
			)
			(layer "F.SilkS")
		)
		(fp_line
			(start 0.9 -1.3)
			(end 0.9 -0.4)
			(stroke
				(width 0.05)
				(type solid)
			)
			(layer "F.CrtYd")
		)
		(fp_line
			(start -0.9 -1.3)
			(end 0.9 -1.3)
			(stroke
				(width 0.05)
				(type solid)
			)
			(layer "F.CrtYd")
		)
		(fp_line
			(start -0.9 -1.3)
			(end -0.9 -1)
			(stroke
				(width 0.05)
				(type solid)
			)
			(layer "F.CrtYd")
		)
		(fp_line
			(start -0.9 -1)
			(end -1.4 -1)
			(stroke
				(width 0.05)
				(type solid)
			)
			(layer "F.CrtYd")
		)
		(fp_line
			(start 1.4 -0.4)
			(end 1.4 0.4)
			(stroke
				(width 0.05)
				(type solid)
			)
			(layer "F.CrtYd")
		)
		(fp_line
			(start 0.9 -0.4)
			(end 1.4 -0.4)
			(stroke
				(width 0.05)
				(type solid)
			)
			(layer "F.CrtYd")
		)
		(fp_line
			(start 1.4 0.4)
			(end 0.9 0.4)
			(stroke
				(width 0.05)
				(type solid)
			)
			(layer "F.CrtYd")
		)
		(fp_line
			(start 0.9 0.4)
			(end 0.9 1.3)
			(stroke
				(width 0.05)
				(type solid)
			)
			(layer "F.CrtYd")
		)
		(fp_line
			(start -0.9 1)
			(end -1.4 1)
			(stroke
				(width 0.05)
				(type solid)
			)
			(layer "F.CrtYd")
		)
		(fp_line
			(start -1.4 1)
			(end -1.4 -1)
			(stroke
				(width 0.05)
				(type solid)
			)
			(layer "F.CrtYd")
		)
		(fp_line
			(start 0.9 1.3)
			(end -0.9 1.3)
			(stroke
				(width 0.05)
				(type solid)
			)
			(layer "F.CrtYd")
		)
		(fp_line
			(start -0.9 1.3)
			(end -0.9 1)
			(stroke
				(width 0.05)
				(type solid)
			)
			(layer "F.CrtYd")
		)
		(fp_rect
			(start -0.623 -0.999)
			(end 0.627 1.001)
			(stroke
				(width 0.15)
				(type solid)
			)
			(fill no)
			(layer "F.Fab")
		)
		(pad "1" smd rect
			(at -1.051 -0.65 180)
			(size 0.6 0.6)
			(layers "F.Cu" "F.Mask" "F.Paste")
			(net 621 "/FPGA bank 14/USR_LED4")
			(pinfunction "G")
			(pintype "input")
		)
		(pad "2" smd rect
			(at -1.051 0.65 180)
			(size 0.6 0.6)
			(layers "F.Cu" "F.Mask" "F.Paste")
			(net 1 "GND")
			(pinfunction "S")
			(pintype "passive")
		)
		(pad "3" smd rect
			(at 1.05 0 180)
			(size 0.6 0.6)
			(layers "F.Cu" "F.Mask" "F.Paste")
			(net 356 "Net-(Q7-D)")
			(pinfunction "D")
			(pintype "passive")
		)
	)
	(footprint "antmicro-footprints:SC70-3"
		(layer "F.Cu")
		(at 89.050501 122.926 90)
		(property "Reference" "Q5"
			(at 0 -1.6 90)
			(layer "F.SilkS")
			(hide yes)
			(effects
				(font
					(size 0.7 0.7)
					(thickness 0.15)
				)
				(justify left bottom)
			)
		)
		(property "Value" "BSS138PW,115"
			(at 0 2.3 90)
			(layer "F.Fab")
			(effects
				(font
					(size 0.7 0.7)
					(thickness 0.15)
				)
				(justify left bottom)
			)
		)
		(property "Datasheet" "https://assets.nexperia.com/documents/data-sheet/BSS138PW.pdf"
			(at 0 0 90)
			(layer "F.Fab")
			(hide yes)
			(effects
				(font
					(size 1.27 1.27)
					(thickness 0.15)
				)
			)
		)
		(property "Description" "Power MOSFET, N Channel, 60 V, 320 mA, 0.9 ohm, SOT-323, Surface Mount"
			(at 0 0 90)
			(layer "F.Fab")
			(hide yes)
			(effects
				(font
					(size 1.27 1.27)
					(thickness 0.15)
				)
			)
		)
		(property "Author" "Antmicro"
			(at 211.976501 33.875499 0)
			(layer "F.Fab")
			(hide yes)
			(effects
				(font
					(size 1 1)
					(thickness 0.15)
				)
			)
		)
		(property "License" "Apache-2.0"
			(at 211.976501 33.875499 0)
			(layer "F.Fab")
			(hide yes)
			(effects
				(font
					(size 1 1)
					(thickness 0.15)
				)
			)
		)
		(property "MPN" "BSS138PW,115"
			(at 211.976501 33.875499 0)
			(layer "F.Fab")
			(hide yes)
			(effects
				(font
					(size 1 1)
					(thickness 0.15)
				)
			)
		)
		(property "Manufacturer" "Nexperia"
			(at 211.976501 33.875499 0)
			(layer "F.Fab")
			(hide yes)
			(effects
				(font
					(size 1 1)
					(thickness 0.15)
				)
			)
		)
		(sheetname "/FPGA bank 14/")
		(sheetfile "fpga-bank-14.kicad_sch")
		(attr smd)
		(fp_line
			(start -0.3 -1)
			(end 0.627 -0.999)
			(stroke
				(width 0.15)
				(type solid)
			)
			(layer "F.SilkS")
		)
		(fp_line
			(start 0.627 -0.6)
			(end 0.627 -0.999)
			(stroke
				(width 0.15)
				(type solid)
			)
			(layer "F.SilkS")
		)
		(fp_line
			(start 0.627 0.6)
			(end 0.627 1.001)
			(stroke
				(width 0.15)
				(type solid)
			)
			(layer "F.SilkS")
		)
		(fp_line
			(start -0.3 1)
			(end 0.627 1.001)
			(stroke
				(width 0.15)
				(type solid)
			)
			(layer "F.SilkS")
		)
		(fp_line
			(start 0.9 -1.3)
			(end 0.9 -0.4)
			(stroke
				(width 0.05)
				(type solid)
			)
			(layer "F.CrtYd")
		)
		(fp_line
			(start -0.9 -1.3)
			(end 0.9 -1.3)
			(stroke
				(width 0.05)
				(type solid)
			)
			(layer "F.CrtYd")
		)
		(fp_line
			(start -0.9 -1.3)
			(end -0.9 -1)
			(stroke
				(width 0.05)
				(type solid)
			)
			(layer "F.CrtYd")
		)
		(fp_line
			(start -0.9 -1)
			(end -1.4 -1)
			(stroke
				(width 0.05)
				(type solid)
			)
			(layer "F.CrtYd")
		)
		(fp_line
			(start 1.4 -0.4)
			(end 1.4 0.4)
			(stroke
				(width 0.05)
				(type solid)
			)
			(layer "F.CrtYd")
		)
		(fp_line
			(start 0.9 -0.4)
			(end 1.4 -0.4)
			(stroke
				(width 0.05)
				(type solid)
			)
			(layer "F.CrtYd")
		)
		(fp_line
			(start 1.4 0.4)
			(end 0.9 0.4)
			(stroke
				(width 0.05)
				(type solid)
			)
			(layer "F.CrtYd")
		)
		(fp_line
			(start 0.9 0.4)
			(end 0.9 1.3)
			(stroke
				(width 0.05)
				(type solid)
			)
			(layer "F.CrtYd")
		)
		(fp_line
			(start -0.9 1)
			(end -1.4 1)
			(stroke
				(width 0.05)
				(type solid)
			)
			(layer "F.CrtYd")
		)
		(fp_line
			(start -1.4 1)
			(end -1.4 -1)
			(stroke
				(width 0.05)
				(type solid)
			)
			(layer "F.CrtYd")
		)
		(fp_line
			(start 0.9 1.3)
			(end -0.9 1.3)
			(stroke
				(width 0.05)
				(type solid)
			)
			(layer "F.CrtYd")
		)
		(fp_line
			(start -0.9 1.3)
			(end -0.9 1)
			(stroke
				(width 0.05)
				(type solid)
			)
			(layer "F.CrtYd")
		)
		(fp_rect
			(start -0.623 -0.999)
			(end 0.627 1.001)
			(stroke
				(width 0.15)
				(type solid)
			)
			(fill no)
			(layer "F.Fab")
		)
		(pad "1" smd rect
			(at -1.051 -0.65 180)
			(size 0.6 0.6)
			(layers "F.Cu" "F.Mask" "F.Paste")
			(net 617 "/FPGA bank 14/USR_LED3")
			(pinfunction "G")
			(pintype "input")
		)
		(pad "2" smd rect
			(at -1.051 0.65 180)
			(size 0.6 0.6)
			(layers "F.Cu" "F.Mask" "F.Paste")
			(net 1 "GND")
			(pinfunction "S")
			(pintype "passive")
		)
		(pad "3" smd rect
			(at 1.05 0 180)
			(size 0.6 0.6)
			(layers "F.Cu" "F.Mask" "F.Paste")
			(net 354 "Net-(Q5-D)")
			(pinfunction "D")
			(pintype "passive")
		)
	)
	(footprint "antmicro-footprints:SOT-23-6"
		(layer "F.Cu")
		(at 196.6 139.265 90)
		(property "Reference" "U22"
			(at -0.835 2.7 90)
			(layer "F.SilkS")
			(effects
				(font
					(size 0.7 0.7)
					(thickness 0.15)
				)
				(justify left bottom)
			)
		)
		(property "Value" "MAX16150A_SOT"
			(at -1.75 2.75 90)
			(layer "F.Fab")
			(effects
				(font
					(size 0.7 0.7)
					(thickness 0.15)
				)
				(justify left bottom)
			)
		)
		(property "Datasheet" "https://datasheets.maximintegrated.com/en/ds/MAX16150.pdf"
			(at 0 0 90)
			(layer "F.Fab")
			(hide yes)
			(effects
				(font
					(size 1.27 1.27)
					(thickness 0.15)
				)
			)
		)
		(property "Author" "Antmicro"
			(at 335.865 -57.335 0)
			(layer "F.Fab")
			(hide yes)
			(effects
				(font
					(size 1 1)
					(thickness 0.15)
				)
			)
		)
		(property "License" "Apache-2.0"
			(at 335.865 -57.335 0)
			(layer "F.Fab")
			(hide yes)
			(effects
				(font
					(size 1 1)
					(thickness 0.15)
				)
			)
		)
		(property "MPN" "MAX16150AUT+T"
			(at 335.865 -57.335 0)
			(layer "F.Fab")
			(hide yes)
			(effects
				(font
					(size 1 1)
					(thickness 0.15)
				)
			)
		)
		(property "Manufacturer" "Maxim Integrated Products"
			(at 335.865 -57.335 0)
			(layer "F.Fab")
			(hide yes)
			(effects
				(font
					(size 1 1)
					(thickness 0.15)
				)
			)
		)
		(sheetname "/Supply/")
		(sheetfile "supply.kicad_sch")
		(attr smd)
		(fp_line
			(start 1.45 -0.7)
			(end 1.45 -0.4)
			(stroke
				(width 0.12)
				(type solid)
			)
			(layer "F.SilkS")
		)
		(fp_line
			(start 1.3 -0.7)
			(end 1.45 -0.7)
			(stroke
				(width 0.12)
				(type solid)
			)
			(layer "F.SilkS")
		)
		(fp_line
			(start -1.3 -0.7)
			(end -1.45 -0.7)
			(stroke
				(width 0.12)
				(type solid)
			)
			(layer "F.SilkS")
		)
		(fp_line
			(start -1.45 -0.7)
			(end -1.45 -0.4)
			(stroke
				(width 0.12)
				(type solid)
			)
			(layer "F.SilkS")
		)
		(fp_line
			(start 1.45 0.7)
			(end 1.45 0.4)
			(stroke
				(width 0.12)
				(type solid)
			)
			(layer "F.SilkS")
		)
		(fp_line
			(start 1.3 0.7)
			(end 1.45 0.7)
			(stroke
				(width 0.12)
				(type solid)
			)
			(layer "F.SilkS")
		)
		(fp_line
			(start -1.45 0.7)
			(end -1.45 0.4)
			(stroke
				(width 0.12)
				(type solid)
			)
			(layer "F.SilkS")
		)
		(fp_rect
			(start -1.55 -1.85)
			(end 1.55 1.75)
			(stroke
				(width 0.05)
				(type solid)
			)
			(fill no)
			(layer "F.CrtYd")
		)
		(fp_line
			(start 1.5 -0.7)
			(end 1.5 0.7)
			(stroke
				(width 0.1)
				(type solid)
			)
			(layer "F.Fab")
		)
		(fp_line
			(start -1.5 -0.7)
			(end 1.5 -0.7)
			(stroke
				(width 0.1)
				(type solid)
			)
			(layer "F.Fab")
		)
		(fp_line
			(start 1.5 0.7)
			(end -1.5 0.7)
			(stroke
				(width 0.1)
				(type solid)
			)
			(layer "F.Fab")
		)
		(fp_line
			(start -1.5 0.7)
			(end -1.5 -0.7)
			(stroke
				(width 0.1)
				(type solid)
			)
			(layer "F.Fab")
		)
		(fp_text user "."
			(at -1.4 1.2 270)
			(layer "F.SilkS")
			(effects
				(font
					(size 1 1)
					(thickness 0.15)
				)
			)
		)
		(pad "1" smd roundrect
			(at -0.954 1.1 90)
			(size 0.55 1)
			(layers "F.Cu" "F.Mask" "F.Paste")
			(roundrect_rratio 0.15)
			(net 252 "/Supply/~{PB_CTRL_IN}")
			(pinfunction "~{PB_IN}")
			(pintype "input")
		)
		(pad "2" smd roundrect
			(at -0.003 1.1 90)
			(size 0.55 1)
			(layers "F.Cu" "F.Mask" "F.Paste")
			(roundrect_rratio 0.15)
			(net 1 "GND")
			(pinfunction "GND")
			(pintype "power_in")
		)
		(pad "3" smd roundrect
			(at 0.947 1.1 90)
			(size 0.55 1)
			(layers "F.Cu" "F.Mask" "F.Paste")
			(roundrect_rratio 0.15)
			(net 41 "+3V3_AON")
			(pinfunction "VCC")
			(pintype "power_in")
		)
		(pad "4" smd roundrect
			(at 0.947 -1.214 90)
			(size 0.55 1)
			(layers "F.Cu" "F.Mask" "F.Paste")
			(roundrect_rratio 0.15)
			(net 186 "/Supply/PB_CTRL_OUT")
			(pinfunction "OUT")
			(pintype "output")
		)
		(pad "5" smd roundrect
			(at -0.003 -1.214 90)
			(size 0.55 1)
			(layers "F.Cu" "F.Mask" "F.Paste")
			(roundrect_rratio 0.15)
			(net 207 "/Supply/~{PB_CTRL_INT}")
			(pinfunction "~{INT}")
			(pintype "output")
		)
		(pad "6" smd roundrect
			(at -0.954 -1.214 90)
			(size 0.55 1)
			(layers "F.Cu" "F.Mask" "F.Paste")
			(roundrect_rratio 0.15)
			(net 185 "/Supply/~{PB_CTRL_CLR}")
			(pinfunction "~{CLR}")
			(pintype "input")
		)
	)
	(footprint "antmicro-footprints:C_0402_1005Metric"
		(layer "F.Cu")
		(at 105.175001 147.9005)
		(descr "Capacitor SMD 0402")
		(tags "capacitor SMD 0402")
		(property "Reference" "C6"
			(at 0 -0.699 0)
			(layer "F.SilkS")
			(hide yes)
			(effects
				(font
					(size 0.7 0.7)
					(thickness 0.15)
				)
				(justify left bottom)
			)
		)
		(property "Value" "C_100n_0402"
			(at -1.022927 2.155213 0)
			(layer "F.Fab")
			(effects
				(font
					(size 0.7 0.7)
					(thickness 0.15)
				)
				(justify left bottom)
			)
		)
		(property "Datasheet" "https://www.murata.com/products/productdetail?partno=GRM155R61H104KE14%23"
			(at 0 0 0)
			(layer "F.Fab")
			(hide yes)
			(effects
				(font
					(size 1.27 1.27)
					(thickness 0.15)
				)
			)
		)
		(property "Author" "Antmicro"
			(at 0 0 0)
			(layer "F.Fab")
			(hide yes)
			(effects
				(font
					(size 1 1)
					(thickness 0.15)
				)
			)
		)
		(property "Dielectric" "X5R"
			(at 0 0 0)
			(layer "F.Fab")
			(hide yes)
			(effects
				(font
					(size 1 1)
					(thickness 0.15)
				)
			)
		)
		(property "License" "Apache-2.0"
			(at 0 0 0)
			(layer "F.Fab")
			(hide yes)
			(effects
				(font
					(size 1 1)
					(thickness 0.15)
				)
			)
		)
		(property "MPN" "GRM155R61H104KE14D"
			(at 0 0 0)
			(layer "F.Fab")
			(hide yes)
			(effects
				(font
					(size 1 1)
					(thickness 0.15)
				)
			)
		)
		(property "Manufacturer" "Murata"
			(at 0 0 0)
			(layer "F.Fab")
			(hide yes)
			(effects
				(font
					(size 1 1)
					(thickness 0.15)
				)
			)
		)
		(property "Val" "100n"
			(at 0 0 0)
			(layer "F.Fab")
			(hide yes)
			(effects
				(font
					(size 1 1)
					(thickness 0.15)
				)
			)
		)
		(property "Voltage" "50V"
			(at 0 0 0)
			(layer "F.Fab")
			(hide yes)
			(effects
				(font
					(size 1 1)
					(thickness 0.15)
				)
			)
		)
		(sheetname "/DDR5 SODIMM/")
		(sheetfile "ddr5-sodimm.kicad_sch")
		(attr smd)
		(fp_rect
			(start -0.9659 -0.481258)
			(end 0.9649 0.458742)
			(stroke
				(width 0.05)
				(type solid)
			)
			(fill no)
			(layer "F.CrtYd")
		)
		(fp_line
			(start -0.499 -0.25)
			(end 0.499 -0.25)
			(stroke
				(width 0.15)
				(type solid)
			)
			(layer "F.Fab")
		)
		(fp_line
			(start -0.499 0.248)
			(end -0.499 -0.25)
			(stroke
				(width 0.15)
				(type solid)
			)
			(layer "F.Fab")
		)
		(fp_line
			(start 0.499 -0.25)
			(end 0.499 0.248)
			(stroke
				(width 0.15)
				(type solid)
			)
			(layer "F.Fab")
		)
		(fp_line
			(start 0.499 0.248)
			(end -0.499 0.248)
			(stroke
				(width 0.15)
				(type solid)
			)
			(layer "F.Fab")
		)
		(pad "1" smd roundrect
			(at -0.484 0)
			(size 0.59 0.64)
			(layers "F.Cu" "F.Mask" "F.Paste")
			(roundrect_rratio 0.25)
			(net 1 "GND")
			(pintype "passive")
		)
		(pad "2" smd roundrect
			(at 0.484 0)
			(size 0.59 0.64)
			(layers "F.Cu" "F.Mask" "F.Paste")
			(roundrect_rratio 0.25)
			(net 201 "+5V")
			(pintype "passive")
		)
	)
	(footprint "antmicro-footprints:TP_1206_SMD_RCW-0C"
		(layer "F.Cu")
		(at 204.8 190 90)
		(property "Reference" "TP20"
			(at -2.29 -1.4 90)
			(layer "F.SilkS")
			(hide yes)
			(effects
				(font
					(size 0.7 0.7)
					(thickness 0.15)
				)
				(justify left bottom)
			)
		)
		(property "Value" "TP_1206_SMD_RCW-0C"
			(at -4.68 2.25 90)
			(layer "F.Fab")
			(effects
				(font
					(size 0.7 0.7)
					(thickness 0.15)
				)
				(justify left bottom)
			)
		)
		(property "Datasheet" "https://www.te.com/commerce/DocumentDelivery/DDEController?Action=srchrtrv&DocNm=1773266&DocType=DS&DocLang=English"
			(at 0 0 90)
			(layer "F.Fab")
			(hide yes)
			(effects
				(font
					(size 1.27 1.27)
					(thickness 0.15)
				)
			)
		)
		(property "Author" "Antmicro"
			(at 394.8 -14.8 0)
			(layer "F.Fab")
			(hide yes)
			(effects
				(font
					(size 1 1)
					(thickness 0.15)
				)
			)
		)
		(property "License" "Apache-2.0"
			(at 394.8 -14.8 0)
			(layer "F.Fab")
			(hide yes)
			(effects
				(font
					(size 1 1)
					(thickness 0.15)
				)
			)
		)
		(property "MPN" "RCW-0C"
			(at 394.8 -14.8 0)
			(layer "F.Fab")
			(hide yes)
			(effects
				(font
					(size 1 1)
					(thickness 0.15)
				)
			)
		)
		(property "Manufacturer" "TE Connectivity"
			(at 394.8 -14.8 0)
			(layer "F.Fab")
			(hide yes)
			(effects
				(font
					(size 1 1)
					(thickness 0.15)
				)
			)
		)
		(sheetname "/Supply/")
		(sheetfile "supply.kicad_sch")
		(attr smd)
		(fp_line
			(start 1.78 -0.981)
			(end 1.281 -0.981)
			(stroke
				(width 0.15)
				(type solid)
			)
			(layer "F.SilkS")
		)
		(fp_line
			(start 1.78 -0.981)
			(end 1.78 -0.479)
			(stroke
				(width 0.15)
				(type solid)
			)
			(layer "F.SilkS")
		)
		(fp_line
			(start -1.779 -0.981)
			(end -1.279 -0.981)
			(stroke
				(width 0.15)
				(type solid)
			)
			(layer "F.SilkS")
		)
		(fp_line
			(start -1.779 -0.981)
			(end -1.779 -0.479)
			(stroke
				(width 0.15)
				(type solid)
			)
			(layer "F.SilkS")
		)
		(fp_line
			(start -1.779 0.482)
			(end -1.779 0.98)
			(stroke
				(width 0.15)
				(type solid)
			)
			(layer "F.SilkS")
		)
		(fp_line
			(start -1.779 0.98)
			(end -1.279 0.98)
			(stroke
				(width 0.15)
				(type solid)
			)
			(layer "F.SilkS")
		)
		(fp_line
			(start 1.78 0.982)
			(end 1.78 0.482)
			(stroke
				(width 0.15)
				(type solid)
			)
			(layer "F.SilkS")
		)
		(fp_line
			(start 1.78 0.982)
			(end 1.281 0.982)
			(stroke
				(width 0.15)
				(type solid)
			)
			(layer "F.SilkS")
		)
		(fp_rect
			(start -2.101 -1.314)
			(end 2.1 1.312)
			(stroke
				(width 0.05)
				(type solid)
			)
			(fill no)
			(layer "F.CrtYd")
		)
		(fp_rect
			(start -1.601 -0.814)
			(end 1.6 0.812)
			(stroke
				(width 0.15)
				(type solid)
			)
			(fill no)
			(layer "F.Fab")
		)
		(pad "1" smd rect
			(at 0 0 90)
			(size 3.4 1.8)
			(layers "F.Cu" "F.Mask" "F.Paste")
			(net 1 "GND")
			(pinfunction "1")
			(pintype "passive")
		)
	)
	(footprint "antmicro-footprints:USON-10_2.5x1mm_P0.5mm"
		(layer "F.Cu")
		(at 84.8 172.95)
		(descr "USON-10 2.5x1mm_ Pitch 0.5mm")
		(tags "USON-10 2.5x1mm Pitch 0.5mm")
		(property "Reference" "U12"
			(at 0.018 -1.7 0)
			(layer "F.SilkS")
			(hide yes)
			(effects
				(font
					(size 0.7 0.7)
					(thickness 0.15)
				)
				(justify left bottom)
			)
		)
		(property "Value" "TPD4E05U06QDQARQ1"
			(at 0.018 2.499 0)
			(layer "F.Fab")
			(effects
				(font
					(size 0.7 0.7)
					(thickness 0.15)
				)
				(justify left bottom)
			)
		)
		(property "Datasheet" "https://www.ti.com/lit/ds/symlink/tpd4e05u06-q1.pdf?HQS=dis-mous-null-mousermode-dsf-pf-null-wwe&ts=1663591265741&ref_url=https%253A%252F%252Fwww.mouser.com%252F"
			(at 0 0 0)
			(layer "F.Fab")
			(hide yes)
			(effects
				(font
					(size 1.27 1.27)
					(thickness 0.15)
				)
			)
		)
		(property "Author" "Antmicro"
			(at 0 0 0)
			(layer "F.Fab")
			(hide yes)
			(effects
				(font
					(size 1 1)
					(thickness 0.15)
				)
			)
		)
		(property "License" "Apache-2.0"
			(at 0 0 0)
			(layer "F.Fab")
			(hide yes)
			(effects
				(font
					(size 1 1)
					(thickness 0.15)
				)
			)
		)
		(property "MPN" "TPD4E05U06QDQARQ1"
			(at 0 0 0)
			(layer "F.Fab")
			(hide yes)
			(effects
				(font
					(size 1 1)
					(thickness 0.15)
				)
			)
		)
		(property "Manufacturer" "Texas Instruments"
			(at 0 0 0)
			(layer "F.Fab")
			(hide yes)
			(effects
				(font
					(size 1 1)
					(thickness 0.15)
				)
			)
		)
		(sheetname "/HDMI + SD Card/")
		(sheetfile "hdmi-sd-card.kicad_sch")
		(attr smd)
		(fp_line
			(start 0.498 -1.401)
			(end -0.5 -1.401)
			(stroke
				(width 0.15)
				(type solid)
			)
			(layer "F.SilkS")
		)
		(fp_line
			(start 0.498 1.398)
			(end -0.5 1.398)
			(stroke
				(width 0.15)
				(type solid)
			)
			(layer "F.SilkS")
		)
		(fp_circle
			(center -0.68 -1.27)
			(end -0.63 -1.27)
			(stroke
				(width 0.15)
				(type solid)
			)
			(fill yes)
			(layer "F.SilkS")
		)
		(fp_rect
			(start -0.8 -1.5)
			(end 0.8 1.499)
			(stroke
				(width 0.05)
				(type solid)
			)
			(fill no)
			(layer "F.CrtYd")
		)
		(fp_line
			(start -0.5 -1)
			(end -0.5 1.249)
			(stroke
				(width 0.15)
				(type solid)
			)
			(layer "F.Fab")
		)
		(fp_line
			(start -0.5 1.249)
			(end 0.498 1.249)
			(stroke
				(width 0.15)
				(type solid)
			)
			(layer "F.Fab")
		)
		(fp_line
			(start -0.25 -1.25)
			(end -0.5 -1)
			(stroke
				(width 0.15)
				(type solid)
			)
			(layer "F.Fab")
		)
		(fp_line
			(start 0.498 -1.25)
			(end -0.25 -1.25)
			(stroke
				(width 0.15)
				(type solid)
			)
			(layer "F.Fab")
		)
		(fp_line
			(start 0.498 -1.25)
			(end 0.498 1.249)
			(stroke
				(width 0.15)
				(type solid)
			)
			(layer "F.Fab")
		)
		(pad "1" smd roundrect
			(at -0.387 -1 270)
			(size 0.25 0.55)
			(layers "F.Cu" "F.Mask" "F.Paste")
			(roundrect_rratio 0.25)
			(net 373 "/FPGA bank 16/SD.CLK")
			(pintype "passive")
		)
		(pad "2" smd roundrect
			(at -0.387 -0.5 270)
			(size 0.25 0.55)
			(layers "F.Cu" "F.Mask" "F.Paste")
			(roundrect_rratio 0.25)
			(net 372 "/FPGA bank 16/SD.CMD")
			(pintype "passive")
		)
		(pad "3" smd roundrect
			(at -0.387 0 270)
			(size 0.4 0.55)
			(layers "F.Cu" "F.Mask" "F.Paste")
			(roundrect_rratio 0.25)
			(net 1 "GND")
			(pintype "power_in")
		)
		(pad "4" smd roundrect
			(at -0.387 0.498 270)
			(size 0.25 0.55)
			(layers "F.Cu" "F.Mask" "F.Paste")
			(roundrect_rratio 0.25)
			(net 371 "/FPGA bank 16/SD.DAT3")
			(pintype "passive")
		)
		(pad "5" smd roundrect
			(at -0.387 0.998 270)
			(size 0.25 0.55)
			(layers "F.Cu" "F.Mask" "F.Paste")
			(roundrect_rratio 0.25)
			(net 350 "/FPGA bank 16/SD.DAT2")
			(pintype "passive")
		)
		(pad "6" smd roundrect
			(at 0.385 0.998 270)
			(size 0.25 0.55)
			(layers "F.Cu" "F.Mask" "F.Paste")
			(roundrect_rratio 0.25)
			(net 350 "/FPGA bank 16/SD.DAT2")
			(pintype "passive")
		)
		(pad "7" smd roundrect
			(at 0.385 0.498 270)
			(size 0.25 0.55)
			(layers "F.Cu" "F.Mask" "F.Paste")
			(roundrect_rratio 0.25)
			(net 371 "/FPGA bank 16/SD.DAT3")
			(pintype "passive")
		)
		(pad "8" smd roundrect
			(at 0.385 0 270)
			(size 0.4 0.55)
			(layers "F.Cu" "F.Mask" "F.Paste")
			(roundrect_rratio 0.25)
			(net 1 "GND")
			(pintype "passive")
		)
		(pad "9" smd roundrect
			(at 0.385 -0.5 270)
			(size 0.25 0.55)
			(layers "F.Cu" "F.Mask" "F.Paste")
			(roundrect_rratio 0.25)
			(net 372 "/FPGA bank 16/SD.CMD")
			(pintype "passive")
		)
		(pad "10" smd roundrect
			(at 0.385 -1 270)
			(size 0.25 0.55)
			(layers "F.Cu" "F.Mask" "F.Paste")
			(roundrect_rratio 0.25)
			(net 373 "/FPGA bank 16/SD.CLK")
			(pintype "passive")
		)
	)
	(footprint "antmicro-footprints:Fiducial_1mm_Mask2mm"
		(layer "F.Cu")
		(at 199 114)
		(descr "Circular Fiducial, 1mm bare copper, 3mm soldermask opening")
		(tags "fiducial")
		(property "Reference" "FID1006"
			(at 0 -1.4 0)
			(layer "F.SilkS")
			(hide yes)
			(effects
				(font
					(size 0.7 0.7)
					(thickness 0.15)
				)
				(justify left bottom)
			)
		)
		(property "Value" "Fiducial_1mm_Mask2mm"
			(at 0 2.2 0)
			(layer "F.Fab")
			(effects
				(font
					(size 0.7 0.7)
					(thickness 0.15)
				)
				(justify left bottom)
			)
		)
		(property "Author" "Antmicro"
			(at 0 0 0)
			(layer "F.Fab")
			(hide yes)
			(effects
				(font
					(size 1 1)
					(thickness 0.15)
				)
			)
		)
		(property "License" "Apache-2.0"
			(at 0 0 0)
			(layer "F.Fab")
			(hide yes)
			(effects
				(font
					(size 1 1)
					(thickness 0.15)
				)
			)
		)
		(property "MPN" ""
			(at 0 0 0)
			(layer "F.Fab")
			(hide yes)
			(effects
				(font
					(size 1 1)
					(thickness 0.15)
				)
			)
		)
		(property "Manufacturer" ""
			(at 0 0 0)
			(layer "F.Fab")
			(hide yes)
			(effects
				(font
					(size 1 1)
					(thickness 0.15)
				)
			)
		)
		(sheetfile "sodimm-ddr5-tester.kicad_sch")
		(attr board_only exclude_from_pos_files exclude_from_bom)
		(fp_circle
			(center 0 0)
			(end 1.24 0)
			(stroke
				(width 0.05)
				(type solid)
			)
			(fill no)
			(layer "F.CrtYd")
		)
		(fp_circle
			(center 0 0)
			(end 0.999 0)
			(stroke
				(width 0.15)
				(type solid)
			)
			(fill no)
			(layer "F.Fab")
		)
		(pad "" smd circle
			(at 0 0)
			(size 1 1)
			(layers "F.Cu" "F.Mask")
			(solder_mask_margin 0.5)
			(clearance 0.5)
		)
	)
	(footprint "antmicro-footprints:R_0402_1005Metric"
		(layer "F.Cu")
		(at 177.9 182.415)
		(descr "Resistor SMD 0402")
		(tags "resistor SMD 0402")
		(property "Reference" "R136"
			(at -1.122484 -0.772697 0)
			(layer "F.SilkS")
			(hide yes)
			(effects
				(font
					(size 0.7 0.7)
					(thickness 0.15)
				)
				(justify left bottom)
			)
		)
		(property "Value" "R_0R_0402"
			(at -1.011843 1.772047 0)
			(layer "F.Fab")
			(effects
				(font
					(size 0.7 0.7)
					(thickness 0.15)
				)
				(justify left bottom)
			)
		)
		(property "Datasheet" "https://industrial.panasonic.com/cdbs/www-data/pdf/RDA0000/AOA0000C301.pdf"
			(at 0 0 0)
			(layer "F.Fab")
			(hide yes)
			(effects
				(font
					(size 1.27 1.27)
					(thickness 0.15)
				)
			)
		)
		(property "Author" "Antmicro"
			(at 0 0 0)
			(layer "F.Fab")
			(hide yes)
			(effects
				(font
					(size 1 1)
					(thickness 0.15)
				)
			)
		)
		(property "Current" "1A"
			(at 0 0 0)
			(layer "F.Fab")
			(hide yes)
			(effects
				(font
					(size 1 1)
					(thickness 0.15)
				)
			)
		)
		(property "License" "Apache-2.0"
			(at 0 0 0)
			(layer "F.Fab")
			(hide yes)
			(effects
				(font
					(size 1 1)
					(thickness 0.15)
				)
			)
		)
		(property "MPN" "ERJ2GE0R00X"
			(at 0 0 0)
			(layer "F.Fab")
			(hide yes)
			(effects
				(font
					(size 1 1)
					(thickness 0.15)
				)
			)
		)
		(property "Manufacturer" "Panasonic"
			(at 0 0 0)
			(layer "F.Fab")
			(hide yes)
			(effects
				(font
					(size 1 1)
					(thickness 0.15)
				)
			)
		)
		(property "Tolerance" ""
			(at 0 0 0)
			(layer "F.Fab")
			(hide yes)
			(effects
				(font
					(size 1 1)
					(thickness 0.15)
				)
			)
		)
		(property "Val" "0R"
			(at 0 0 0)
			(layer "F.Fab")
			(hide yes)
			(effects
				(font
					(size 1 1)
					(thickness 0.15)
				)
			)
		)
		(sheetname "/Supply/")
		(sheetfile "supply.kicad_sch")
		(attr smd)
		(fp_rect
			(start -0.93 -0.47)
			(end 0.93 0.47)
			(stroke
				(width 0.05)
				(type solid)
			)
			(fill no)
			(layer "F.CrtYd")
		)
		(fp_rect
			(start -0.5 -0.25)
			(end 0.5 0.25)
			(stroke
				(width 0.15)
				(type solid)
			)
			(fill no)
			(layer "F.Fab")
		)
		(pad "1" smd roundrect
			(at -0.485 0)
			(size 0.59 0.64)
			(layers "F.Cu" "F.Mask" "F.Paste")
			(roundrect_rratio 0.25)
			(net 240 "POWER")
			(pintype "passive")
		)
		(pad "2" smd roundrect
			(at 0.485 0)
			(size 0.59 0.64)
			(layers "F.Cu" "F.Mask" "F.Paste")
			(roundrect_rratio 0.25)
			(net 280 "/Supply/PG1")
			(pintype "passive")
		)
	)
	(footprint "antmicro-footprints:Fiducial_1mm_Mask2mm"
		(layer "F.Cu")
		(at 82.460501 197.866)
		(descr "Circular Fiducial, 1mm bare copper, 3mm soldermask opening")
		(tags "fiducial")
		(property "Reference" "FID1004"
			(at 0 -1.4 0)
			(layer "F.SilkS")
			(hide yes)
			(effects
				(font
					(size 0.7 0.7)
					(thickness 0.15)
				)
				(justify left bottom)
			)
		)
		(property "Value" "Fiducial_1mm_Mask2mm"
			(at 0 2.2 0)
			(layer "F.Fab")
			(effects
				(font
					(size 0.7 0.7)
					(thickness 0.15)
				)
				(justify left bottom)
			)
		)
		(property "Author" "Antmicro"
			(at 0 0 0)
			(layer "F.Fab")
			(hide yes)
			(effects
				(font
					(size 1 1)
					(thickness 0.15)
				)
			)
		)
		(property "License" "Apache-2.0"
			(at 0 0 0)
			(layer "F.Fab")
			(hide yes)
			(effects
				(font
					(size 1 1)
					(thickness 0.15)
				)
			)
		)
		(property "MPN" ""
			(at 0 0 0)
			(layer "F.Fab")
			(hide yes)
			(effects
				(font
					(size 1 1)
					(thickness 0.15)
				)
			)
		)
		(property "Manufacturer" ""
			(at 0 0 0)
			(layer "F.Fab")
			(hide yes)
			(effects
				(font
					(size 1 1)
					(thickness 0.15)
				)
			)
		)
		(sheetfile "sodimm-ddr5-tester.kicad_sch")
		(attr board_only exclude_from_pos_files exclude_from_bom)
		(fp_circle
			(center 0 0)
			(end 1.24 0)
			(stroke
				(width 0.05)
				(type solid)
			)
			(fill no)
			(layer "F.CrtYd")
		)
		(fp_circle
			(center 0 0)
			(end 0.999 0)
			(stroke
				(width 0.15)
				(type solid)
			)
			(fill no)
			(layer "F.Fab")
		)
		(pad "" smd circle
			(at 0 0)
			(size 1 1)
			(layers "F.Cu" "F.Mask")
			(solder_mask_margin 0.5)
			(clearance 0.5)
		)
	)
	(footprint "antmicro-footprints:R_0402_1005Metric"
		(layer "F.Cu")
		(at 99.850501 120.291 -90)
		(descr "Resistor SMD 0402")
		(tags "resistor SMD 0402")
		(property "Reference" "R62"
			(at -1.122484 -0.772697 270)
			(layer "F.SilkS")
			(hide yes)
			(effects
				(font
					(size 0.7 0.7)
					(thickness 0.15)
				)
				(justify left bottom)
			)
		)
		(property "Value" "R_330R_0402"
			(at -1.011843 1.772047 270)
			(layer "F.Fab")
			(effects
				(font
					(size 0.7 0.7)
					(thickness 0.15)
				)
				(justify left bottom)
			)
		)
		(property "Datasheet" "https://www.bourns.com/docs/product-datasheets/cr.pdf"
			(at 0 0 270)
			(layer "F.Fab")
			(hide yes)
			(effects
				(font
					(size 1.27 1.27)
					(thickness 0.15)
				)
			)
		)
		(property "Author" "Antmicro"
			(at -20.440499 220.141501 0)
			(layer "F.Fab")
			(hide yes)
			(effects
				(font
					(size 1 1)
					(thickness 0.15)
				)
			)
		)
		(property "License" "Apache-2.0"
			(at -20.440499 220.141501 0)
			(layer "F.Fab")
			(hide yes)
			(effects
				(font
					(size 1 1)
					(thickness 0.15)
				)
			)
		)
		(property "MPN" "CR0402-FX-3300GLF"
			(at -20.440499 220.141501 0)
			(layer "F.Fab")
			(hide yes)
			(effects
				(font
					(size 1 1)
					(thickness 0.15)
				)
			)
		)
		(property "Manufacturer" "Bourns"
			(at -20.440499 220.141501 0)
			(layer "F.Fab")
			(hide yes)
			(effects
				(font
					(size 1 1)
					(thickness 0.15)
				)
			)
		)
		(property "Tolerance" "1%"
			(at -20.440499 220.141501 0)
			(layer "F.Fab")
			(hide yes)
			(effects
				(font
					(size 1 1)
					(thickness 0.15)
				)
			)
		)
		(property "Val" "330R"
			(at -20.440499 220.141501 0)
			(layer "F.Fab")
			(hide yes)
			(effects
				(font
					(size 1 1)
					(thickness 0.15)
				)
			)
		)
		(sheetname "/DDR5 SODIMM/")
		(sheetfile "ddr5-sodimm.kicad_sch")
		(attr smd)
		(fp_rect
			(start -0.93 -0.47)
			(end 0.93 0.47)
			(stroke
				(width 0.05)
				(type solid)
			)
			(fill no)
			(layer "F.CrtYd")
		)
		(fp_rect
			(start -0.5 -0.25)
			(end 0.5 0.25)
			(stroke
				(width 0.15)
				(type solid)
			)
			(fill no)
			(layer "F.Fab")
		)
		(pad "1" smd roundrect
			(at -0.485 0 270)
			(size 0.59 0.64)
			(layers "F.Cu" "F.Mask" "F.Paste")
			(roundrect_rratio 0.25)
			(net 302 "Net-(D9-C_{G})")
			(pintype "passive")
		)
		(pad "2" smd roundrect
			(at 0.485 0 270)
			(size 0.59 0.64)
			(layers "F.Cu" "F.Mask" "F.Paste")
			(roundrect_rratio 0.25)
			(net 359 "Net-(Q10-D)")
			(pintype "passive")
		)
	)
	(footprint "antmicro-footprints:C_0402_1005Metric"
		(layer "F.Cu")
		(at 183.120108 163.651)
		(descr "Capacitor SMD 0402")
		(tags "capacitor SMD 0402")
		(property "Reference" "C214"
			(at 0 -0.699 0)
			(layer "F.SilkS")
			(hide yes)
			(effects
				(font
					(size 0.7 0.7)
					(thickness 0.15)
				)
				(justify left bottom)
			)
		)
		(property "Value" "C_100n_0402"
			(at -1.022927 2.155213 0)
			(layer "F.Fab")
			(effects
				(font
					(size 0.7 0.7)
					(thickness 0.15)
				)
				(justify left bottom)
			)
		)
		(property "Datasheet" "https://www.murata.com/products/productdetail?partno=GRM155R61H104KE14%23"
			(at 0 0 0)
			(layer "F.Fab")
			(hide yes)
			(effects
				(font
					(size 1.27 1.27)
					(thickness 0.15)
				)
			)
		)
		(property "Author" "Antmicro"
			(at 0 0 0)
			(layer "F.Fab")
			(hide yes)
			(effects
				(font
					(size 1 1)
					(thickness 0.15)
				)
			)
		)
		(property "Dielectric" "X5R"
			(at 0 0 0)
			(layer "F.Fab")
			(hide yes)
			(effects
				(font
					(size 1 1)
					(thickness 0.15)
				)
			)
		)
		(property "License" "Apache-2.0"
			(at 0 0 0)
			(layer "F.Fab")
			(hide yes)
			(effects
				(font
					(size 1 1)
					(thickness 0.15)
				)
			)
		)
		(property "MPN" "GRM155R61H104KE14D"
			(at 0 0 0)
			(layer "F.Fab")
			(hide yes)
			(effects
				(font
					(size 1 1)
					(thickness 0.15)
				)
			)
		)
		(property "Manufacturer" "Murata"
			(at 0 0 0)
			(layer "F.Fab")
			(hide yes)
			(effects
				(font
					(size 1 1)
					(thickness 0.15)
				)
			)
		)
		(property "Val" "100n"
			(at 0 0 0)
			(layer "F.Fab")
			(hide yes)
			(effects
				(font
					(size 1 1)
					(thickness 0.15)
				)
			)
		)
		(property "Voltage" "50V"
			(at 0 0 0)
			(layer "F.Fab")
			(hide yes)
			(effects
				(font
					(size 1 1)
					(thickness 0.15)
				)
			)
		)
		(sheetname "/Supply/")
		(sheetfile "supply.kicad_sch")
		(attr smd)
		(fp_rect
			(start -0.9659 -0.481258)
			(end 0.9649 0.458742)
			(stroke
				(width 0.05)
				(type solid)
			)
			(fill no)
			(layer "F.CrtYd")
		)
		(fp_line
			(start -0.499 -0.25)
			(end 0.499 -0.25)
			(stroke
				(width 0.15)
				(type solid)
			)
			(layer "F.Fab")
		)
		(fp_line
			(start -0.499 0.248)
			(end -0.499 -0.25)
			(stroke
				(width 0.15)
				(type solid)
			)
			(layer "F.Fab")
		)
		(fp_line
			(start 0.499 -0.25)
			(end 0.499 0.248)
			(stroke
				(width 0.15)
				(type solid)
			)
			(layer "F.Fab")
		)
		(fp_line
			(start 0.499 0.248)
			(end -0.499 0.248)
			(stroke
				(width 0.15)
				(type solid)
			)
			(layer "F.Fab")
		)
		(pad "1" smd roundrect
			(at -0.484 0)
			(size 0.59 0.64)
			(layers "F.Cu" "F.Mask" "F.Paste")
			(roundrect_rratio 0.25)
			(net 200 "+3V3")
			(pintype "passive")
		)
		(pad "2" smd roundrect
			(at 0.484 0)
			(size 0.59 0.64)
			(layers "F.Cu" "F.Mask" "F.Paste")
			(roundrect_rratio 0.25)
			(net 1 "GND")
			(pintype "passive")
		)
	)
	(footprint "antmicro-footprints:LED_0603_1608Metric_G"
		(layer "F.Cu")
		(at 73.5 126.3)
		(descr "LED SMD 0603 Green")
		(tags "LED SMD 0603 Green")
		(property "Reference" "D3"
			(at -0.001 -0.901 0)
			(layer "F.SilkS")
			(hide yes)
			(effects
				(font
					(size 0.7 0.7)
					(thickness 0.15)
				)
				(justify left bottom)
			)
		)
		(property "Value" "LED_G_0603_KP-1608CGCK"
			(at -0.001 1.599 0)
			(layer "F.Fab")
			(effects
				(font
					(size 0.7 0.7)
					(thickness 0.15)
				)
				(justify left bottom)
			)
		)
		(property "Datasheet" "http://www.farnell.com/datasheets/2045956.pdf"
			(at 0 0 0)
			(layer "F.Fab")
			(hide yes)
			(effects
				(font
					(size 1.27 1.27)
					(thickness 0.15)
				)
			)
		)
		(property "Author" "Antmicro"
			(at 0 0 0)
			(layer "F.Fab")
			(hide yes)
			(effects
				(font
					(size 1 1)
					(thickness 0.15)
				)
			)
		)
		(property "License" "Apache-2.0"
			(at 0 0 0)
			(layer "F.Fab")
			(hide yes)
			(effects
				(font
					(size 1 1)
					(thickness 0.15)
				)
			)
		)
		(property "MPN" "KP-1608CGCK"
			(at 0 0 0)
			(layer "F.Fab")
			(hide yes)
			(effects
				(font
					(size 1 1)
					(thickness 0.15)
				)
			)
		)
		(property "Manufacturer" "Kingbright"
			(at 0 0 0)
			(layer "F.Fab")
			(hide yes)
			(effects
				(font
					(size 1 1)
					(thickness 0.15)
				)
			)
		)
		(sheetname "/FPGA Config/")
		(sheetfile "fpga-config.kicad_sch")
		(attr smd)
		(fp_line
			(start -0.271 -0.349)
			(end 0.269 -0.349)
			(stroke
				(width 0.15)
				(type solid)
			)
			(layer "F.SilkS")
		)
		(fp_line
			(start -0.271 0.348)
			(end 0.269 0.348)
			(stroke
				(width 0.15)
				(type solid)
			)
			(layer "F.SilkS")
		)
		(fp_line
			(start -0.107 -0.201)
			(end -0.107 0.198)
			(stroke
				(width 0.1)
				(type solid)
			)
			(layer "F.SilkS")
		)
		(fp_line
			(start -0.107 -0.201)
			(end 0.092 -0.001)
			(stroke
				(width 0.1)
				(type solid)
			)
			(layer "F.SilkS")
		)
		(fp_line
			(start -0.107 -0.001)
			(end -0.291 -0.001)
			(stroke
				(width 0.1)
				(type solid)
			)
			(layer "F.SilkS")
		)
		(fp_line
			(start 0.092 -0.201)
			(end 0.092 0.198)
			(stroke
				(width 0.1)
				(type solid)
			)
			(layer "F.SilkS")
		)
		(fp_line
			(start 0.092 -0.001)
			(end -0.107 0.198)
			(stroke
				(width 0.1)
				(type solid)
			)
			(layer "F.SilkS")
		)
		(fp_line
			(start 0.092 -0.001)
			(end 0.292 -0.001)
			(stroke
				(width 0.1)
				(type solid)
			)
			(layer "F.SilkS")
		)
		(fp_line
			(start 1.249 0.319)
			(end 1.249 -0.321)
			(stroke
				(width 0.15)
				(type solid)
			)
			(layer "F.SilkS")
		)
		(fp_rect
			(start -1.2192 -0.6096)
			(end 1.27 0.6016)
			(stroke
				(width 0.05)
				(type solid)
			)
			(fill no)
			(layer "F.CrtYd")
		)
		(fp_line
			(start -0.849 0.025)
			(end -0.442 0.381)
			(stroke
				(width 0.15)
				(type solid)
			)
			(layer "F.Fab")
		)
		(fp_line
			(start -0.6 -0.001)
			(end -0.202 -0.001)
			(stroke
				(width 0.15)
				(type solid)
			)
			(layer "F.Fab")
		)
		(fp_line
			(start -0.202 -0.201)
			(end -0.202 -0.001)
			(stroke
				(width 0.15)
				(type solid)
			)
			(layer "F.Fab")
		)
		(fp_line
			(start -0.202 -0.001)
			(end -0.202 0.201)
			(stroke
				(width 0.15)
				(type solid)
			)
			(layer "F.Fab")
		)
		(fp_line
			(start -0.202 0.201)
			(end 0.1 -0.001)
			(stroke
				(width 0.15)
				(type solid)
			)
			(layer "F.Fab")
		)
		(fp_line
			(start 0.1 -0.001)
			(end -0.202 -0.201)
			(stroke
				(width 0.15)
				(type solid)
			)
			(layer "F.Fab")
		)
		(fp_line
			(start 0.198 -0.201)
			(end 0.198 -0.101)
			(stroke
				(width 0.15)
				(type solid)
			)
			(layer "F.Fab")
		)
		(fp_line
			(start 0.198 -0.001)
			(end 0.596 -0.001)
			(stroke
				(width 0.15)
				(type solid)
			)
			(layer "F.Fab")
		)
		(fp_line
			(start 0.198 0.201)
			(end 0.198 -0.101)
			(stroke
				(width 0.15)
				(type solid)
			)
			(layer "F.Fab")
		)
		(fp_rect
			(start -0.849 -0.401)
			(end 0.849 0.401)
			(stroke
				(width 0.15)
				(type solid)
			)
			(fill no)
			(layer "F.Fab")
		)
		(pad "1" smd rect
			(at -0.751 -0.001 180)
			(size 0.8 0.8)
			(layers "F.Cu" "F.Mask" "F.Paste")
			(net 200 "+3V3")
			(pinfunction "1")
			(pintype "passive")
		)
		(pad "2" smd rect
			(at 0.749 -0.001 180)
			(size 0.8 0.8)
			(layers "F.Cu" "F.Mask" "F.Paste")
			(net 306 "Net-(D3-Pad2)")
			(pinfunction "2")
			(pintype "passive")
		)
	)
	(footprint "antmicro-footprints:SOT-23-5"
		(layer "F.Cu")
		(at 181.65 190.2 180)
		(property "Reference" "U34"
			(at -1.1 -1.95 0)
			(layer "F.SilkS")
			(effects
				(font
					(size 0.7 0.7)
					(thickness 0.15)
				)
				(justify right top)
			)
		)
		(property "Value" "AT24CS01_SOT23"
			(at 0.002 2.799 0)
			(layer "F.Fab")
			(effects
				(font
					(size 0.7 0.7)
					(thickness 0.15)
				)
				(justify right top)
			)
		)
		(property "Datasheet" "http://ww1.microchip.com/downloads/en/devicedoc/Atmel-8815-SEEPROM-AT24CS01-02-Datasheet.pdf"
			(at 0 0 0)
			(layer "F.Fab")
			(hide yes)
			(effects
				(font
					(size 1.27 1.27)
					(thickness 0.15)
				)
			)
		)
		(property "Description" "EEPROM Memory IC 1Kbit I²C 1 MHz 550 ns SOT-23-5"
			(at 0 0 0)
			(layer "F.Fab")
			(hide yes)
			(effects
				(font
					(size 1.27 1.27)
					(thickness 0.15)
				)
			)
		)
		(property "Manufacturer" "Atmel"
			(at 0 0 180)
			(unlocked yes)
			(layer "F.Fab")
			(hide yes)
			(effects
				(font
					(size 1 1)
					(thickness 0.15)
				)
			)
		)
		(property "MPN" "AT24CS01-ST"
			(at 0 0 180)
			(unlocked yes)
			(layer "F.Fab")
			(hide yes)
			(effects
				(font
					(size 1 1)
					(thickness 0.15)
				)
			)
		)
		(property "Author" "Antmicro"
			(at 0 0 180)
			(unlocked yes)
			(layer "F.Fab")
			(hide yes)
			(effects
				(font
					(size 1 1)
					(thickness 0.15)
				)
			)
		)
		(property "License" "Apache-2.0"
			(at 0 0 180)
			(unlocked yes)
			(layer "F.Fab")
			(hide yes)
			(effects
				(font
					(size 1 1)
					(thickness 0.15)
				)
			)
		)
		(sheetname "/I^{2}C/")
		(sheetfile "i2c.kicad_sch")
		(attr smd)
		(fp_line
			(start 0.8 1.599)
			(end 0.549 1.599)
			(stroke
				(width 0.15)
				(type solid)
			)
			(layer "F.SilkS")
		)
		(fp_line
			(start 0.8 1.3)
			(end 0.8 1.599)
			(stroke
				(width 0.15)
				(type solid)
			)
			(layer "F.SilkS")
		)
		(fp_line
			(start 0.8 0.55)
			(end 0.8 -0.55)
			(stroke
				(width 0.15)
				(type solid)
			)
			(layer "F.SilkS")
		)
		(fp_line
			(start 0.8 -1.3)
			(end 0.8 -1.6)
			(stroke
				(width 0.15)
				(type solid)
			)
			(layer "F.SilkS")
		)
		(fp_line
			(start 0.8 -1.6)
			(end 0.5 -1.6)
			(stroke
				(width 0.15)
				(type solid)
			)
			(layer "F.SilkS")
		)
		(fp_line
			(start -0.55 1.6)
			(end -0.85 1.6)
			(stroke
				(width 0.15)
				(type solid)
			)
			(layer "F.SilkS")
		)
		(fp_line
			(start -0.8 -1.6)
			(end -0.5 -1.6)
			(stroke
				(width 0.15)
				(type solid)
			)
			(layer "F.SilkS")
		)
		(fp_line
			(start -0.8 -1.6)
			(end -0.8 -1.3)
			(stroke
				(width 0.15)
				(type solid)
			)
			(layer "F.SilkS")
		)
		(fp_line
			(start -0.85 1.6)
			(end -0.85 1.301)
			(stroke
				(width 0.15)
				(type solid)
			)
			(layer "F.SilkS")
		)
		(fp_circle
			(center -1.25 -1.5)
			(end -1.2 -1.5)
			(stroke
				(width 0.15)
				(type solid)
			)
			(fill yes)
			(layer "F.SilkS")
		)
		(fp_poly
			(pts
				(xy 1.9 -1.76) (xy 1.9 1.75) (xy -1.9 1.75) (xy -1.9 -1.76)
			)
			(stroke
				(width 0.05)
				(type solid)
			)
			(fill no)
			(layer "F.CrtYd")
		)
		(fp_line
			(start -0.398 -1.525999)
			(end -0.874 -1.05)
			(stroke
				(width 0.15)
				(type solid)
			)
			(layer "F.Fab")
		)
		(fp_poly
			(pts
				(xy 0.874 1.523) (xy 0.874 -1.525) (xy -0.873 -1.525) (xy -0.873 1.523)
			)
			(stroke
				(width 0.15)
				(type solid)
			)
			(fill no)
			(layer "F.Fab")
		)
		(fp_text user "${REFERENCE}"
			(at -1.898 4.299 0)
			(layer "F.Fab")
			(effects
				(font
					(size 0.7 0.7)
					(thickness 0.15)
				)
				(justify right top)
			)
		)
		(fp_text user "Author: Antmicro"
			(at -1.898 5.499 0)
			(layer "F.Fab")
			(effects
				(font
					(size 0.7 0.7)
					(thickness 0.15)
				)
				(justify right top)
			)
		)
		(fp_text user "License: Apache-2.0"
			(at -1.898 6.7 0)
			(layer "F.Fab")
			(effects
				(font
					(size 0.7 0.7)
					(thickness 0.15)
				)
				(justify right top)
			)
		)
		(pad "1" smd rect
			(at -1.351 -0.951 90)
			(size 0.55 1)
			(layers "F.Cu" "F.Mask" "F.Paste")
			(net 762 "Net-(U34-SCL)")
			(pinfunction "SCL")
			(pintype "passive")
		)
		(pad "2" smd rect
			(at -1.351 0 90)
			(size 0.55 1)
			(layers "F.Cu" "F.Mask" "F.Paste")
			(net 1 "GND")
			(pinfunction "GND")
			(pintype "passive")
		)
		(pad "3" smd rect
			(at -1.351 0.949 90)
			(size 0.55 1)
			(layers "F.Cu" "F.Mask" "F.Paste")
			(net 761 "Net-(U34-SDA)")
			(pinfunction "SDA")
			(pintype "passive")
		)
		(pad "4" smd rect
			(at 1.35 0.949 90)
			(size 0.55 1)
			(layers "F.Cu" "F.Mask" "F.Paste")
			(net 759 "Net-(D17-C)")
			(pinfunction "VCC")
			(pintype "passive")
		)
		(pad "5" smd rect
			(at 1.35 -0.951 90)
			(size 0.55 1)
			(layers "F.Cu" "F.Mask" "F.Paste")
			(net 1 "GND")
			(pinfunction "WP")
			(pintype "passive")
		)
	)
	(footprint "antmicro-footprints:C_0805_2012Metric"
		(layer "F.Cu")
		(at 203.395501 184.4605 90)
		(descr "Capacitor SMD 0805")
		(tags "capacitor SMD 0805")
		(property "Reference" "C171"
			(at -2.10551 -1.198678 90)
			(layer "F.SilkS")
			(hide yes)
			(effects
				(font
					(size 0.7 0.7)
					(thickness 0.15)
				)
				(justify left bottom)
			)
		)
		(property "Value" "C_22u_25V_0805"
			(at -2.055717 1.963152 90)
			(layer "F.Fab")
			(effects
				(font
					(size 0.7 0.7)
					(thickness 0.15)
				)
				(justify left bottom)
			)
		)
		(property "Datasheet" "https://product.samsungsem.com/mlcc/CL21A226MAYNNN.do"
			(at 0 0 90)
			(layer "F.Fab")
			(hide yes)
			(effects
				(font
					(size 1.27 1.27)
					(thickness 0.15)
				)
			)
		)
		(property "Author" "Antmicro"
			(at 387.856001 -18.935001 0)
			(layer "F.Fab")
			(hide yes)
			(effects
				(font
					(size 1 1)
					(thickness 0.15)
				)
			)
		)
		(property "Dielectric" ""
			(at 387.856001 -18.935001 0)
			(layer "F.Fab")
			(hide yes)
			(effects
				(font
					(size 1 1)
					(thickness 0.15)
				)
			)
		)
		(property "License" "Apache-2.0"
			(at 387.856001 -18.935001 0)
			(layer "F.Fab")
			(hide yes)
			(effects
				(font
					(size 1 1)
					(thickness 0.15)
				)
			)
		)
		(property "MPN" "CL21A226MAYNNNE"
			(at 387.856001 -18.935001 0)
			(layer "F.Fab")
			(hide yes)
			(effects
				(font
					(size 1 1)
					(thickness 0.15)
				)
			)
		)
		(property "Manufacturer" "Samsung Electro-Mechanics"
			(at 387.856001 -18.935001 0)
			(layer "F.Fab")
			(hide yes)
			(effects
				(font
					(size 1 1)
					(thickness 0.15)
				)
			)
		)
		(property "Val" "22u_25V"
			(at 387.856001 -18.935001 0)
			(layer "F.Fab")
			(hide yes)
			(effects
				(font
					(size 1 1)
					(thickness 0.15)
				)
			)
		)
		(property "Voltage" ""
			(at 387.856001 -18.935001 0)
			(layer "F.Fab")
			(hide yes)
			(effects
				(font
					(size 1 1)
					(thickness 0.15)
				)
			)
		)
		(sheetname "/Supply/")
		(sheetfile "supply.kicad_sch")
		(attr smd)
		(fp_line
			(start -0.3 -0.8)
			(end 0.3 -0.8)
			(stroke
				(width 0.15)
				(type solid)
			)
			(layer "F.SilkS")
		)
		(fp_line
			(start -0.3 0.8)
			(end 0.3 0.8)
			(stroke
				(width 0.15)
				(type solid)
			)
			(layer "F.SilkS")
		)
		(fp_rect
			(start -1.9 -0.93)
			(end 1.9 0.93)
			(stroke
				(width 0.05)
				(type solid)
			)
			(fill no)
			(layer "F.CrtYd")
		)
		(fp_rect
			(start -0.95 -0.675)
			(end 0.95 0.675)
			(stroke
				(width 0.15)
				(type solid)
			)
			(fill no)
			(layer "F.Fab")
		)
		(pad "1" smd rect
			(at -1.05 0 90)
			(size 1.2 1.2)
			(layers "F.Cu" "F.Mask" "F.Paste")
			(net 1 "GND")
			(pintype "passive")
		)
		(pad "2" smd rect
			(at 1.05 0 90)
			(size 1.2 1.2)
			(layers "F.Cu" "F.Mask" "F.Paste")
			(net 38 "VDC")
			(pintype "passive")
		)
	)
	(footprint "antmicro-footprints:C_0603_1608Metric"
		(layer "F.Cu")
		(at 118.1 205.3 180)
		(descr "Capacitor SMD 0603")
		(tags "capacitor 0603")
		(property "Reference" "C225"
			(at -1.42757 -1.000252 180)
			(layer "F.SilkS")
			(hide yes)
			(effects
				(font
					(size 0.7 0.7)
					(thickness 0.15)
				)
				(justify left bottom)
			)
		)
		(property "Value" "C_10u_25V_0603"
			(at -1.42757 1.770288 180)
			(layer "F.Fab")
			(effects
				(font
					(size 0.7 0.7)
					(thickness 0.15)
				)
				(justify left bottom)
			)
		)
		(property "Datasheet" "https://product.tdk.com/en/search/capacitor/ceramic/mlcc/info?part_no=C1608X5R1E106M080AC"
			(at 0 0 180)
			(layer "F.Fab")
			(hide yes)
			(effects
				(font
					(size 1.27 1.27)
					(thickness 0.15)
				)
			)
		)
		(property "Author" "Antmicro"
			(at 236.2 410.6 0)
			(layer "F.Fab")
			(hide yes)
			(effects
				(font
					(size 1 1)
					(thickness 0.15)
				)
			)
		)
		(property "Dielectric" ""
			(at 236.2 410.6 0)
			(layer "F.Fab")
			(hide yes)
			(effects
				(font
					(size 1 1)
					(thickness 0.15)
				)
			)
		)
		(property "License" "Apache-2.0"
			(at 236.2 410.6 0)
			(layer "F.Fab")
			(hide yes)
			(effects
				(font
					(size 1 1)
					(thickness 0.15)
				)
			)
		)
		(property "MPN" "C1608X5R1E106M080AC"
			(at 236.2 410.6 0)
			(layer "F.Fab")
			(hide yes)
			(effects
				(font
					(size 1 1)
					(thickness 0.15)
				)
			)
		)
		(property "Manufacturer" "TDK"
			(at 236.2 410.6 0)
			(layer "F.Fab")
			(hide yes)
			(effects
				(font
					(size 1 1)
					(thickness 0.15)
				)
			)
		)
		(property "Val" "10u/25V"
			(at 236.2 410.6 0)
			(layer "F.Fab")
			(hide yes)
			(effects
				(font
					(size 1 1)
					(thickness 0.15)
				)
			)
		)
		(property "Voltage" ""
			(at 236.2 410.6 0)
			(layer "F.Fab")
			(hide yes)
			(effects
				(font
					(size 1 1)
					(thickness 0.15)
				)
			)
		)
		(sheetname "/PCIe connector/")
		(sheetfile "pcie-connector.kicad_sch")
		(attr smd)
		(fp_line
			(start -0.3 0.3)
			(end 0.3 0.3)
			(stroke
				(width 0.15)
				(type solid)
			)
			(layer "F.SilkS")
		)
		(fp_line
			(start -0.3 -0.3)
			(end 0.3 -0.3)
			(stroke
				(width 0.15)
				(type solid)
			)
			(layer "F.SilkS")
		)
		(fp_rect
			(start -1.24 -0.7)
			(end 1.24 0.7)
			(stroke
				(width 0.05)
				(type solid)
			)
			(fill no)
			(layer "F.CrtYd")
		)
		(fp_rect
			(start -0.8 -0.4)
			(end 0.8 0.4)
			(stroke
				(width 0.15)
				(type solid)
			)
			(fill no)
			(layer "F.Fab")
		)
		(pad "1" smd roundrect
			(at -0.7 0 180)
			(size 0.6 0.8)
			(layers "F.Cu" "F.Mask" "F.Paste")
			(roundrect_rratio 0.2)
			(net 1 "GND")
			(pintype "passive")
		)
		(pad "2" smd roundrect
			(at 0.7 0 180)
			(size 0.6 0.8)
			(layers "F.Cu" "F.Mask" "F.Paste")
			(roundrect_rratio 0.2)
			(net 11 "+12V")
			(pintype "passive")
		)
	)
	(footprint "antmicro-footprints:NetTie-2_SMD_Pad0.127mm"
		(layer "F.Cu")
		(at 189.525 189.101)
		(descr "Net tie, 2 pin, 0.127mm  SMD pads")
		(tags "net tie")
		(property "Reference" "NT1"
			(at -0.128 -1.345 0)
			(layer "F.SilkS")
			(hide yes)
			(effects
				(font
					(size 0.7 0.7)
					(thickness 0.15)
				)
				(justify left bottom)
			)
		)
		(property "Value" "Net-Tie_P0.127mm"
			(at 0 1.199 0)
			(layer "F.Fab")
			(effects
				(font
					(size 0.7 0.7)
					(thickness 0.15)
				)
				(justify left bottom)
			)
		)
		(property "Author" "Antmicro"
			(at 0 0 0)
			(layer "F.Fab")
			(hide yes)
			(effects
				(font
					(size 1 1)
					(thickness 0.15)
				)
			)
		)
		(property "License" "Apache-2.0"
			(at 0 0 0)
			(layer "F.Fab")
			(hide yes)
			(effects
				(font
					(size 1 1)
					(thickness 0.15)
				)
			)
		)
		(property "MPN" ""
			(at 0 0 0)
			(layer "F.Fab")
			(hide yes)
			(effects
				(font
					(size 1 1)
					(thickness 0.15)
				)
			)
		)
		(property "Manufacturer" ""
			(at 0 0 0)
			(layer "F.Fab")
			(hide yes)
			(effects
				(font
					(size 1 1)
					(thickness 0.15)
				)
			)
		)
		(property ki_fp_filters "Net*Tie*")
		(sheetname "/Supply/")
		(sheetfile "supply.kicad_sch")
		(attr smd exclude_from_pos_files exclude_from_bom)
		(net_tie_pad_groups "1, 2")
		(fp_poly
			(pts
				(xy -0.0635 -0.0635) (xy 0.0625 -0.0635) (xy 0.0625 0.0635) (xy -0.0635 0.0635)
			)
			(stroke
				(width 0)
				(type solid)
			)
			(fill yes)
			(layer "F.Cu")
		)
		(pad "1" smd roundrect
			(at -0.127 0 180)
			(size 0.127 0.127)
			(layers "F.Cu")
			(roundrect_rratio 0.5)
			(chamfer_ratio 0)
			(chamfer top_left bottom_left)
			(net 86 "/Supply/MGTAVCC_SEN_+")
			(pinfunction "1")
			(pintype "passive")
		)
		(pad "2" smd roundrect
			(at 0.126 0)
			(size 0.127 0.127)
			(layers "F.Cu")
			(roundrect_rratio 0.5)
			(chamfer_ratio 0)
			(chamfer top_left bottom_left)
			(net 42 "/Supply/MGTAVCC_local")
			(pinfunction "2")
			(pintype "passive")
		)
	)
	(footprint "antmicro-footprints:LED_0603_1608Metric_G"
		(layer "F.Cu")
		(at 76.060501 126.276)
		(descr "LED SMD 0603 Green")
		(tags "LED SMD 0603 Green")
		(property "Reference" "D2"
			(at -0.001 -0.901 0)
			(layer "F.SilkS")
			(hide yes)
			(effects
				(font
					(size 0.7 0.7)
					(thickness 0.15)
				)
				(justify left bottom)
			)
		)
		(property "Value" "LED_G_0603_KP-1608CGCK"
			(at -0.001 1.599 0)
			(layer "F.Fab")
			(effects
				(font
					(size 0.7 0.7)
					(thickness 0.15)
				)
				(justify left bottom)
			)
		)
		(property "Datasheet" "http://www.farnell.com/datasheets/2045956.pdf"
			(at 0 0 0)
			(layer "F.Fab")
			(hide yes)
			(effects
				(font
					(size 1.27 1.27)
					(thickness 0.15)
				)
			)
		)
		(property "Author" "Antmicro"
			(at 0 0 0)
			(layer "F.Fab")
			(hide yes)
			(effects
				(font
					(size 1 1)
					(thickness 0.15)
				)
			)
		)
		(property "License" "Apache-2.0"
			(at 0 0 0)
			(layer "F.Fab")
			(hide yes)
			(effects
				(font
					(size 1 1)
					(thickness 0.15)
				)
			)
		)
		(property "MPN" "KP-1608CGCK"
			(at 0 0 0)
			(layer "F.Fab")
			(hide yes)
			(effects
				(font
					(size 1 1)
					(thickness 0.15)
				)
			)
		)
		(property "Manufacturer" "Kingbright"
			(at 0 0 0)
			(layer "F.Fab")
			(hide yes)
			(effects
				(font
					(size 1 1)
					(thickness 0.15)
				)
			)
		)
		(sheetname "/FPGA Config/")
		(sheetfile "fpga-config.kicad_sch")
		(attr smd)
		(fp_line
			(start -0.271 -0.349)
			(end 0.269 -0.349)
			(stroke
				(width 0.15)
				(type solid)
			)
			(layer "F.SilkS")
		)
		(fp_line
			(start -0.271 0.348)
			(end 0.269 0.348)
			(stroke
				(width 0.15)
				(type solid)
			)
			(layer "F.SilkS")
		)
		(fp_line
			(start -0.107 -0.201)
			(end -0.107 0.198)
			(stroke
				(width 0.1)
				(type solid)
			)
			(layer "F.SilkS")
		)
		(fp_line
			(start -0.107 -0.201)
			(end 0.092 -0.001)
			(stroke
				(width 0.1)
				(type solid)
			)
			(layer "F.SilkS")
		)
		(fp_line
			(start -0.107 -0.001)
			(end -0.291 -0.001)
			(stroke
				(width 0.1)
				(type solid)
			)
			(layer "F.SilkS")
		)
		(fp_line
			(start 0.092 -0.201)
			(end 0.092 0.198)
			(stroke
				(width 0.1)
				(type solid)
			)
			(layer "F.SilkS")
		)
		(fp_line
			(start 0.092 -0.001)
			(end -0.107 0.198)
			(stroke
				(width 0.1)
				(type solid)
			)
			(layer "F.SilkS")
		)
		(fp_line
			(start 0.092 -0.001)
			(end 0.292 -0.001)
			(stroke
				(width 0.1)
				(type solid)
			)
			(layer "F.SilkS")
		)
		(fp_line
			(start 1.249 0.319)
			(end 1.249 -0.321)
			(stroke
				(width 0.15)
				(type solid)
			)
			(layer "F.SilkS")
		)
		(fp_rect
			(start -1.2192 -0.6096)
			(end 1.27 0.6016)
			(stroke
				(width 0.05)
				(type solid)
			)
			(fill no)
			(layer "F.CrtYd")
		)
		(fp_line
			(start -0.849 0.025)
			(end -0.442 0.381)
			(stroke
				(width 0.15)
				(type solid)
			)
			(layer "F.Fab")
		)
		(fp_line
			(start -0.6 -0.001)
			(end -0.202 -0.001)
			(stroke
				(width 0.15)
				(type solid)
			)
			(layer "F.Fab")
		)
		(fp_line
			(start -0.202 -0.201)
			(end -0.202 -0.001)
			(stroke
				(width 0.15)
				(type solid)
			)
			(layer "F.Fab")
		)
		(fp_line
			(start -0.202 -0.001)
			(end -0.202 0.201)
			(stroke
				(width 0.15)
				(type solid)
			)
			(layer "F.Fab")
		)
		(fp_line
			(start -0.202 0.201)
			(end 0.1 -0.001)
			(stroke
				(width 0.15)
				(type solid)
			)
			(layer "F.Fab")
		)
		(fp_line
			(start 0.1 -0.001)
			(end -0.202 -0.201)
			(stroke
				(width 0.15)
				(type solid)
			)
			(layer "F.Fab")
		)
		(fp_line
			(start 0.198 -0.201)
			(end 0.198 -0.101)
			(stroke
				(width 0.15)
				(type solid)
			)
			(layer "F.Fab")
		)
		(fp_line
			(start 0.198 -0.001)
			(end 0.596 -0.001)
			(stroke
				(width 0.15)
				(type solid)
			)
			(layer "F.Fab")
		)
		(fp_line
			(start 0.198 0.201)
			(end 0.198 -0.101)
			(stroke
				(width 0.15)
				(type solid)
			)
			(layer "F.Fab")
		)
		(fp_rect
			(start -0.849 -0.401)
			(end 0.849 0.401)
			(stroke
				(width 0.15)
				(type solid)
			)
			(fill no)
			(layer "F.Fab")
		)
		(pad "1" smd rect
			(at -0.751 -0.001 180)
			(size 0.8 0.8)
			(layers "F.Cu" "F.Mask" "F.Paste")
			(net 200 "+3V3")
			(pinfunction "1")
			(pintype "passive")
		)
		(pad "2" smd rect
			(at 0.749 -0.001 180)
			(size 0.8 0.8)
			(layers "F.Cu" "F.Mask" "F.Paste")
			(net 305 "Net-(D2-Pad2)")
			(pinfunction "2")
			(pintype "passive")
		)
	)
	(footprint "antmicro-footprints:L_Bourns-SRP6050CA"
		(layer "F.Cu")
		(at 170.825501 188.176 180)
		(property "Reference" "L1"
			(at 0 -3.89 180)
			(layer "F.SilkS")
			(hide yes)
			(effects
				(font
					(size 0.7 0.7)
					(thickness 0.15)
				)
				(justify left bottom)
			)
		)
		(property "Value" "L_1u5_17A_Bourns-SRP6050CA"
			(at -0.025 4.85 180)
			(layer "F.Fab")
			(effects
				(font
					(size 0.7 0.7)
					(thickness 0.15)
				)
				(justify left bottom)
			)
		)
		(property "Datasheet" "https://www.bourns.com/docs/Product-Datasheets/SRP6050CA.pdf"
			(at 0 0 180)
			(layer "F.Fab")
			(hide yes)
			(effects
				(font
					(size 1.27 1.27)
					(thickness 0.15)
				)
			)
		)
		(property "Author" "Antmicro"
			(at 341.651002 376.352 0)
			(layer "F.Fab")
			(hide yes)
			(effects
				(font
					(size 1 1)
					(thickness 0.15)
				)
			)
		)
		(property "IMax" "17 A"
			(at 341.651002 376.352 0)
			(layer "F.Fab")
			(hide yes)
			(effects
				(font
					(size 1 1)
					(thickness 0.15)
				)
			)
		)
		(property "ISat" "19.5 A"
			(at 341.651002 376.352 0)
			(layer "F.Fab")
			(hide yes)
			(effects
				(font
					(size 1 1)
					(thickness 0.15)
				)
			)
		)
		(property "License" "Apache-2.0"
			(at 341.651002 376.352 0)
			(layer "F.Fab")
			(hide yes)
			(effects
				(font
					(size 1 1)
					(thickness 0.15)
				)
			)
		)
		(property "MPN" "SRP6050CA-1R5M"
			(at 341.651002 376.352 0)
			(layer "F.Fab")
			(hide yes)
			(effects
				(font
					(size 1 1)
					(thickness 0.15)
				)
			)
		)
		(property "Manufacturer" "Bourns"
			(at 341.651002 376.352 0)
			(layer "F.Fab")
			(hide yes)
			(effects
				(font
					(size 1 1)
					(thickness 0.15)
				)
			)
		)
		(property "Size" "6.6x6.6"
			(at 341.651002 376.352 0)
			(layer "F.Fab")
			(hide yes)
			(effects
				(font
					(size 1 1)
					(thickness 0.15)
				)
			)
		)
		(property "Val" "1u5/17A"
			(at 341.651002 376.352 0)
			(layer "F.Fab")
			(hide yes)
			(effects
				(font
					(size 1 1)
					(thickness 0.15)
				)
			)
		)
		(sheetname "/Supply/")
		(sheetfile "supply.kicad_sch")
		(attr smd)
		(fp_line
			(start 3.2 3.298)
			(end -3.2 3.298)
			(stroke
				(width 0.15)
				(type solid)
			)
			(layer "F.SilkS")
		)
		(fp_line
			(start 3.2 -3.301)
			(end 3.2 3.298)
			(stroke
				(width 0.15)
				(type solid)
			)
			(layer "F.SilkS")
		)
		(fp_line
			(start -3.2 -3.301)
			(end 3.2 -3.301)
			(stroke
				(width 0.15)
				(type solid)
			)
			(layer "F.SilkS")
		)
		(fp_line
			(start -3.2 -3.301)
			(end -3.2 3.298)
			(stroke
				(width 0.15)
				(type solid)
			)
			(layer "F.SilkS")
		)
		(fp_rect
			(start -3.45 -3.55)
			(end 3.45 3.55)
			(stroke
				(width 0.05)
				(type solid)
			)
			(fill no)
			(layer "F.CrtYd")
		)
		(fp_rect
			(start -3.202 -3.301)
			(end 3.2 3.298)
			(stroke
				(width 0.15)
				(type solid)
			)
			(fill no)
			(layer "F.Fab")
		)
		(pad "1" smd roundrect
			(at -2.025 0 180)
			(size 1.55 5.6)
			(layers "F.Cu" "F.Mask" "F.Paste")
			(roundrect_rratio 0.1)
			(net 66 "/Supply/1V0_SW")
			(pintype "passive")
		)
		(pad "2" smd roundrect
			(at 2.025 0 180)
			(size 1.55 5.6)
			(layers "F.Cu" "F.Mask" "F.Paste")
			(roundrect_rratio 0.1)
			(net 78 "/Supply/1V0_REG")
			(pintype "passive")
		)
	)
	(footprint "antmicro-footprints:TP_SMD_1mm"
		(layer "F.Cu")
		(at 78.15 149)
		(property "Reference" "TP22"
			(at 0 -0.731898 0)
			(layer "F.SilkS")
			(hide yes)
			(effects
				(font
					(size 0.7 0.7)
					(thickness 0.15)
				)
				(justify left bottom)
			)
		)
		(property "Value" "TP_1mm_SMD"
			(at 0 1.4 0)
			(layer "F.Fab")
			(effects
				(font
					(size 0.7 0.7)
					(thickness 0.15)
				)
				(justify left bottom)
			)
		)
		(property "Author" "Antmicro"
			(at 0 0 0)
			(layer "F.Fab")
			(hide yes)
			(effects
				(font
					(size 1 1)
					(thickness 0.15)
				)
			)
		)
		(property "License" "Apache-2.0"
			(at 0 0 0)
			(layer "F.Fab")
			(hide yes)
			(effects
				(font
					(size 1 1)
					(thickness 0.15)
				)
			)
		)
		(property "MPN" ""
			(at 0 0 0)
			(layer "F.Fab")
			(hide yes)
			(effects
				(font
					(size 1 1)
					(thickness 0.15)
				)
			)
		)
		(property "Manufacturer" ""
			(at 0 0 0)
			(layer "F.Fab")
			(hide yes)
			(effects
				(font
					(size 1 1)
					(thickness 0.15)
				)
			)
		)
		(sheetname "/Debug FTDI/")
		(sheetfile "debug-ftdi.kicad_sch")
		(attr exclude_from_pos_files)
		(pad "1" smd circle
			(at 0 0)
			(size 1 1)
			(layers "F.Cu" "F.Mask")
			(net 2 "/Debug FTDI/VBUS")
			(pinfunction "1")
			(pintype "passive")
		)
	)
	(footprint "antmicro-footprints:SW_DIP_SPSTx08_Slide_Copal_CVS-08xB_W5.9mm_P1mm"
		(layer "F.Cu")
		(at 202.1285 153.3035)
		(descr "SMD 8x-dip-switch SPST Copal_CVS-08xB, Slide, row spacing 5.9 mm (232 mils), body size  (see http://www.nidec-copal-electronics.com/e/catalog/switch/cvs.pdf)")
		(tags "SMD DIP Switch SPST Slide 5.9mm 232mil")
		(property "Reference" "SW4"
			(at 1.3715 5.8965 0)
			(layer "F.SilkS")
			(effects
				(font
					(size 0.7 0.7)
					(thickness 0.15)
				)
				(justify left bottom)
			)
		)
		(property "Value" "SW_CVS-08TB"
			(at -14.59 6.29 0)
			(layer "F.Fab")
			(effects
				(font
					(size 0.7 0.7)
					(thickness 0.15)
				)
				(justify left bottom)
			)
		)
		(property "Datasheet" "https://www.mouser.com/datasheet/2/972/cvs-1827291.pdf"
			(at 0 0 0)
			(layer "F.Fab")
			(hide yes)
			(effects
				(font
					(size 1.27 1.27)
					(thickness 0.15)
				)
			)
		)
		(property "Author" "Antmicro"
			(at 0 0 0)
			(layer "F.Fab")
			(hide yes)
			(effects
				(font
					(size 1 1)
					(thickness 0.15)
				)
			)
		)
		(property "License" "Apache-2.0"
			(at 0 0 0)
			(layer "F.Fab")
			(hide yes)
			(effects
				(font
					(size 1 1)
					(thickness 0.15)
				)
			)
		)
		(property "MPN" "CVS-08TB"
			(at 0 0 0)
			(layer "F.Fab")
			(hide yes)
			(effects
				(font
					(size 1 1)
					(thickness 0.15)
				)
			)
		)
		(property "Manufacturer" "Nidec Components"
			(at 0 0 0)
			(layer "F.Fab")
			(hide yes)
			(effects
				(font
					(size 1 1)
					(thickness 0.15)
				)
			)
		)
		(property ki_fp_filters "SW?DIP?x2*")
		(sheetname "/Supply/")
		(sheetfile "supply.kicad_sch")
		(attr smd)
		(fp_line
			(start -1.561 -4.912)
			(end 1.56 -4.912)
			(stroke
				(width 0.15)
				(type solid)
			)
			(layer "F.SilkS")
		)
		(fp_line
			(start -1.561 4.91)
			(end 1.56 4.91)
			(stroke
				(width 0.15)
				(type solid)
			)
			(layer "F.SilkS")
		)
		(fp_circle
			(center -3.31 -4.2)
			(end -3.261 -4.2)
			(stroke
				(width 0.15)
				(type solid)
			)
			(fill yes)
			(layer "F.SilkS")
		)
		(fp_rect
			(start -3.601 -5)
			(end 3.598 4.998)
			(stroke
				(width 0.05)
				(type solid)
			)
			(fill no)
			(layer "F.CrtYd")
		)
		(fp_line
			(start -2.351 -3.5)
			(end -1.351 -4.5)
			(stroke
				(width 0.15)
				(type solid)
			)
			(layer "F.Fab")
		)
		(fp_line
			(start -2.351 4.498)
			(end -2.351 -3.5)
			(stroke
				(width 0.15)
				(type solid)
			)
			(layer "F.Fab")
		)
		(fp_line
			(start -1.351 -4.5)
			(end 2.35 -4.5)
			(stroke
				(width 0.15)
				(type solid)
			)
			(layer "F.Fab")
		)
		(fp_line
			(start -1 -3.75)
			(end -1 -3.25)
			(stroke
				(width 0.15)
				(type solid)
			)
			(layer "F.Fab")
		)
		(fp_line
			(start -1 -3.65)
			(end -0.335 -3.65)
			(stroke
				(width 0.15)
				(type solid)
			)
			(layer "F.Fab")
		)
		(fp_line
			(start -1 -3.551)
			(end -0.335 -3.551)
			(stroke
				(width 0.15)
				(type solid)
			)
			(layer "F.Fab")
		)
		(fp_line
			(start -1 -3.451)
			(end -0.335 -3.451)
			(stroke
				(width 0.15)
				(type solid)
			)
			(layer "F.Fab")
		)
		(fp_line
			(start -1 -3.351)
			(end -0.335 -3.351)
			(stroke
				(width 0.15)
				(type solid)
			)
			(layer "F.Fab")
		)
		(fp_line
			(start -1 -3.25)
			(end 0.998 -3.25)
			(stroke
				(width 0.15)
				(type solid)
			)
			(layer "F.Fab")
		)
		(fp_line
			(start -1 -2.75)
			(end -1 -2.25)
			(stroke
				(width 0.15)
				(type solid)
			)
			(layer "F.Fab")
		)
		(fp_line
			(start -1 -2.65)
			(end -0.335 -2.65)
			(stroke
				(width 0.15)
				(type solid)
			)
			(layer "F.Fab")
		)
		(fp_line
			(start -1 -2.551)
			(end -0.335 -2.551)
			(stroke
				(width 0.15)
				(type solid)
			)
			(layer "F.Fab")
		)
		(fp_line
			(start -1 -2.452)
			(end -0.335 -2.452)
			(stroke
				(width 0.15)
				(type solid)
			)
			(layer "F.Fab")
		)
		(fp_line
			(start -1 -2.351)
			(end -0.335 -2.351)
			(stroke
				(width 0.15)
				(type solid)
			)
			(layer "F.Fab")
		)
		(fp_line
			(start -1 -2.25)
			(end 0.998 -2.25)
			(stroke
				(width 0.15)
				(type solid)
			)
			(layer "F.Fab")
		)
		(fp_line
			(start -1 -1.75)
			(end -1 -1.25)
			(stroke
				(width 0.15)
				(type solid)
			)
			(layer "F.Fab")
		)
		(fp_line
			(start -1 -1.651)
			(end -0.335 -1.651)
			(stroke
				(width 0.15)
				(type solid)
			)
			(layer "F.Fab")
		)
		(fp_line
			(start -1 -1.551)
			(end -0.335 -1.551)
			(stroke
				(width 0.15)
				(type solid)
			)
			(layer "F.Fab")
		)
		(fp_line
			(start -1 -1.45)
			(end -0.335 -1.45)
			(stroke
				(width 0.15)
				(type solid)
			)
			(layer "F.Fab")
		)
		(fp_line
			(start -1 -1.351)
			(end -0.335 -1.351)
			(stroke
				(width 0.15)
				(type solid)
			)
			(layer "F.Fab")
		)
		(fp_line
			(start -1 -1.25)
			(end 0.998 -1.25)
			(stroke
				(width 0.15)
				(type solid)
			)
			(layer "F.Fab")
		)
		(fp_line
			(start -1 -0.75)
			(end -1 -0.25)
			(stroke
				(width 0.15)
				(type solid)
			)
			(layer "F.Fab")
		)
		(fp_line
			(start -1 -0.652)
			(end -0.335 -0.652)
			(stroke
				(width 0.15)
				(type solid)
			)
			(layer "F.Fab")
		)
		(fp_line
			(start -1 -0.552)
			(end -0.335 -0.552)
			(stroke
				(width 0.15)
				(type solid)
			)
			(layer "F.Fab")
		)
		(fp_line
			(start -1 -0.452)
			(end -0.335 -0.452)
			(stroke
				(width 0.15)
				(type solid)
			)
			(layer "F.Fab")
		)
		(fp_line
			(start -1 -0.351)
			(end -0.335 -0.351)
			(stroke
				(width 0.15)
				(type solid)
			)
			(layer "F.Fab")
		)
		(fp_line
			(start -1 -0.25)
			(end 0.998 -0.25)
			(stroke
				(width 0.15)
				(type solid)
			)
			(layer "F.Fab")
		)
		(fp_line
			(start -1 0.248)
			(end -1 0.748)
			(stroke
				(width 0.15)
				(type solid)
			)
			(layer "F.Fab")
		)
		(fp_line
			(start -1 0.349)
			(end -0.335 0.349)
			(stroke
				(width 0.15)
				(type solid)
			)
			(layer "F.Fab")
		)
		(fp_line
			(start -1 0.45)
			(end -0.335 0.45)
			(stroke
				(width 0.15)
				(type solid)
			)
			(layer "F.Fab")
		)
		(fp_line
			(start -1 0.55)
			(end -0.335 0.55)
			(stroke
				(width 0.15)
				(type solid)
			)
			(layer "F.Fab")
		)
		(fp_line
			(start -1 0.65)
			(end -0.335 0.65)
			(stroke
				(width 0.15)
				(type solid)
			)
			(layer "F.Fab")
		)
		(fp_line
			(start -1 0.748)
			(end -0.335 0.748)
			(stroke
				(width 0.15)
				(type solid)
			)
			(layer "F.Fab")
		)
		(fp_line
			(start -1 0.748)
			(end 0.998 0.748)
			(stroke
				(width 0.15)
				(type solid)
			)
			(layer "F.Fab")
		)
		(fp_line
			(start -1 1.249)
			(end -1 1.749)
			(stroke
				(width 0.15)
				(type solid)
			)
			(layer "F.Fab")
		)
		(fp_line
			(start -1 1.35)
			(end -0.335 1.35)
			(stroke
				(width 0.15)
				(type solid)
			)
			(layer "F.Fab")
		)
		(fp_line
			(start -1 1.449)
			(end -0.335 1.449)
			(stroke
				(width 0.15)
				(type solid)
			)
			(layer "F.Fab")
		)
		(fp_line
			(start -1 1.55)
			(end -0.335 1.55)
			(stroke
				(width 0.15)
				(type solid)
			)
			(layer "F.Fab")
		)
		(fp_line
			(start -1 1.648)
			(end -0.335 1.648)
			(stroke
				(width 0.15)
				(type solid)
			)
			(layer "F.Fab")
		)
		(fp_line
			(start -1 1.749)
			(end -0.335 1.749)
			(stroke
				(width 0.15)
				(type solid)
			)
			(layer "F.Fab")
		)
		(fp_line
			(start -1 1.749)
			(end 0.998 1.749)
			(stroke
				(width 0.15)
				(type solid)
			)
			(layer "F.Fab")
		)
		(fp_line
			(start -1 2.249)
			(end -1 2.749)
			(stroke
				(width 0.15)
				(type solid)
			)
			(layer "F.Fab")
		)
		(fp_line
			(start -1 2.35)
			(end -0.335 2.35)
			(stroke
				(width 0.15)
				(type solid)
			)
			(layer "F.Fab")
		)
		(fp_line
			(start -1 2.45)
			(end -0.335 2.45)
			(stroke
				(width 0.15)
				(type solid)
			)
			(layer "F.Fab")
		)
		(fp_line
			(start -1 2.548)
			(end -0.335 2.548)
			(stroke
				(width 0.15)
				(type solid)
			)
			(layer "F.Fab")
		)
		(fp_line
			(start -1 2.648)
			(end -0.335 2.648)
			(stroke
				(width 0.15)
				(type solid)
			)
			(layer "F.Fab")
		)
		(fp_line
			(start -1 2.749)
			(end -0.335 2.749)
			(stroke
				(width 0.15)
				(type solid)
			)
			(layer "F.Fab")
		)
		(fp_line
			(start -1 2.749)
			(end 0.998 2.749)
			(stroke
				(width 0.15)
				(type solid)
			)
			(layer "F.Fab")
		)
		(fp_line
			(start -1 3.249)
			(end -1 3.749)
			(stroke
				(width 0.15)
				(type solid)
			)
			(layer "F.Fab")
		)
		(fp_line
			(start -1 3.35)
			(end -0.335 3.35)
			(stroke
				(width 0.15)
				(type solid)
			)
			(layer "F.Fab")
		)
		(fp_line
			(start -1 3.45)
			(end -0.335 3.45)
			(stroke
				(width 0.15)
				(type solid)
			)
			(layer "F.Fab")
		)
		(fp_line
			(start -1 3.548)
			(end -0.335 3.548)
			(stroke
				(width 0.15)
				(type solid)
			)
			(layer "F.Fab")
		)
		(fp_line
			(start -1 3.648)
			(end -0.335 3.648)
			(stroke
				(width 0.15)
				(type solid)
			)
			(layer "F.Fab")
		)
		(fp_line
			(start -1 3.749)
			(end -0.335 3.749)
			(stroke
				(width 0.15)
				(type solid)
			)
			(layer "F.Fab")
		)
		(fp_line
			(start -1 3.749)
			(end 0.998 3.749)
			(stroke
				(width 0.15)
				(type solid)
			)
			(layer "F.Fab")
		)
		(fp_line
			(start -0.335 -3.75)
			(end -0.335 -3.25)
			(stroke
				(width 0.15)
				(type solid)
			)
			(layer "F.Fab")
		)
		(fp_line
			(start -0.335 -2.75)
			(end -0.335 -2.25)
			(stroke
				(width 0.15)
				(type solid)
			)
			(layer "F.Fab")
		)
		(fp_line
			(start -0.335 -1.75)
			(end -0.335 -1.25)
			(stroke
				(width 0.15)
				(type solid)
			)
			(layer "F.Fab")
		)
		(fp_line
			(start -0.335 -0.75)
			(end -0.335 -0.25)
			(stroke
				(width 0.15)
				(type solid)
			)
			(layer "F.Fab")
		)
		(fp_line
			(start -0.335 0.248)
			(end -0.335 0.748)
			(stroke
				(width 0.15)
				(type solid)
			)
			(layer "F.Fab")
		)
		(fp_line
			(start -0.335 1.249)
			(end -0.335 1.749)
			(stroke
				(width 0.15)
				(type solid)
			)
			(layer "F.Fab")
		)
		(fp_line
			(start -0.335 2.249)
			(end -0.335 2.749)
			(stroke
				(width 0.15)
				(type solid)
			)
			(layer "F.Fab")
		)
		(fp_line
			(start -0.335 3.249)
			(end -0.335 3.749)
			(stroke
				(width 0.15)
				(type solid)
			)
			(layer "F.Fab")
		)
		(fp_line
			(start 0.998 -3.75)
			(end -1 -3.75)
			(stroke
				(width 0.15)
				(type solid)
			)
			(layer "F.Fab")
		)
		(fp_line
			(start 0.998 -3.25)
			(end 0.998 -3.75)
			(stroke
				(width 0.15)
				(type solid)
			)
			(layer "F.Fab")
		)
		(fp_line
			(start 0.998 -2.75)
			(end -1 -2.75)
			(stroke
				(width 0.15)
				(type solid)
			)
			(layer "F.Fab")
		)
		(fp_line
			(start 0.998 -2.25)
			(end 0.998 -2.75)
			(stroke
				(width 0.15)
				(type solid)
			)
			(layer "F.Fab")
		)
		(fp_line
			(start 0.998 -1.75)
			(end -1 -1.75)
			(stroke
				(width 0.15)
				(type solid)
			)
			(layer "F.Fab")
		)
		(fp_line
			(start 0.998 -1.25)
			(end 0.998 -1.75)
			(stroke
				(width 0.15)
				(type solid)
			)
			(layer "F.Fab")
		)
		(fp_line
			(start 0.998 -0.75)
			(end -1 -0.75)
			(stroke
				(width 0.15)
				(type solid)
			)
			(layer "F.Fab")
		)
		(fp_line
			(start 0.998 -0.25)
			(end 0.998 -0.75)
			(stroke
				(width 0.15)
				(type solid)
			)
			(layer "F.Fab")
		)
		(fp_line
			(start 0.998 0.248)
			(end -1 0.248)
			(stroke
				(width 0.15)
				(type solid)
			)
			(layer "F.Fab")
		)
		(fp_line
			(start 0.998 0.748)
			(end 0.998 0.248)
			(stroke
				(width 0.15)
				(type solid)
			)
			(layer "F.Fab")
		)
		(fp_line
			(start 0.998 1.249)
			(end -1 1.249)
			(stroke
				(width 0.15)
				(type solid)
			)
			(layer "F.Fab")
		)
		(fp_line
			(start 0.998 1.749)
			(end 0.998 1.249)
			(stroke
				(width 0.15)
				(type solid)
			)
			(layer "F.Fab")
		)
		(fp_line
			(start 0.998 2.249)
			(end -1 2.249)
			(stroke
				(width 0.15)
				(type solid)
			)
			(layer "F.Fab")
		)
		(fp_line
			(start 0.998 2.749)
			(end 0.998 2.249)
			(stroke
				(width 0.15)
				(type solid)
			)
			(layer "F.Fab")
		)
		(fp_line
			(start 0.998 3.249)
			(end -1 3.249)
			(stroke
				(width 0.15)
				(type solid)
			)
			(layer "F.Fab")
		)
		(fp_line
			(start 0.998 3.749)
			(end 0.998 3.249)
			(stroke
				(width 0.15)
				(type solid)
			)
			(layer "F.Fab")
		)
		(fp_line
			(start 2.35 -4.5)
			(end 2.35 4.498)
			(stroke
				(width 0.15)
				(type solid)
			)
			(layer "F.Fab")
		)
		(fp_line
			(start 2.35 4.498)
			(end -2.351 4.498)
			(stroke
				(width 0.15)
				(type solid)
			)
			(layer "F.Fab")
		)
		(fp_text user "on"
			(at -1.56 0.69 90)
			(layer "F.Fab")
			(effects
				(font
					(size 0.7 0.7)
					(thickness 0.15)
				)
				(justify left bottom)
			)
		)
		(pad "1" smd rect
			(at -2.952 -3.5)
			(size 1.2 0.5)
			(layers "F.Cu" "F.Mask" "F.Paste")
			(net 186 "/Supply/PB_CTRL_OUT")
			(pinfunction "1")
			(pintype "passive")
		)
		(pad "2" smd rect
			(at -2.952 -2.5)
			(size 1.2 0.5)
			(layers "F.Cu" "F.Mask" "F.Paste")
			(net 207 "/Supply/~{PB_CTRL_INT}")
			(pinfunction "2")
			(pintype "passive")
		)
		(pad "3" smd rect
			(at -2.952 -1.5)
			(size 1.2 0.5)
			(layers "F.Cu" "F.Mask" "F.Paste")
			(net 686 "IN1")
			(pinfunction "3")
			(pintype "passive")
		)
		(pad "4" smd rect
			(at -2.952 -0.5)
			(size 1.2 0.5)
			(layers "F.Cu" "F.Mask" "F.Paste")
			(net 687 "IN2")
			(pinfunction "4")
			(pintype "passive")
		)
		(pad "5" smd rect
			(at -2.952 0.498)
			(size 1.2 0.5)
			(layers "F.Cu" "F.Mask" "F.Paste")
			(net 690 "/I^{2}C/PWR.SDA")
			(pinfunction "5")
			(pintype "passive")
		)
		(pad "6" smd rect
			(at -2.952 1.499)
			(size 1.2 0.5)
			(layers "F.Cu" "F.Mask" "F.Paste")
			(net 691 "/I^{2}C/PWR.SCL")
			(pinfunction "6")
			(pintype "passive")
		)
		(pad "7" smd rect
			(at -2.952 2.499)
			(size 1.2 0.5)
			(layers "F.Cu" "F.Mask" "F.Paste")
			(net 691 "/I^{2}C/PWR.SCL")
			(pinfunction "7")
			(pintype "passive")
		)
		(pad "8" smd rect
			(at -2.952 3.499)
			(size 1.2 0.5)
			(layers "F.Cu" "F.Mask" "F.Paste")
			(net 263 "FTDI_DIS")
			(pinfunction "8")
			(pintype "passive")
		)
		(pad "9" smd rect
			(at 2.95 3.499)
			(size 1.2 0.5)
			(layers "F.Cu" "F.Mask" "F.Paste")
			(net 1 "GND")
			(pinfunction "9")
			(pintype "passive")
		)
		(pad "10" smd rect
			(at 2.95 2.499)
			(size 1.2 0.5)
			(layers "F.Cu" "F.Mask" "F.Paste")
			(net 285 "/Supply/QDCDC2_SCL")
			(pinfunction "10")
			(pintype "passive")
		)
		(pad "11" smd rect
			(at 2.95 1.499)
			(size 1.2 0.5)
			(layers "F.Cu" "F.Mask" "F.Paste")
			(net 297 "/Supply/PWR_SCL_2")
			(pinfunction "11")
			(pintype "passive")
		)
		(pad "12" smd rect
			(at 2.95 0.498)
			(size 1.2 0.5)
			(layers "F.Cu" "F.Mask" "F.Paste")
			(net 298 "/Supply/PWR_SDA_2")
			(pinfunction "12")
			(pintype "passive")
		)
		(pad "13" smd rect
			(at 2.95 -0.5)
			(size 1.2 0.5)
			(layers "F.Cu" "F.Mask" "F.Paste")
			(net 1 "GND")
			(pinfunction "13")
			(pintype "passive")
		)
		(pad "14" smd rect
			(at 2.95 -1.5)
			(size 1.2 0.5)
			(layers "F.Cu" "F.Mask" "F.Paste")
			(net 1 "GND")
			(pinfunction "14")
			(pintype "passive")
		)
		(pad "15" smd rect
			(at 2.95 -2.5)
			(size 1.2 0.5)
			(layers "F.Cu" "F.Mask" "F.Paste")
			(net 185 "/Supply/~{PB_CTRL_CLR}")
			(pinfunction "15")
			(pintype "passive")
		)
		(pad "16" smd rect
			(at 2.95 -3.5)
			(size 1.2 0.5)
			(layers "F.Cu" "F.Mask" "F.Paste")
			(net 62 "/Supply/SEQ_EN")
			(pinfunction "16")
			(pintype "passive")
		)
		(pad "17" smd rect
			(at -2.15 -4.5)
			(size 0.7 0.7)
			(layers "F.Cu" "F.Mask" "F.Paste")
			(net 1 "GND")
			(pinfunction "17")
			(pintype "power_in")
		)
		(pad "17" smd rect
			(at -2.15 4.498)
			(size 0.7 0.7)
			(layers "F.Cu" "F.Mask" "F.Paste")
			(net 1 "GND")
			(pinfunction "17")
			(pintype "power_in")
		)
		(pad "17" smd rect
			(at 2.148 -4.5)
			(size 0.7 0.7)
			(layers "F.Cu" "F.Mask" "F.Paste")
			(net 1 "GND")
			(pinfunction "17")
			(pintype "power_in")
		)
		(pad "17" smd rect
			(at 2.148 4.498)
			(size 0.7 0.7)
			(layers "F.Cu" "F.Mask" "F.Paste")
			(net 1 "GND")
			(pinfunction "17")
			(pintype "power_in")
		)
	)
	(footprint "antmicro-footprints:Heatsink_960-27-12-D-AB-0"
		(layer "F.Cu")
		(at 138.880501 174.811 90)
		(descr "27mm x 27mm Heat Sink, BGA, Black Anodized Aluminum, Top Mount, Push Pin")
		(property "Reference" "H1"
			(at 0 -21.8 90)
			(unlocked yes)
			(layer "F.SilkS")
			(hide yes)
			(effects
				(font
					(size 0.7 0.7)
					(thickness 0.15)
				)
				(justify left bottom)
			)
		)
		(property "Value" "Heatsink_960-27-12-D-AB-0"
			(at 0 22.6 90)
			(unlocked yes)
			(layer "F.Fab")
			(effects
				(font
					(size 0.7 0.7)
					(thickness 0.15)
				)
				(justify left bottom)
			)
		)
		(property "Datasheet" "https://media.digikey.com/pdf/Data%20Sheets/Wakefield%20Thermal%20PDFs/960_Series.pdf"
			(at 0 0 90)
			(layer "F.Fab")
			(hide yes)
			(effects
				(font
					(size 1.27 1.27)
					(thickness 0.15)
				)
			)
		)
		(property "Author" "Antmicro"
			(at 313.691501 35.930499 0)
			(layer "F.Fab")
			(hide yes)
			(effects
				(font
					(size 1 1)
					(thickness 0.15)
				)
			)
		)
		(property "License" "Apache-2.0"
			(at 313.691501 35.930499 0)
			(layer "F.Fab")
			(hide yes)
			(effects
				(font
					(size 1 1)
					(thickness 0.15)
				)
			)
		)
		(property "MPN" "960-27-12-D-AB-0"
			(at 313.691501 35.930499 0)
			(layer "F.Fab")
			(hide yes)
			(effects
				(font
					(size 1 1)
					(thickness 0.15)
				)
			)
		)
		(property "Manufacturer" "Wakefield-Vette"
			(at 313.691501 35.930499 0)
			(layer "F.Fab")
			(hide yes)
			(effects
				(font
					(size 1 1)
					(thickness 0.15)
				)
			)
		)
		(property ki_fp_filters "Heatsink_*")
		(sheetname "/")
		(sheetfile "sodimm-ddr5-tester.kicad_sch")
		(attr through_hole exclude_from_pos_files exclude_from_bom dnp)
		(fp_rect
			(start -21.35 -21.35)
			(end 21.36 21.35)
			(stroke
				(width 0.05)
				(type solid)
			)
			(fill no)
			(layer "F.CrtYd")
		)
		(fp_circle
			(center 16.91 -16.93)
			(end 19.46 -16.93)
			(stroke
				(width 0.05)
				(type solid)
			)
			(fill no)
			(layer "F.CrtYd")
		)
		(fp_circle
			(center -16.92 16.92)
			(end -14.38 16.92)
			(stroke
				(width 0.05)
				(type solid)
			)
			(fill no)
			(layer "F.CrtYd")
		)
		(pad "" np_thru_hole circle
			(at -16.92 16.925 90)
			(size 3.18 3.18)
			(drill 3.18)
			(layers "*.Cu" "*.Mask")
		)
		(pad "" np_thru_hole circle
			(at 16.93 -16.925 90)
			(size 3.18 3.18)
			(drill 3.18)
			(layers "*.Cu" "*.Mask")
		)
	)
	(footprint "antmicro-footprints:R_0603_1608Metric"
		(layer "F.Cu")
		(at 166.100501 194.15 180)
		(descr "Resistor SMD 0603")
		(tags "resistor SMD 0603")
		(property "Reference" "R189"
			(at 1.550501 0.9 180)
			(layer "F.SilkS")
			(effects
				(font
					(size 0.7 0.7)
					(thickness 0.15)
				)
				(justify left bottom)
			)
		)
		(property "Value" "R_0R_22.4A_0603"
			(at 0 1.6 180)
			(layer "F.Fab")
			(effects
				(font
					(size 0.7 0.7)
					(thickness 0.15)
				)
				(justify left bottom)
			)
		)
		(property "Datasheet" "https://fscdn.rohm.com/en/products/databook/datasheet/passive/resistor/chip_resistor/pmr-jpw-e.pdf"
			(at 0 0 180)
			(layer "F.Fab")
			(hide yes)
			(effects
				(font
					(size 1.27 1.27)
					(thickness 0.15)
				)
			)
		)
		(property "Author" "Antmicro"
			(at 332.201002 388.3 0)
			(layer "F.Fab")
			(hide yes)
			(effects
				(font
					(size 1 1)
					(thickness 0.15)
				)
			)
		)
		(property "License" "Apache-2.0"
			(at 332.201002 388.3 0)
			(layer "F.Fab")
			(hide yes)
			(effects
				(font
					(size 1 1)
					(thickness 0.15)
				)
			)
		)
		(property "MPN" "PMR03EZPJ000"
			(at 332.201002 388.3 0)
			(layer "F.Fab")
			(hide yes)
			(effects
				(font
					(size 1 1)
					(thickness 0.15)
				)
			)
		)
		(property "Manufacturer" "ROHM Semiconductor"
			(at 332.201002 388.3 0)
			(layer "F.Fab")
			(hide yes)
			(effects
				(font
					(size 1 1)
					(thickness 0.15)
				)
			)
		)
		(property "Max. Curr." "22.4A"
			(at 332.201002 388.3 0)
			(layer "F.Fab")
			(hide yes)
			(effects
				(font
					(size 1 1)
					(thickness 0.15)
				)
			)
		)
		(property "Val" "0R"
			(at 332.201002 388.3 0)
			(layer "F.Fab")
			(hide yes)
			(effects
				(font
					(size 1 1)
					(thickness 0.15)
				)
			)
		)
		(sheetname "/Supply/")
		(sheetfile "supply.kicad_sch")
		(attr smd)
		(fp_line
			(start -0.3 0.3)
			(end 0.3 0.3)
			(stroke
				(width 0.15)
				(type solid)
			)
			(layer "F.SilkS")
		)
		(fp_line
			(start -0.3 -0.3)
			(end 0.3 -0.3)
			(stroke
				(width 0.15)
				(type solid)
			)
			(layer "F.SilkS")
		)
		(fp_rect
			(start -1.25 -0.7)
			(end 1.25 0.7)
			(stroke
				(width 0.05)
				(type solid)
			)
			(fill no)
			(layer "F.CrtYd")
		)
		(fp_rect
			(start -0.8 -0.4)
			(end 0.8 0.4)
			(stroke
				(width 0.15)
				(type solid)
			)
			(fill no)
			(layer "F.Fab")
		)
		(pad "1" smd roundrect
			(at -0.7 0 180)
			(size 0.6 0.8)
			(layers "F.Cu" "F.Mask" "F.Paste")
			(roundrect_rratio 0.2)
			(net 78 "/Supply/1V0_REG")
			(pintype "passive")
		)
		(pad "2" smd roundrect
			(at 0.7 0 180)
			(size 0.6 0.8)
			(layers "F.Cu" "F.Mask" "F.Paste")
			(roundrect_rratio 0.2)
			(net 227 "+1V0")
			(pintype "passive")
		)
	)
	(footprint "antmicro-footprints:SOT-143-4"
		(layer "F.Cu")
		(at 196.5495 142.8135 -90)
		(descr "http://datasheets.maximintegrated.com/en/ds/MAX6816-MAX6818.pdf")
		(property "Reference" "U26"
			(at 1.6865 -2.7505 270)
			(layer "F.SilkS")
			(effects
				(font
					(size 0.7 0.7)
					(thickness 0.15)
				)
				(justify left bottom)
			)
		)
		(property "Value" "MAX812REUS+T"
			(at 0 2.999 270)
			(layer "F.Fab")
			(effects
				(font
					(size 0.7 0.7)
					(thickness 0.15)
				)
				(justify left bottom)
			)
		)
		(property "Datasheet" "https://datasheets.maximintegrated.com/en/ds/MAX811-MAX812T.pdf"
			(at 0 0 270)
			(layer "F.Fab")
			(hide yes)
			(effects
				(font
					(size 1.27 1.27)
					(thickness 0.15)
				)
			)
		)
		(property "Author" "Antmicro"
			(at 53.736 339.363 0)
			(layer "F.Fab")
			(hide yes)
			(effects
				(font
					(size 1 1)
					(thickness 0.15)
				)
			)
		)
		(property "License" "Apache-2.0"
			(at 53.736 339.363 0)
			(layer "F.Fab")
			(hide yes)
			(effects
				(font
					(size 1 1)
					(thickness 0.15)
				)
			)
		)
		(property "MPN" "MAX812REUS+T"
			(at 53.736 339.363 0)
			(layer "F.Fab")
			(hide yes)
			(effects
				(font
					(size 1 1)
					(thickness 0.15)
				)
			)
		)
		(property "Manufacturer" "Maxim Integrated Products"
			(at 53.736 339.363 0)
			(layer "F.Fab")
			(hide yes)
			(effects
				(font
					(size 1 1)
					(thickness 0.15)
				)
			)
		)
		(sheetname "/Supply/")
		(sheetfile "supply.kicad_sch")
		(attr smd)
		(fp_circle
			(center -2.1 1.7)
			(end -2.05 1.7)
			(stroke
				(width 0.15)
				(type solid)
			)
			(fill yes)
			(layer "F.SilkS")
		)
		(fp_rect
			(start -1.776 -1.896)
			(end 1.773 1.895)
			(stroke
				(width 0.05)
				(type solid)
			)
			(fill no)
			(layer "F.CrtYd")
		)
		(fp_line
			(start -1.46 0.65)
			(end 1.459 0.65)
			(stroke
				(width 0.15)
				(type solid)
			)
			(layer "F.Fab")
		)
		(fp_line
			(start -1.46 0.65)
			(end -1.46 -0.652)
			(stroke
				(width 0.15)
				(type solid)
			)
			(layer "F.Fab")
		)
		(fp_line
			(start 1.459 -0.652)
			(end 1.459 0.65)
			(stroke
				(width 0.15)
				(type solid)
			)
			(layer "F.Fab")
		)
		(fp_line
			(start 1.459 -0.652)
			(end -1.46 -0.652)
			(stroke
				(width 0.15)
				(type solid)
			)
			(layer "F.Fab")
		)
		(pad "1" smd roundrect
			(at -0.76 0.998 270)
			(size 0.94 1.31)
			(layers "F.Cu" "F.Mask" "F.Paste")
			(roundrect_rratio 0.25)
			(net 1 "GND")
			(pinfunction "GND")
			(pintype "power_in")
		)
		(pad "2" smd roundrect
			(at 0.959 0.998 270)
			(size 0.55 1.31)
			(layers "F.Cu" "F.Mask" "F.Paste")
			(roundrect_rratio 0.25)
			(net 368 "Net-(Q17-G)")
			(pinfunction "~{RST}")
			(pintype "output")
		)
		(pad "3" smd roundrect
			(at 0.959 -1 270)
			(size 0.55 1.31)
			(layers "F.Cu" "F.Mask" "F.Paste")
			(roundrect_rratio 0.25)
			(net 367 "Net-(Q16-D)")
			(pinfunction "~{MR}")
			(pintype "input")
		)
		(pad "4" smd roundrect
			(at -0.96 -1 270)
			(size 0.55 1.31)
			(layers "F.Cu" "F.Mask" "F.Paste")
			(roundrect_rratio 0.25)
			(net 41 "+3V3_AON")
			(pinfunction "VCC")
			(pintype "power_in")
		)
	)
	(footprint "antmicro-footprints:C_0603_1608Metric"
		(layer "F.Cu")
		(at 168.655502 197.114502 180)
		(descr "Capacitor SMD 0603")
		(tags "capacitor 0603")
		(property "Reference" "C219"
			(at -1.42757 -1.000252 180)
			(layer "F.SilkS")
			(hide yes)
			(effects
				(font
					(size 0.7 0.7)
					(thickness 0.15)
				)
				(justify left bottom)
			)
		)
		(property "Value" "C_22u_0603"
			(at -1.42757 1.770288 180)
			(layer "F.Fab")
			(effects
				(font
					(size 0.7 0.7)
					(thickness 0.15)
				)
				(justify left bottom)
			)
		)
		(property "Datasheet" "https://www.murata.com/products/productdetail?partno=GRM188R60J226MEA0%23"
			(at 0 0 180)
			(layer "F.Fab")
			(hide yes)
			(effects
				(font
					(size 1.27 1.27)
					(thickness 0.15)
				)
			)
		)
		(property "Author" "Antmicro"
			(at 337.311004 394.229004 0)
			(layer "F.Fab")
			(hide yes)
			(effects
				(font
					(size 1 1)
					(thickness 0.15)
				)
			)
		)
		(property "Dielectric" ""
			(at 337.311004 394.229004 0)
			(layer "F.Fab")
			(hide yes)
			(effects
				(font
					(size 1 1)
					(thickness 0.15)
				)
			)
		)
		(property "License" "Apache-2.0"
			(at 337.311004 394.229004 0)
			(layer "F.Fab")
			(hide yes)
			(effects
				(font
					(size 1 1)
					(thickness 0.15)
				)
			)
		)
		(property "MPN" "GRM188R60J226MEA0D"
			(at 337.311004 394.229004 0)
			(layer "F.Fab")
			(hide yes)
			(effects
				(font
					(size 1 1)
					(thickness 0.15)
				)
			)
		)
		(property "Manufacturer" "Murata"
			(at 337.311004 394.229004 0)
			(layer "F.Fab")
			(hide yes)
			(effects
				(font
					(size 1 1)
					(thickness 0.15)
				)
			)
		)
		(property "Val" "22u"
			(at 337.311004 394.229004 0)
			(layer "F.Fab")
			(hide yes)
			(effects
				(font
					(size 1 1)
					(thickness 0.15)
				)
			)
		)
		(property "Voltage" ""
			(at 337.311004 394.229004 0)
			(layer "F.Fab")
			(hide yes)
			(effects
				(font
					(size 1 1)
					(thickness 0.15)
				)
			)
		)
		(sheetname "/Supply/")
		(sheetfile "supply.kicad_sch")
		(attr smd)
		(fp_line
			(start -0.3 0.3)
			(end 0.3 0.3)
			(stroke
				(width 0.15)
				(type solid)
			)
			(layer "F.SilkS")
		)
		(fp_line
			(start -0.3 -0.3)
			(end 0.3 -0.3)
			(stroke
				(width 0.15)
				(type solid)
			)
			(layer "F.SilkS")
		)
		(fp_rect
			(start -1.24 -0.7)
			(end 1.24 0.7)
			(stroke
				(width 0.05)
				(type solid)
			)
			(fill no)
			(layer "F.CrtYd")
		)
		(fp_rect
			(start -0.8 -0.4)
			(end 0.8 0.4)
			(stroke
				(width 0.15)
				(type solid)
			)
			(fill no)
			(layer "F.Fab")
		)
		(pad "1" smd roundrect
			(at -0.7 0 180)
			(size 0.6 0.8)
			(layers "F.Cu" "F.Mask" "F.Paste")
			(roundrect_rratio 0.2)
			(net 1 "GND")
			(pintype "passive")
		)
		(pad "2" smd roundrect
			(at 0.7 0 180)
			(size 0.6 0.8)
			(layers "F.Cu" "F.Mask" "F.Paste")
			(roundrect_rratio 0.2)
			(net 78 "/Supply/1V0_REG")
			(pintype "passive")
		)
	)
	(footprint "antmicro-footprints:R_0402_1005Metric"
		(layer "F.Cu")
		(at 82.010758 182.9281 -90)
		(descr "Resistor SMD 0402")
		(tags "resistor SMD 0402")
		(property "Reference" "R89"
			(at -1.122484 -0.772697 270)
			(layer "F.SilkS")
			(hide yes)
			(effects
				(font
					(size 0.7 0.7)
					(thickness 0.15)
				)
				(justify left bottom)
			)
		)
		(property "Value" "R_330R_0402"
			(at -1.011843 1.772047 270)
			(layer "F.Fab")
			(effects
				(font
					(size 0.7 0.7)
					(thickness 0.15)
				)
				(justify left bottom)
			)
		)
		(property "Datasheet" "https://www.bourns.com/docs/product-datasheets/cr.pdf"
			(at 0 0 270)
			(layer "F.Fab")
			(hide yes)
			(effects
				(font
					(size 1.27 1.27)
					(thickness 0.15)
				)
			)
		)
		(property "Author" "Antmicro"
			(at -100.917342 264.938858 0)
			(layer "F.Fab")
			(hide yes)
			(effects
				(font
					(size 1 1)
					(thickness 0.15)
				)
			)
		)
		(property "License" "Apache-2.0"
			(at -100.917342 264.938858 0)
			(layer "F.Fab")
			(hide yes)
			(effects
				(font
					(size 1 1)
					(thickness 0.15)
				)
			)
		)
		(property "MPN" "CR0402-FX-3300GLF"
			(at -100.917342 264.938858 0)
			(layer "F.Fab")
			(hide yes)
			(effects
				(font
					(size 1 1)
					(thickness 0.15)
				)
			)
		)
		(property "Manufacturer" "Bourns"
			(at -100.917342 264.938858 0)
			(layer "F.Fab")
			(hide yes)
			(effects
				(font
					(size 1 1)
					(thickness 0.15)
				)
			)
		)
		(property "Tolerance" "1%"
			(at -100.917342 264.938858 0)
			(layer "F.Fab")
			(hide yes)
			(effects
				(font
					(size 1 1)
					(thickness 0.15)
				)
			)
		)
		(property "Val" "330R"
			(at -100.917342 264.938858 0)
			(layer "F.Fab")
			(hide yes)
			(effects
				(font
					(size 1 1)
					(thickness 0.15)
				)
			)
		)
		(sheetname "/HDMI + SD Card/")
		(sheetfile "hdmi-sd-card.kicad_sch")
		(attr smd)
		(fp_rect
			(start -0.93 -0.47)
			(end 0.93 0.47)
			(stroke
				(width 0.05)
				(type solid)
			)
			(fill no)
			(layer "F.CrtYd")
		)
		(fp_rect
			(start -0.5 -0.25)
			(end 0.5 0.25)
			(stroke
				(width 0.15)
				(type solid)
			)
			(fill no)
			(layer "F.Fab")
		)
		(pad "1" smd roundrect
			(at -0.485 0 270)
			(size 0.59 0.64)
			(layers "F.Cu" "F.Mask" "F.Paste")
			(roundrect_rratio 0.25)
			(net 1 "GND")
			(pintype "passive")
		)
		(pad "2" smd roundrect
			(at 0.485 0 270)
			(size 0.59 0.64)
			(layers "F.Cu" "F.Mask" "F.Paste")
			(roundrect_rratio 0.25)
			(net 251 "Net-(C132-Pad1)")
			(pintype "passive")
		)
	)
	(footprint "antmicro-footprints:R_0402_1005Metric"
		(layer "F.Cu")
		(at 97.700501 126.735461 -90)
		(descr "Resistor SMD 0402")
		(tags "resistor SMD 0402")
		(property "Reference" "R11"
			(at -1.122484 -0.772697 270)
			(layer "F.SilkS")
			(hide yes)
			(effects
				(font
					(size 0.7 0.7)
					(thickness 0.15)
				)
				(justify left bottom)
			)
		)
		(property "Value" "R_330R_0402"
			(at -1.011843 1.772047 270)
			(layer "F.Fab")
			(effects
				(font
					(size 0.7 0.7)
					(thickness 0.15)
				)
				(justify left bottom)
			)
		)
		(property "Datasheet" "https://www.bourns.com/docs/product-datasheets/cr.pdf"
			(at 0 0 270)
			(layer "F.Fab")
			(hide yes)
			(effects
				(font
					(size 1.27 1.27)
					(thickness 0.15)
				)
			)
		)
		(property "Author" "Antmicro"
			(at -29.03496 224.435962 0)
			(layer "F.Fab")
			(hide yes)
			(effects
				(font
					(size 1 1)
					(thickness 0.15)
				)
			)
		)
		(property "License" "Apache-2.0"
			(at -29.03496 224.435962 0)
			(layer "F.Fab")
			(hide yes)
			(effects
				(font
					(size 1 1)
					(thickness 0.15)
				)
			)
		)
		(property "MPN" "CR0402-FX-3300GLF"
			(at -29.03496 224.435962 0)
			(layer "F.Fab")
			(hide yes)
			(effects
				(font
					(size 1 1)
					(thickness 0.15)
				)
			)
		)
		(property "Manufacturer" "Bourns"
			(at -29.03496 224.435962 0)
			(layer "F.Fab")
			(hide yes)
			(effects
				(font
					(size 1 1)
					(thickness 0.15)
				)
			)
		)
		(property "Tolerance" "1%"
			(at -29.03496 224.435962 0)
			(layer "F.Fab")
			(hide yes)
			(effects
				(font
					(size 1 1)
					(thickness 0.15)
				)
			)
		)
		(property "Val" "330R"
			(at -29.03496 224.435962 0)
			(layer "F.Fab")
			(hide yes)
			(effects
				(font
					(size 1 1)
					(thickness 0.15)
				)
			)
		)
		(sheetname "/FPGA Config/")
		(sheetfile "fpga-config.kicad_sch")
		(attr smd)
		(fp_rect
			(start -0.93 -0.47)
			(end 0.93 0.47)
			(stroke
				(width 0.05)
				(type solid)
			)
			(fill no)
			(layer "F.CrtYd")
		)
		(fp_rect
			(start -0.5 -0.25)
			(end 0.5 0.25)
			(stroke
				(width 0.15)
				(type solid)
			)
			(fill no)
			(layer "F.Fab")
		)
		(pad "1" smd roundrect
			(at -0.485 0 270)
			(size 0.59 0.64)
			(layers "F.Cu" "F.Mask" "F.Paste")
			(roundrect_rratio 0.25)
			(net 304 "Net-(D1-Pad2)")
			(pintype "passive")
		)
		(pad "2" smd roundrect
			(at 0.485 0 270)
			(size 0.59 0.64)
			(layers "F.Cu" "F.Mask" "F.Paste")
			(roundrect_rratio 0.25)
			(net 347 "Net-(Q1-D)")
			(pintype "passive")
		)
	)
	(footprint "antmicro-footprints:C_0603_1608Metric"
		(layer "F.Cu")
		(at 121.8 200.05 180)
		(descr "Capacitor SMD 0603")
		(tags "capacitor 0603")
		(property "Reference" "C180"
			(at -1.42757 -1.000252 180)
			(layer "F.SilkS")
			(hide yes)
			(effects
				(font
					(size 0.7 0.7)
					(thickness 0.15)
				)
				(justify left bottom)
			)
		)
		(property "Value" "C_1u_25V_0603"
			(at -1.42757 1.770288 180)
			(layer "F.Fab")
			(effects
				(font
					(size 0.7 0.7)
					(thickness 0.15)
				)
				(justify left bottom)
			)
		)
		(property "Datasheet" "https://product.samsungsem.com/mlcc/CL10A105KA8NNN.do"
			(at 0 0 180)
			(layer "F.Fab")
			(hide yes)
			(effects
				(font
					(size 1.27 1.27)
					(thickness 0.15)
				)
			)
		)
		(property "Author" "Antmicro"
			(at 243.6 400.1 0)
			(layer "F.Fab")
			(hide yes)
			(effects
				(font
					(size 1 1)
					(thickness 0.15)
				)
			)
		)
		(property "Dielectric" ""
			(at 243.6 400.1 0)
			(layer "F.Fab")
			(hide yes)
			(effects
				(font
					(size 1 1)
					(thickness 0.15)
				)
			)
		)
		(property "License" "Apache-2.0"
			(at 243.6 400.1 0)
			(layer "F.Fab")
			(hide yes)
			(effects
				(font
					(size 1 1)
					(thickness 0.15)
				)
			)
		)
		(property "MPN" "CL10A105KA8NNNC"
			(at 243.6 400.1 0)
			(layer "F.Fab")
			(hide yes)
			(effects
				(font
					(size 1 1)
					(thickness 0.15)
				)
			)
		)
		(property "Manufacturer" "Samsung Electro-Mechanics"
			(at 243.6 400.1 0)
			(layer "F.Fab")
			(hide yes)
			(effects
				(font
					(size 1 1)
					(thickness 0.15)
				)
			)
		)
		(property "Val" "1u/25V"
			(at 243.6 400.1 0)
			(layer "F.Fab")
			(hide yes)
			(effects
				(font
					(size 1 1)
					(thickness 0.15)
				)
			)
		)
		(property "Voltage" ""
			(at 243.6 400.1 0)
			(layer "F.Fab")
			(hide yes)
			(effects
				(font
					(size 1 1)
					(thickness 0.15)
				)
			)
		)
		(sheetname "/Supply/")
		(sheetfile "supply.kicad_sch")
		(attr smd)
		(fp_line
			(start -0.3 0.3)
			(end 0.3 0.3)
			(stroke
				(width 0.15)
				(type solid)
			)
			(layer "F.SilkS")
		)
		(fp_line
			(start -0.3 -0.3)
			(end 0.3 -0.3)
			(stroke
				(width 0.15)
				(type solid)
			)
			(layer "F.SilkS")
		)
		(fp_rect
			(start -1.24 -0.7)
			(end 1.24 0.7)
			(stroke
				(width 0.05)
				(type solid)
			)
			(fill no)
			(layer "F.CrtYd")
		)
		(fp_rect
			(start -0.8 -0.4)
			(end 0.8 0.4)
			(stroke
				(width 0.15)
				(type solid)
			)
			(fill no)
			(layer "F.Fab")
		)
		(pad "1" smd roundrect
			(at -0.7 0 180)
			(size 0.6 0.8)
			(layers "F.Cu" "F.Mask" "F.Paste")
			(roundrect_rratio 0.2)
			(net 1 "GND")
			(pintype "passive")
		)
		(pad "2" smd roundrect
			(at 0.7 0 180)
			(size 0.6 0.8)
			(layers "F.Cu" "F.Mask" "F.Paste")
			(roundrect_rratio 0.2)
			(net 38 "VDC")
			(pintype "passive")
		)
	)
	(footprint "antmicro-footprints:TP_SMD_1mm"
		(layer "F.Cu")
		(at 186.4 173.5)
		(property "Reference" "TP9"
			(at 0 -0.731898 0)
			(layer "F.SilkS")
			(hide yes)
			(effects
				(font
					(size 0.7 0.7)
					(thickness 0.15)
				)
				(justify left bottom)
			)
		)
		(property "Value" "TP_1mm_SMD"
			(at 0 1.4 0)
			(layer "F.Fab")
			(effects
				(font
					(size 0.7 0.7)
					(thickness 0.15)
				)
				(justify left bottom)
			)
		)
		(property "Author" "Antmicro"
			(at 0 0 0)
			(layer "F.Fab")
			(hide yes)
			(effects
				(font
					(size 1 1)
					(thickness 0.15)
				)
			)
		)
		(property "License" "Apache-2.0"
			(at 0 0 0)
			(layer "F.Fab")
			(hide yes)
			(effects
				(font
					(size 1 1)
					(thickness 0.15)
				)
			)
		)
		(property "MPN" ""
			(at 0 0 0)
			(layer "F.Fab")
			(hide yes)
			(effects
				(font
					(size 1 1)
					(thickness 0.15)
				)
			)
		)
		(property "Manufacturer" ""
			(at 0 0 0)
			(layer "F.Fab")
			(hide yes)
			(effects
				(font
					(size 1 1)
					(thickness 0.15)
				)
			)
		)
		(sheetname "/Supply/")
		(sheetfile "supply.kicad_sch")
		(attr exclude_from_pos_files)
		(pad "1" smd circle
			(at 0 0)
			(size 1 1)
			(layers "F.Cu" "F.Mask")
			(net 199 "+1V2")
			(pinfunction "1")
			(pintype "passive")
		)
	)
	(footprint "antmicro-footprints:R_0402_1005Metric"
		(layer "F.Cu")
		(at 103.05 184.785 90)
		(descr "Resistor SMD 0402")
		(tags "resistor SMD 0402")
		(property "Reference" "R93"
			(at -1.122484 -0.772697 90)
			(layer "F.SilkS")
			(hide yes)
			(effects
				(font
					(size 0.7 0.7)
					(thickness 0.15)
				)
				(justify left bottom)
			)
		)
		(property "Value" "R_0R_0402"
			(at -1.011843 1.772047 90)
			(layer "F.Fab")
			(effects
				(font
					(size 0.7 0.7)
					(thickness 0.15)
				)
				(justify left bottom)
			)
		)
		(property "Datasheet" "https://industrial.panasonic.com/cdbs/www-data/pdf/RDA0000/AOA0000C301.pdf"
			(at 0 0 90)
			(layer "F.Fab")
			(hide yes)
			(effects
				(font
					(size 1.27 1.27)
					(thickness 0.15)
				)
			)
		)
		(property "Author" "Antmicro"
			(at 287.835 81.735 0)
			(layer "F.Fab")
			(hide yes)
			(effects
				(font
					(size 1 1)
					(thickness 0.15)
				)
			)
		)
		(property "Current" "1A"
			(at 287.835 81.735 0)
			(layer "F.Fab")
			(hide yes)
			(effects
				(font
					(size 1 1)
					(thickness 0.15)
				)
			)
		)
		(property "License" "Apache-2.0"
			(at 287.835 81.735 0)
			(layer "F.Fab")
			(hide yes)
			(effects
				(font
					(size 1 1)
					(thickness 0.15)
				)
			)
		)
		(property "MPN" "ERJ2GE0R00X"
			(at 287.835 81.735 0)
			(layer "F.Fab")
			(hide yes)
			(effects
				(font
					(size 1 1)
					(thickness 0.15)
				)
			)
		)
		(property "Manufacturer" "Panasonic"
			(at 287.835 81.735 0)
			(layer "F.Fab")
			(hide yes)
			(effects
				(font
					(size 1 1)
					(thickness 0.15)
				)
			)
		)
		(property "Tolerance" ""
			(at 287.835 81.735 0)
			(layer "F.Fab")
			(hide yes)
			(effects
				(font
					(size 1 1)
					(thickness 0.15)
				)
			)
		)
		(property "Val" "0R"
			(at 287.835 81.735 0)
			(layer "F.Fab")
			(hide yes)
			(effects
				(font
					(size 1 1)
					(thickness 0.15)
				)
			)
		)
		(sheetname "/Debug FTDI/")
		(sheetfile "debug-ftdi.kicad_sch")
		(attr smd)
		(fp_rect
			(start -0.93 -0.47)
			(end 0.93 0.47)
			(stroke
				(width 0.05)
				(type solid)
			)
			(fill no)
			(layer "F.CrtYd")
		)
		(fp_rect
			(start -0.5 -0.25)
			(end 0.5 0.25)
			(stroke
				(width 0.15)
				(type solid)
			)
			(fill no)
			(layer "F.Fab")
		)
		(pad "1" smd roundrect
			(at -0.485 0 90)
			(size 0.59 0.64)
			(layers "F.Cu" "F.Mask" "F.Paste")
			(roundrect_rratio 0.25)
			(net 672 "/Debug FTDI/FTDI.SDA")
			(pintype "passive")
		)
		(pad "2" smd roundrect
			(at 0.485 0 90)
			(size 0.59 0.64)
			(layers "F.Cu" "F.Mask" "F.Paste")
			(roundrect_rratio 0.25)
			(net 43 "/Debug FTDI/FTDI_SDA_IN")
			(pintype "passive")
		)
	)
	(footprint "antmicro-footprints:TP_SMD_1mm"
		(layer "F.Cu")
		(at 186.4 182.1)
		(property "Reference" "TP15"
			(at 0 -0.731898 0)
			(layer "F.SilkS")
			(hide yes)
			(effects
				(font
					(size 0.7 0.7)
					(thickness 0.15)
				)
				(justify left bottom)
			)
		)
		(property "Value" "TP_1mm_SMD"
			(at 0 1.4 0)
			(layer "F.Fab")
			(effects
				(font
					(size 0.7 0.7)
					(thickness 0.15)
				)
				(justify left bottom)
			)
		)
		(property "Author" "Antmicro"
			(at 0 0 0)
			(layer "F.Fab")
			(hide yes)
			(effects
				(font
					(size 1 1)
					(thickness 0.15)
				)
			)
		)
		(property "License" "Apache-2.0"
			(at 0 0 0)
			(layer "F.Fab")
			(hide yes)
			(effects
				(font
					(size 1 1)
					(thickness 0.15)
				)
			)
		)
		(property "MPN" ""
			(at 0 0 0)
			(layer "F.Fab")
			(hide yes)
			(effects
				(font
					(size 1 1)
					(thickness 0.15)
				)
			)
		)
		(property "Manufacturer" ""
			(at 0 0 0)
			(layer "F.Fab")
			(hide yes)
			(effects
				(font
					(size 1 1)
					(thickness 0.15)
				)
			)
		)
		(sheetname "/Supply/")
		(sheetfile "supply.kicad_sch")
		(attr exclude_from_pos_files)
		(pad "1" smd circle
			(at 0 0)
			(size 1 1)
			(layers "F.Cu" "F.Mask")
			(net 188 "+1V8")
			(pinfunction "1")
			(pintype "passive")
		)
	)
	(footprint "antmicro-footprints:SW_DIP_SPSTx02_Slide_Copal_CVS-02xB_W5.9mm_P1mm"
		(layer "F.Cu")
		(at 118.3 193.2)
		(descr "SMD 2x-dip-switch SPST Copal_CVS-02xB, Slide, row spacing 5.9 mm")
		(tags "SMD DIP Switch SPST Slide 5.9mm")
		(property "Reference" "SW6"
			(at 1.8 3.3 0)
			(layer "F.SilkS")
			(effects
				(font
					(size 0.7 0.7)
					(thickness 0.15)
				)
				(justify left bottom)
			)
		)
		(property "Value" "SW_CVS-02B"
			(at 0 2.91 0)
			(layer "F.Fab")
			(effects
				(font
					(size 0.7 0.7)
					(thickness 0.15)
				)
				(justify left bottom)
			)
		)
		(property "Datasheet" "https://www.mouser.com/datasheet/2/972/cvs-1827291.pdf"
			(at 0 0 0)
			(layer "F.Fab")
			(hide yes)
			(effects
				(font
					(size 1.27 1.27)
					(thickness 0.15)
				)
			)
		)
		(property "Author" "Antmicro"
			(at 0 0 0)
			(layer "F.Fab")
			(hide yes)
			(effects
				(font
					(size 1 1)
					(thickness 0.15)
				)
			)
		)
		(property "License" "Apache-2.0"
			(at 0 0 0)
			(layer "F.Fab")
			(hide yes)
			(effects
				(font
					(size 1 1)
					(thickness 0.15)
				)
			)
		)
		(property "MPN" "CVS-02B"
			(at 0 0 0)
			(layer "F.Fab")
			(hide yes)
			(effects
				(font
					(size 1 1)
					(thickness 0.15)
				)
			)
		)
		(property "Manufacturer" "Nidec Components"
			(at 0 0 0)
			(layer "F.Fab")
			(hide yes)
			(effects
				(font
					(size 1 1)
					(thickness 0.15)
				)
			)
		)
		(property ki_fp_filters "SW?DIP?x2*")
		(sheetname "/PCIe connector/")
		(sheetfile "pcie-connector.kicad_sch")
		(attr smd)
		(fp_line
			(start -1.561 -1.911)
			(end 1.56 -1.911)
			(stroke
				(width 0.15)
				(type solid)
			)
			(layer "F.SilkS")
		)
		(fp_line
			(start -1.561 1.908)
			(end 1.56 1.908)
			(stroke
				(width 0.15)
				(type solid)
			)
			(layer "F.SilkS")
		)
		(fp_circle
			(center -3.4 -1.1)
			(end -3.35 -1.06)
			(stroke
				(width 0.15)
				(type solid)
			)
			(fill yes)
			(layer "F.SilkS")
		)
		(fp_rect
			(start -3.6 -2)
			(end 3.6 2)
			(stroke
				(width 0.05)
				(type solid)
			)
			(fill no)
			(layer "F.CrtYd")
		)
		(fp_line
			(start -2.351 -0.5)
			(end -1.351 -1.5)
			(stroke
				(width 0.15)
				(type solid)
			)
			(layer "F.Fab")
		)
		(fp_line
			(start -1 -0.75)
			(end -1 -0.25)
			(stroke
				(width 0.15)
				(type solid)
			)
			(layer "F.Fab")
		)
		(fp_line
			(start -1 -0.652)
			(end -0.335 -0.652)
			(stroke
				(width 0.15)
				(type solid)
			)
			(layer "F.Fab")
		)
		(fp_line
			(start -1 -0.552)
			(end -0.335 -0.552)
			(stroke
				(width 0.15)
				(type solid)
			)
			(layer "F.Fab")
		)
		(fp_line
			(start -1 -0.452)
			(end -0.335 -0.452)
			(stroke
				(width 0.15)
				(type solid)
			)
			(layer "F.Fab")
		)
		(fp_line
			(start -1 -0.351)
			(end -0.335 -0.351)
			(stroke
				(width 0.15)
				(type solid)
			)
			(layer "F.Fab")
		)
		(fp_line
			(start -1 -0.25)
			(end 0.998 -0.25)
			(stroke
				(width 0.15)
				(type solid)
			)
			(layer "F.Fab")
		)
		(fp_line
			(start -1 0.248)
			(end -1 0.748)
			(stroke
				(width 0.15)
				(type solid)
			)
			(layer "F.Fab")
		)
		(fp_line
			(start -1 0.349)
			(end -0.335 0.349)
			(stroke
				(width 0.15)
				(type solid)
			)
			(layer "F.Fab")
		)
		(fp_line
			(start -1 0.45)
			(end -0.335 0.45)
			(stroke
				(width 0.15)
				(type solid)
			)
			(layer "F.Fab")
		)
		(fp_line
			(start -1 0.55)
			(end -0.335 0.55)
			(stroke
				(width 0.15)
				(type solid)
			)
			(layer "F.Fab")
		)
		(fp_line
			(start -1 0.65)
			(end -0.335 0.65)
			(stroke
				(width 0.15)
				(type solid)
			)
			(layer "F.Fab")
		)
		(fp_line
			(start -1 0.748)
			(end 0.998 0.748)
			(stroke
				(width 0.15)
				(type solid)
			)
			(layer "F.Fab")
		)
		(fp_line
			(start -0.335 -0.75)
			(end -0.335 -0.25)
			(stroke
				(width 0.15)
				(type solid)
			)
			(layer "F.Fab")
		)
		(fp_line
			(start -0.335 0.248)
			(end -0.335 0.748)
			(stroke
				(width 0.15)
				(type solid)
			)
			(layer "F.Fab")
		)
		(fp_line
			(start 0.998 -0.75)
			(end -1 -0.75)
			(stroke
				(width 0.15)
				(type solid)
			)
			(layer "F.Fab")
		)
		(fp_line
			(start 0.998 -0.25)
			(end 0.998 -0.75)
			(stroke
				(width 0.15)
				(type solid)
			)
			(layer "F.Fab")
		)
		(fp_line
			(start 0.998 0.248)
			(end -1 0.248)
			(stroke
				(width 0.15)
				(type solid)
			)
			(layer "F.Fab")
		)
		(fp_line
			(start 0.998 0.748)
			(end 0.998 0.248)
			(stroke
				(width 0.15)
				(type solid)
			)
			(layer "F.Fab")
		)
		(fp_rect
			(start 2.35 1.499)
			(end -2.351 -1.5)
			(stroke
				(width 0.15)
				(type solid)
			)
			(fill no)
			(layer "F.Fab")
		)
		(fp_text user "on"
			(at -1.5 0.739 90)
			(layer "F.Fab")
			(effects
				(font
					(size 0.7 0.7)
					(thickness 0.15)
				)
				(justify left bottom)
			)
		)
		(pad "1" smd rect
			(at -2.95 -0.5)
			(size 1.2 0.5)
			(layers "F.Cu" "F.Mask" "F.Paste")
			(net 229 "/PCIe connector/PRSNT#1")
			(pintype "passive")
		)
		(pad "2" smd rect
			(at -2.95 0.5)
			(size 1.2 0.5)
			(layers "F.Cu" "F.Mask" "F.Paste")
			(net 229 "/PCIe connector/PRSNT#1")
			(pintype "passive")
		)
		(pad "3" smd rect
			(at 2.95 0.5)
			(size 1.2 0.5)
			(layers "F.Cu" "F.Mask" "F.Paste")
			(net 231 "/PCIe connector/x4")
			(pintype "passive")
		)
		(pad "4" smd rect
			(at 2.95 -0.5)
			(size 1.2 0.5)
			(layers "F.Cu" "F.Mask" "F.Paste")
			(net 230 "/PCIe connector/x1")
			(pintype "passive")
		)
		(pad "SH" smd rect
			(at -2.15 -1.5)
			(size 0.7 0.7)
			(layers "F.Cu" "F.Mask" "F.Paste")
			(net 1 "GND")
			(pinfunction "SH")
			(pintype "power_in")
		)
		(pad "SH" smd rect
			(at -2.15 1.5)
			(size 0.7 0.7)
			(layers "F.Cu" "F.Mask" "F.Paste")
			(net 1 "GND")
			(pinfunction "SH")
			(pintype "power_in")
		)
		(pad "SH" smd rect
			(at 2.15 -1.5)
			(size 0.7 0.7)
			(layers "F.Cu" "F.Mask" "F.Paste")
			(net 1 "GND")
			(pinfunction "SH")
			(pintype "power_in")
		)
		(pad "SH" smd rect
			(at 2.15 1.5)
			(size 0.7 0.7)
			(layers "F.Cu" "F.Mask" "F.Paste")
			(net 1 "GND")
			(pinfunction "SH")
			(pintype "power_in")
		)
	)
	(footprint "antmicro-footprints:NetTie-2_SMD_Pad0.127mm"
		(layer "F.Cu")
		(at 198.226501 159.7 180)
		(descr "Net tie, 2 pin, 0.127mm  SMD pads")
		(tags "net tie")
		(property "Reference" "NT15"
			(at -0.128 -1.345 180)
			(layer "F.SilkS")
			(hide yes)
			(effects
				(font
					(size 0.7 0.7)
					(thickness 0.15)
				)
				(justify left bottom)
			)
		)
		(property "Value" "Net-Tie_P0.127mm"
			(at 0 1.199 180)
			(layer "F.Fab")
			(effects
				(font
					(size 0.7 0.7)
					(thickness 0.15)
				)
				(justify left bottom)
			)
		)
		(property "Author" "Antmicro"
			(at 396.453002 319.4 0)
			(layer "F.Fab")
			(hide yes)
			(effects
				(font
					(size 1 1)
					(thickness 0.15)
				)
			)
		)
		(property "License" "Apache-2.0"
			(at 396.453002 319.4 0)
			(layer "F.Fab")
			(hide yes)
			(effects
				(font
					(size 1 1)
					(thickness 0.15)
				)
			)
		)
		(property "MPN" ""
			(at 396.453002 319.4 0)
			(layer "F.Fab")
			(hide yes)
			(effects
				(font
					(size 1 1)
					(thickness 0.15)
				)
			)
		)
		(property "Manufacturer" ""
			(at 396.453002 319.4 0)
			(layer "F.Fab")
			(hide yes)
			(effects
				(font
					(size 1 1)
					(thickness 0.15)
				)
			)
		)
		(property ki_fp_filters "Net*Tie*")
		(sheetname "/Supply/")
		(sheetfile "supply.kicad_sch")
		(attr smd exclude_from_pos_files exclude_from_bom)
		(net_tie_pad_groups "1, 2")
		(fp_poly
			(pts
				(xy -0.0635 -0.0635) (xy 0.0625 -0.0635) (xy 0.0625 0.0635) (xy -0.0635 0.0635)
			)
			(stroke
				(width 0)
				(type solid)
			)
			(fill yes)
			(layer "F.Cu")
		)
		(pad "1" smd roundrect
			(at -0.127 0)
			(size 0.127 0.127)
			(layers "F.Cu")
			(roundrect_rratio 0.5)
			(chamfer_ratio 0)
			(chamfer top_left bottom_left)
			(net 175 "/Supply/1V1_SEN_-")
			(pinfunction "1")
			(pintype "passive")
		)
		(pad "2" smd roundrect
			(at 0.126 0 180)
			(size 0.127 0.127)
			(layers "F.Cu")
			(roundrect_rratio 0.5)
			(chamfer_ratio 0)
			(chamfer top_left bottom_left)
			(net 206 "+1V1")
			(pinfunction "2")
			(pintype "passive")
		)
	)
	(footprint "antmicro-footprints:C_0402_1005Metric"
		(layer "F.Cu")
		(at 199.203499 135.48 90)
		(descr "Capacitor SMD 0402")
		(tags "capacitor SMD 0402")
		(property "Reference" "C194"
			(at 0 -0.699 90)
			(layer "F.SilkS")
			(hide yes)
			(effects
				(font
					(size 0.7 0.7)
					(thickness 0.15)
				)
				(justify left bottom)
			)
		)
		(property "Value" "C_1u_0402"
			(at -1.022927 2.155213 90)
			(layer "F.Fab")
			(effects
				(font
					(size 0.7 0.7)
					(thickness 0.15)
				)
				(justify left bottom)
			)
		)
		(property "Datasheet" "https://product.tdk.com/en/search/capacitor/ceramic/mlcc/info?part_no=C1005X6S1A105K050BC"
			(at 0 0 90)
			(layer "F.Fab")
			(hide yes)
			(effects
				(font
					(size 1.27 1.27)
					(thickness 0.15)
				)
			)
		)
		(property "Author" "Antmicro"
			(at 334.683499 -63.723499 0)
			(layer "F.Fab")
			(hide yes)
			(effects
				(font
					(size 1 1)
					(thickness 0.15)
				)
			)
		)
		(property "Dielectric" ""
			(at 334.683499 -63.723499 0)
			(layer "F.Fab")
			(hide yes)
			(effects
				(font
					(size 1 1)
					(thickness 0.15)
				)
			)
		)
		(property "License" "Apache-2.0"
			(at 334.683499 -63.723499 0)
			(layer "F.Fab")
			(hide yes)
			(effects
				(font
					(size 1 1)
					(thickness 0.15)
				)
			)
		)
		(property "MPN" "C1005X6S1A105K050BC"
			(at 334.683499 -63.723499 0)
			(layer "F.Fab")
			(hide yes)
			(effects
				(font
					(size 1 1)
					(thickness 0.15)
				)
			)
		)
		(property "Manufacturer" "TDK"
			(at 334.683499 -63.723499 0)
			(layer "F.Fab")
			(hide yes)
			(effects
				(font
					(size 1 1)
					(thickness 0.15)
				)
			)
		)
		(property "Val" "1u"
			(at 334.683499 -63.723499 0)
			(layer "F.Fab")
			(hide yes)
			(effects
				(font
					(size 1 1)
					(thickness 0.15)
				)
			)
		)
		(property "Voltage" ""
			(at 334.683499 -63.723499 0)
			(layer "F.Fab")
			(hide yes)
			(effects
				(font
					(size 1 1)
					(thickness 0.15)
				)
			)
		)
		(sheetname "/Supply/")
		(sheetfile "supply.kicad_sch")
		(attr smd)
		(fp_rect
			(start -0.9659 -0.481258)
			(end 0.9649 0.458742)
			(stroke
				(width 0.05)
				(type solid)
			)
			(fill no)
			(layer "F.CrtYd")
		)
		(fp_line
			(start 0.499 -0.25)
			(end 0.499 0.248)
			(stroke
				(width 0.15)
				(type solid)
			)
			(layer "F.Fab")
		)
		(fp_line
			(start -0.499 -0.25)
			(end 0.499 -0.25)
			(stroke
				(width 0.15)
				(type solid)
			)
			(layer "F.Fab")
		)
		(fp_line
			(start 0.499 0.248)
			(end -0.499 0.248)
			(stroke
				(width 0.15)
				(type solid)
			)
			(layer "F.Fab")
		)
		(fp_line
			(start -0.499 0.248)
			(end -0.499 -0.25)
			(stroke
				(width 0.15)
				(type solid)
			)
			(layer "F.Fab")
		)
		(pad "1" smd roundrect
			(at -0.484 0 90)
			(size 0.59 0.64)
			(layers "F.Cu" "F.Mask" "F.Paste")
			(roundrect_rratio 0.25)
			(net 1 "GND")
			(pintype "passive")
		)
		(pad "2" smd roundrect
			(at 0.484 0 90)
			(size 0.59 0.64)
			(layers "F.Cu" "F.Mask" "F.Paste")
			(roundrect_rratio 0.25)
			(net 41 "+3V3_AON")
			(pintype "passive")
		)
	)
	(footprint "antmicro-footprints:R_0402_1005Metric"
		(layer "F.Cu")
		(at 185 164.951 -90)
		(descr "Resistor SMD 0402")
		(tags "resistor SMD 0402")
		(property "Reference" "R182"
			(at -1.122484 -0.772697 270)
			(layer "F.SilkS")
			(hide yes)
			(effects
				(font
					(size 0.7 0.7)
					(thickness 0.15)
				)
				(justify left bottom)
			)
		)
		(property "Value" "R_10k_0402"
			(at -1.011843 1.772047 270)
			(layer "F.Fab")
			(effects
				(font
					(size 0.7 0.7)
					(thickness 0.15)
				)
				(justify left bottom)
			)
		)
		(property "Datasheet" "https://www.bourns.com/docs/product-datasheets/cr.pdf"
			(at 0 0 270)
			(layer "F.Fab")
			(hide yes)
			(effects
				(font
					(size 1.27 1.27)
					(thickness 0.15)
				)
			)
		)
		(property "Author" "Antmicro"
			(at 20.049 349.951 0)
			(layer "F.Fab")
			(hide yes)
			(effects
				(font
					(size 1 1)
					(thickness 0.15)
				)
			)
		)
		(property "License" "Apache-2.0"
			(at 20.049 349.951 0)
			(layer "F.Fab")
			(hide yes)
			(effects
				(font
					(size 1 1)
					(thickness 0.15)
				)
			)
		)
		(property "MPN" "CR0402-FX-1002GLF"
			(at 20.049 349.951 0)
			(layer "F.Fab")
			(hide yes)
			(effects
				(font
					(size 1 1)
					(thickness 0.15)
				)
			)
		)
		(property "Manufacturer" "Bourns"
			(at 20.049 349.951 0)
			(layer "F.Fab")
			(hide yes)
			(effects
				(font
					(size 1 1)
					(thickness 0.15)
				)
			)
		)
		(property "Tolerance" "1%"
			(at 20.049 349.951 0)
			(layer "F.Fab")
			(hide yes)
			(effects
				(font
					(size 1 1)
					(thickness 0.15)
				)
			)
		)
		(property "Val" "10k"
			(at 20.049 349.951 0)
			(layer "F.Fab")
			(hide yes)
			(effects
				(font
					(size 1 1)
					(thickness 0.15)
				)
			)
		)
		(sheetname "/Supply/")
		(sheetfile "supply.kicad_sch")
		(attr smd)
		(fp_rect
			(start -0.93 -0.47)
			(end 0.93 0.47)
			(stroke
				(width 0.05)
				(type solid)
			)
			(fill no)
			(layer "F.CrtYd")
		)
		(fp_rect
			(start -0.5 -0.25)
			(end 0.5 0.25)
			(stroke
				(width 0.15)
				(type solid)
			)
			(fill no)
			(layer "F.Fab")
		)
		(pad "1" smd roundrect
			(at -0.485 0 270)
			(size 0.59 0.64)
			(layers "F.Cu" "F.Mask" "F.Paste")
			(roundrect_rratio 0.25)
			(net 200 "+3V3")
			(pintype "passive")
		)
		(pad "2" smd roundrect
			(at 0.485 0 270)
			(size 0.59 0.64)
			(layers "F.Cu" "F.Mask" "F.Paste")
			(roundrect_rratio 0.25)
			(net 386 "Net-(U30-~{PWRDN})")
			(pintype "passive")
		)
	)
	(footprint "antmicro-footprints:LED_0603_1608Metric_G"
		(layer "F.Cu")
		(at 94.450501 116.426 -90)
		(descr "LED SMD 0603 Green")
		(tags "LED SMD 0603 Green")
		(property "Reference" "D8"
			(at -0.001 -0.901 270)
			(layer "F.SilkS")
			(hide yes)
			(effects
				(font
					(size 0.7 0.7)
					(thickness 0.15)
				)
				(justify left bottom)
			)
		)
		(property "Value" "LED_G_0603_KP-1608CGCK"
			(at -0.001 1.599 270)
			(layer "F.Fab")
			(effects
				(font
					(size 0.7 0.7)
					(thickness 0.15)
				)
				(justify left bottom)
			)
		)
		(property "Datasheet" "http://www.farnell.com/datasheets/2045956.pdf"
			(at 0 0 270)
			(layer "F.Fab")
			(hide yes)
			(effects
				(font
					(size 1.27 1.27)
					(thickness 0.15)
				)
			)
		)
		(property "Author" "Antmicro"
			(at -21.975499 210.876501 0)
			(layer "F.Fab")
			(hide yes)
			(effects
				(font
					(size 1 1)
					(thickness 0.15)
				)
			)
		)
		(property "License" "Apache-2.0"
			(at -21.975499 210.876501 0)
			(layer "F.Fab")
			(hide yes)
			(effects
				(font
					(size 1 1)
					(thickness 0.15)
				)
			)
		)
		(property "MPN" "KP-1608CGCK"
			(at -21.975499 210.876501 0)
			(layer "F.Fab")
			(hide yes)
			(effects
				(font
					(size 1 1)
					(thickness 0.15)
				)
			)
		)
		(property "Manufacturer" "Kingbright"
			(at -21.975499 210.876501 0)
			(layer "F.Fab")
			(hide yes)
			(effects
				(font
					(size 1 1)
					(thickness 0.15)
				)
			)
		)
		(sheetname "/FPGA bank 14/")
		(sheetfile "fpga-bank-14.kicad_sch")
		(attr smd)
		(fp_line
			(start -0.271 0.348)
			(end 0.269 0.348)
			(stroke
				(width 0.15)
				(type solid)
			)
			(layer "F.SilkS")
		)
		(fp_line
			(start 1.249 0.319)
			(end 1.249 -0.321)
			(stroke
				(width 0.15)
				(type solid)
			)
			(layer "F.SilkS")
		)
		(fp_line
			(start -0.107 -0.001)
			(end -0.291 -0.001)
			(stroke
				(width 0.1)
				(type solid)
			)
			(layer "F.SilkS")
		)
		(fp_line
			(start 0.092 -0.001)
			(end -0.107 0.198)
			(stroke
				(width 0.1)
				(type solid)
			)
			(layer "F.SilkS")
		)
		(fp_line
			(start 0.092 -0.001)
			(end 0.292 -0.001)
			(stroke
				(width 0.1)
				(type solid)
			)
			(layer "F.SilkS")
		)
		(fp_line
			(start -0.107 -0.201)
			(end -0.107 0.198)
			(stroke
				(width 0.1)
				(type solid)
			)
			(layer "F.SilkS")
		)
		(fp_line
			(start -0.107 -0.201)
			(end 0.092 -0.001)
			(stroke
				(width 0.1)
				(type solid)
			)
			(layer "F.SilkS")
		)
		(fp_line
			(start 0.092 -0.201)
			(end 0.092 0.198)
			(stroke
				(width 0.1)
				(type solid)
			)
			(layer "F.SilkS")
		)
		(fp_line
			(start -0.271 -0.349)
			(end 0.269 -0.349)
			(stroke
				(width 0.15)
				(type solid)
			)
			(layer "F.SilkS")
		)
		(fp_rect
			(start -1.2192 -0.6096)
			(end 1.27 0.6016)
			(stroke
				(width 0.05)
				(type solid)
			)
			(fill no)
			(layer "F.CrtYd")
		)
		(fp_line
			(start -0.202 0.201)
			(end 0.1 -0.001)
			(stroke
				(width 0.15)
				(type solid)
			)
			(layer "F.Fab")
		)
		(fp_line
			(start 0.198 0.201)
			(end 0.198 -0.101)
			(stroke
				(width 0.15)
				(type solid)
			)
			(layer "F.Fab")
		)
		(fp_line
			(start -0.849 0.025)
			(end -0.442 0.381)
			(stroke
				(width 0.15)
				(type solid)
			)
			(layer "F.Fab")
		)
		(fp_line
			(start -0.6 -0.001)
			(end -0.202 -0.001)
			(stroke
				(width 0.15)
				(type solid)
			)
			(layer "F.Fab")
		)
		(fp_line
			(start -0.202 -0.001)
			(end -0.202 0.201)
			(stroke
				(width 0.15)
				(type solid)
			)
			(layer "F.Fab")
		)
		(fp_line
			(start 0.1 -0.001)
			(end -0.202 -0.201)
			(stroke
				(width 0.15)
				(type solid)
			)
			(layer "F.Fab")
		)
		(fp_line
			(start 0.198 -0.001)
			(end 0.596 -0.001)
			(stroke
				(width 0.15)
				(type solid)
			)
			(layer "F.Fab")
		)
		(fp_line
			(start -0.202 -0.201)
			(end -0.202 -0.001)
			(stroke
				(width 0.15)
				(type solid)
			)
			(layer "F.Fab")
		)
		(fp_line
			(start 0.198 -0.201)
			(end 0.198 -0.101)
			(stroke
				(width 0.15)
				(type solid)
			)
			(layer "F.Fab")
		)
		(fp_rect
			(start -0.849 -0.401)
			(end 0.849 0.401)
			(stroke
				(width 0.15)
				(type solid)
			)
			(fill no)
			(layer "F.Fab")
		)
		(pad "1" smd rect
			(at -0.751 -0.001 90)
			(size 0.8 0.8)
			(layers "F.Cu" "F.Mask" "F.Paste")
			(net 200 "+3V3")
			(pinfunction "1")
			(pintype "passive")
		)
		(pad "2" smd rect
			(at 0.749 -0.001 90)
			(size 0.8 0.8)
			(layers "F.Cu" "F.Mask" "F.Paste")
			(net 33 "Net-(D8-Pad2)")
			(pinfunction "2")
			(pintype "passive")
		)
	)
	(footprint "antmicro-footprints:R_0402_1005Metric"
		(layer "F.Cu")
		(at 77.2 160.115 90)
		(descr "Resistor SMD 0402")
		(tags "resistor SMD 0402")
		(property "Reference" "R90"
			(at -1.122484 -0.772697 90)
			(layer "F.SilkS")
			(hide yes)
			(effects
				(font
					(size 0.7 0.7)
					(thickness 0.15)
				)
				(justify left bottom)
			)
		)
		(property "Value" "R_330R_0402"
			(at -1.011843 1.772047 90)
			(layer "F.Fab")
			(effects
				(font
					(size 0.7 0.7)
					(thickness 0.15)
				)
				(justify left bottom)
			)
		)
		(property "Datasheet" "https://www.bourns.com/docs/product-datasheets/cr.pdf"
			(at 0 0 90)
			(layer "F.Fab")
			(hide yes)
			(effects
				(font
					(size 1.27 1.27)
					(thickness 0.15)
				)
			)
		)
		(property "Author" "Antmicro"
			(at 237.315 82.915 0)
			(layer "F.Fab")
			(hide yes)
			(effects
				(font
					(size 1 1)
					(thickness 0.15)
				)
			)
		)
		(property "License" "Apache-2.0"
			(at 237.315 82.915 0)
			(layer "F.Fab")
			(hide yes)
			(effects
				(font
					(size 1 1)
					(thickness 0.15)
				)
			)
		)
		(property "MPN" "CR0402-FX-3300GLF"
			(at 237.315 82.915 0)
			(layer "F.Fab")
			(hide yes)
			(effects
				(font
					(size 1 1)
					(thickness 0.15)
				)
			)
		)
		(property "Manufacturer" "Bourns"
			(at 237.315 82.915 0)
			(layer "F.Fab")
			(hide yes)
			(effects
				(font
					(size 1 1)
					(thickness 0.15)
				)
			)
		)
		(property "Tolerance" "1%"
			(at 237.315 82.915 0)
			(layer "F.Fab")
			(hide yes)
			(effects
				(font
					(size 1 1)
					(thickness 0.15)
				)
			)
		)
		(property "Val" "330R"
			(at 237.315 82.915 0)
			(layer "F.Fab")
			(hide yes)
			(effects
				(font
					(size 1 1)
					(thickness 0.15)
				)
			)
		)
		(sheetname "/Debug FTDI/")
		(sheetfile "debug-ftdi.kicad_sch")
		(attr smd)
		(fp_rect
			(start -0.93 -0.47)
			(end 0.93 0.47)
			(stroke
				(width 0.05)
				(type solid)
			)
			(fill no)
			(layer "F.CrtYd")
		)
		(fp_rect
			(start -0.5 -0.25)
			(end 0.5 0.25)
			(stroke
				(width 0.15)
				(type solid)
			)
			(fill no)
			(layer "F.Fab")
		)
		(pad "1" smd roundrect
			(at -0.485 0 90)
			(size 0.59 0.64)
			(layers "F.Cu" "F.Mask" "F.Paste")
			(roundrect_rratio 0.25)
			(net 1 "GND")
			(pintype "passive")
		)
		(pad "2" smd roundrect
			(at 0.485 0 90)
			(size 0.59 0.64)
			(layers "F.Cu" "F.Mask" "F.Paste")
			(roundrect_rratio 0.25)
			(net 593 "Net-(C133-Pad1)")
			(pintype "passive")
		)
	)
	(footprint "antmicro-footprints:C_0402_1005Metric"
		(layer "F.Cu")
		(at 107.251 182.718 90)
		(descr "Capacitor SMD 0402")
		(tags "capacitor SMD 0402")
		(property "Reference" "C131"
			(at 0 -0.699 90)
			(layer "F.SilkS")
			(hide yes)
			(effects
				(font
					(size 0.7 0.7)
					(thickness 0.15)
				)
				(justify left bottom)
			)
		)
		(property "Value" "C_100n_0402"
			(at -1.022927 2.155213 90)
			(layer "F.Fab")
			(effects
				(font
					(size 0.7 0.7)
					(thickness 0.15)
				)
				(justify left bottom)
			)
		)
		(property "Datasheet" "https://www.murata.com/products/productdetail?partno=GRM155R61H104KE14%23"
			(at 0 0 90)
			(layer "F.Fab")
			(hide yes)
			(effects
				(font
					(size 1.27 1.27)
					(thickness 0.15)
				)
			)
		)
		(property "Author" "Antmicro"
			(at 289.969 75.467 0)
			(layer "F.Fab")
			(hide yes)
			(effects
				(font
					(size 1 1)
					(thickness 0.15)
				)
			)
		)
		(property "Dielectric" "X5R"
			(at 289.969 75.467 0)
			(layer "F.Fab")
			(hide yes)
			(effects
				(font
					(size 1 1)
					(thickness 0.15)
				)
			)
		)
		(property "License" "Apache-2.0"
			(at 289.969 75.467 0)
			(layer "F.Fab")
			(hide yes)
			(effects
				(font
					(size 1 1)
					(thickness 0.15)
				)
			)
		)
		(property "MPN" "GRM155R61H104KE14D"
			(at 289.969 75.467 0)
			(layer "F.Fab")
			(hide yes)
			(effects
				(font
					(size 1 1)
					(thickness 0.15)
				)
			)
		)
		(property "Manufacturer" "Murata"
			(at 289.969 75.467 0)
			(layer "F.Fab")
			(hide yes)
			(effects
				(font
					(size 1 1)
					(thickness 0.15)
				)
			)
		)
		(property "Val" "100n"
			(at 289.969 75.467 0)
			(layer "F.Fab")
			(hide yes)
			(effects
				(font
					(size 1 1)
					(thickness 0.15)
				)
			)
		)
		(property "Voltage" "50V"
			(at 289.969 75.467 0)
			(layer "F.Fab")
			(hide yes)
			(effects
				(font
					(size 1 1)
					(thickness 0.15)
				)
			)
		)
		(sheetname "/Debug FTDI/")
		(sheetfile "debug-ftdi.kicad_sch")
		(attr smd)
		(fp_rect
			(start -0.9659 -0.481258)
			(end 0.9649 0.458742)
			(stroke
				(width 0.05)
				(type solid)
			)
			(fill no)
			(layer "F.CrtYd")
		)
		(fp_line
			(start 0.499 -0.25)
			(end 0.499 0.248)
			(stroke
				(width 0.15)
				(type solid)
			)
			(layer "F.Fab")
		)
		(fp_line
			(start -0.499 -0.25)
			(end 0.499 -0.25)
			(stroke
				(width 0.15)
				(type solid)
			)
			(layer "F.Fab")
		)
		(fp_line
			(start 0.499 0.248)
			(end -0.499 0.248)
			(stroke
				(width 0.15)
				(type solid)
			)
			(layer "F.Fab")
		)
		(fp_line
			(start -0.499 0.248)
			(end -0.499 -0.25)
			(stroke
				(width 0.15)
				(type solid)
			)
			(layer "F.Fab")
		)
		(pad "1" smd roundrect
			(at -0.484 0 90)
			(size 0.59 0.64)
			(layers "F.Cu" "F.Mask" "F.Paste")
			(roundrect_rratio 0.25)
			(net 1 "GND")
			(pintype "passive")
		)
		(pad "2" smd roundrect
			(at 0.484 0 90)
			(size 0.59 0.64)
			(layers "F.Cu" "F.Mask" "F.Paste")
			(roundrect_rratio 0.25)
			(net 41 "+3V3_AON")
			(pintype "passive")
		)
	)
	(footprint "antmicro-footprints:TP_SMD_1mm"
		(layer "F.Cu")
		(at 186.5 159.2)
		(property "Reference" "TP13"
			(at 0 -0.731898 0)
			(layer "F.SilkS")
			(hide yes)
			(effects
				(font
					(size 0.7 0.7)
					(thickness 0.15)
				)
				(justify left bottom)
			)
		)
		(property "Value" "TP_1mm_SMD"
			(at 0 1.4 0)
			(layer "F.Fab")
			(effects
				(font
					(size 0.7 0.7)
					(thickness 0.15)
				)
				(justify left bottom)
			)
		)
		(property "Author" "Antmicro"
			(at 0 0 0)
			(layer "F.Fab")
			(hide yes)
			(effects
				(font
					(size 1 1)
					(thickness 0.15)
				)
			)
		)
		(property "License" "Apache-2.0"
			(at 0 0 0)
			(layer "F.Fab")
			(hide yes)
			(effects
				(font
					(size 1 1)
					(thickness 0.15)
				)
			)
		)
		(property "MPN" ""
			(at 0 0 0)
			(layer "F.Fab")
			(hide yes)
			(effects
				(font
					(size 1 1)
					(thickness 0.15)
				)
			)
		)
		(property "Manufacturer" ""
			(at 0 0 0)
			(layer "F.Fab")
			(hide yes)
			(effects
				(font
					(size 1 1)
					(thickness 0.15)
				)
			)
		)
		(sheetname "/Supply/")
		(sheetfile "supply.kicad_sch")
		(attr exclude_from_pos_files)
		(pad "1" smd circle
			(at 0 0)
			(size 1 1)
			(layers "F.Cu" "F.Mask")
			(net 206 "+1V1")
			(pinfunction "1")
			(pintype "passive")
		)
	)
	(footprint "antmicro-footprints:SC70-3"
		(layer "F.Cu")
		(at 102.100501 120.876 180)
		(property "Reference" "Q10"
			(at 0 -1.6 180)
			(layer "F.SilkS")
			(hide yes)
			(effects
				(font
					(size 0.7 0.7)
					(thickness 0.15)
				)
				(justify left bottom)
			)
		)
		(property "Value" "BSS138PW,115"
			(at 0 2.3 180)
			(layer "F.Fab")
			(effects
				(font
					(size 0.7 0.7)
					(thickness 0.15)
				)
				(justify left bottom)
			)
		)
		(property "Datasheet" "https://assets.nexperia.com/documents/data-sheet/BSS138PW.pdf"
			(at 0 0 180)
			(layer "F.Fab")
			(hide yes)
			(effects
				(font
					(size 1.27 1.27)
					(thickness 0.15)
				)
			)
		)
		(property "Description" "Power MOSFET, N Channel, 60 V, 320 mA, 0.9 ohm, SOT-323, Surface Mount"
			(at 0 0 180)
			(layer "F.Fab")
			(hide yes)
			(effects
				(font
					(size 1.27 1.27)
					(thickness 0.15)
				)
			)
		)
		(property "Author" "Antmicro"
			(at 204.201002 241.752 0)
			(layer "F.Fab")
			(hide yes)
			(effects
				(font
					(size 1 1)
					(thickness 0.15)
				)
			)
		)
		(property "License" "Apache-2.0"
			(at 204.201002 241.752 0)
			(layer "F.Fab")
			(hide yes)
			(effects
				(font
					(size 1 1)
					(thickness 0.15)
				)
			)
		)
		(property "MPN" "BSS138PW,115"
			(at 204.201002 241.752 0)
			(layer "F.Fab")
			(hide yes)
			(effects
				(font
					(size 1 1)
					(thickness 0.15)
				)
			)
		)
		(property "Manufacturer" "Nexperia"
			(at 204.201002 241.752 0)
			(layer "F.Fab")
			(hide yes)
			(effects
				(font
					(size 1 1)
					(thickness 0.15)
				)
			)
		)
		(sheetname "/DDR5 SODIMM/")
		(sheetfile "ddr5-sodimm.kicad_sch")
		(attr smd)
		(fp_line
			(start 0.627 0.6)
			(end 0.627 1.001)
			(stroke
				(width 0.15)
				(type solid)
			)
			(layer "F.SilkS")
		)
		(fp_line
			(start 0.627 -0.6)
			(end 0.627 -0.999)
			(stroke
				(width 0.15)
				(type solid)
			)
			(layer "F.SilkS")
		)
		(fp_line
			(start -0.3 1)
			(end 0.627 1.001)
			(stroke
				(width 0.15)
				(type solid)
			)
			(layer "F.SilkS")
		)
		(fp_line
			(start -0.3 -1)
			(end 0.627 -0.999)
			(stroke
				(width 0.15)
				(type solid)
			)
			(layer "F.SilkS")
		)
		(fp_line
			(start 1.4 0.4)
			(end 0.9 0.4)
			(stroke
				(width 0.05)
				(type solid)
			)
			(layer "F.CrtYd")
		)
		(fp_line
			(start 1.4 -0.4)
			(end 1.4 0.4)
			(stroke
				(width 0.05)
				(type solid)
			)
			(layer "F.CrtYd")
		)
		(fp_line
			(start 0.9 1.3)
			(end -0.9 1.3)
			(stroke
				(width 0.05)
				(type solid)
			)
			(layer "F.CrtYd")
		)
		(fp_line
			(start 0.9 0.4)
			(end 0.9 1.3)
			(stroke
				(width 0.05)
				(type solid)
			)
			(layer "F.CrtYd")
		)
		(fp_line
			(start 0.9 -0.4)
			(end 1.4 -0.4)
			(stroke
				(width 0.05)
				(type solid)
			)
			(layer "F.CrtYd")
		)
		(fp_line
			(start 0.9 -1.3)
			(end 0.9 -0.4)
			(stroke
				(width 0.05)
				(type solid)
			)
			(layer "F.CrtYd")
		)
		(fp_line
			(start -0.9 1.3)
			(end -0.9 1)
			(stroke
				(width 0.05)
				(type solid)
			)
			(layer "F.CrtYd")
		)
		(fp_line
			(start -0.9 1)
			(end -1.4 1)
			(stroke
				(width 0.05)
				(type solid)
			)
			(layer "F.CrtYd")
		)
		(fp_line
			(start -0.9 -1)
			(end -1.4 -1)
			(stroke
				(width 0.05)
				(type solid)
			)
			(layer "F.CrtYd")
		)
		(fp_line
			(start -0.9 -1.3)
			(end 0.9 -1.3)
			(stroke
				(width 0.05)
				(type solid)
			)
			(layer "F.CrtYd")
		)
		(fp_line
			(start -0.9 -1.3)
			(end -0.9 -1)
			(stroke
				(width 0.05)
				(type solid)
			)
			(layer "F.CrtYd")
		)
		(fp_line
			(start -1.4 1)
			(end -1.4 -1)
			(stroke
				(width 0.05)
				(type solid)
			)
			(layer "F.CrtYd")
		)
		(fp_rect
			(start -0.623 -0.999)
			(end 0.627 1.001)
			(stroke
				(width 0.15)
				(type solid)
			)
			(fill no)
			(layer "F.Fab")
		)
		(pad "1" smd rect
			(at -1.051 -0.65 270)
			(size 0.6 0.6)
			(layers "F.Cu" "F.Mask" "F.Paste")
			(net 235 "HOT_SWAP_GREEN")
			(pinfunction "G")
			(pintype "input")
		)
		(pad "2" smd rect
			(at -1.051 0.65 270)
			(size 0.6 0.6)
			(layers "F.Cu" "F.Mask" "F.Paste")
			(net 1 "GND")
			(pinfunction "S")
			(pintype "passive")
		)
		(pad "3" smd rect
			(at 1.05 0 270)
			(size 0.6 0.6)
			(layers "F.Cu" "F.Mask" "F.Paste")
			(net 359 "Net-(Q10-D)")
			(pinfunction "D")
			(pintype "passive")
		)
	)
	(footprint "antmicro-footprints:NetTie-2_SMD_Pad0.127mm"
		(layer "F.Cu")
		(at 199.825 191.326)
		(descr "Net tie, 2 pin, 0.127mm  SMD pads")
		(tags "net tie")
		(property "Reference" "NT4"
			(at -0.128 -1.345 0)
			(layer "F.SilkS")
			(hide yes)
			(effects
				(font
					(size 0.7 0.7)
					(thickness 0.15)
				)
				(justify left bottom)
			)
		)
		(property "Value" "Net-Tie_P0.127mm"
			(at 0 1.199 0)
			(layer "F.Fab")
			(effects
				(font
					(size 0.7 0.7)
					(thickness 0.15)
				)
				(justify left bottom)
			)
		)
		(property "Author" "Antmicro"
			(at 0 0 0)
			(layer "F.Fab")
			(hide yes)
			(effects
				(font
					(size 1 1)
					(thickness 0.15)
				)
			)
		)
		(property "License" "Apache-2.0"
			(at 0 0 0)
			(layer "F.Fab")
			(hide yes)
			(effects
				(font
					(size 1 1)
					(thickness 0.15)
				)
			)
		)
		(property "MPN" ""
			(at 0 0 0)
			(layer "F.Fab")
			(hide yes)
			(effects
				(font
					(size 1 1)
					(thickness 0.15)
				)
			)
		)
		(property "Manufacturer" ""
			(at 0 0 0)
			(layer "F.Fab")
			(hide yes)
			(effects
				(font
					(size 1 1)
					(thickness 0.15)
				)
			)
		)
		(property ki_fp_filters "Net*Tie*")
		(sheetname "/Supply/")
		(sheetfile "supply.kicad_sch")
		(attr smd exclude_from_pos_files exclude_from_bom)
		(net_tie_pad_groups "1, 2")
		(fp_poly
			(pts
				(xy -0.0635 -0.0635) (xy 0.0625 -0.0635) (xy 0.0625 0.0635) (xy -0.0635 0.0635)
			)
			(stroke
				(width 0)
				(type solid)
			)
			(fill yes)
			(layer "F.Cu")
		)
		(pad "1" smd roundrect
			(at -0.127 0 180)
			(size 0.127 0.127)
			(layers "F.Cu")
			(roundrect_rratio 0.5)
			(chamfer_ratio 0)
			(chamfer top_left bottom_left)
			(net 131 "/Supply/1V7_SEN_+")
			(pinfunction "1")
			(pintype "passive")
		)
		(pad "2" smd roundrect
			(at 0.126 0)
			(size 0.127 0.127)
			(layers "F.Cu")
			(roundrect_rratio 0.5)
			(chamfer_ratio 0)
			(chamfer top_left bottom_left)
			(net 58 "/Supply/1V7_local")
			(pinfunction "2")
			(pintype "passive")
		)
	)
	(footprint "antmicro-footprints:R_0402_1005Metric"
		(layer "F.Cu")
		(at 114.4 186.6 -90)
		(descr "Resistor SMD 0402")
		(tags "resistor SMD 0402")
		(property "Reference" "R6"
			(at -1.122484 -0.772697 270)
			(layer "F.SilkS")
			(hide yes)
			(effects
				(font
					(size 0.7 0.7)
					(thickness 0.15)
				)
				(justify left bottom)
			)
		)
		(property "Value" "R_22R_0402"
			(at -1.011843 1.772047 270)
			(layer "F.Fab")
			(effects
				(font
					(size 0.7 0.7)
					(thickness 0.15)
				)
				(justify left bottom)
			)
		)
		(property "Datasheet" "https://www.bourns.com/docs/product-datasheets/cr.pdf"
			(at 0 0 270)
			(layer "F.Fab")
			(hide yes)
			(effects
				(font
					(size 1.27 1.27)
					(thickness 0.15)
				)
			)
		)
		(property "Author" "Antmicro"
			(at -72.2 301 0)
			(layer "F.Fab")
			(hide yes)
			(effects
				(font
					(size 1 1)
					(thickness 0.15)
				)
			)
		)
		(property "License" "Apache-2.0"
			(at -72.2 301 0)
			(layer "F.Fab")
			(hide yes)
			(effects
				(font
					(size 1 1)
					(thickness 0.15)
				)
			)
		)
		(property "MPN" "CR0402-FX-22R0GLF"
			(at -72.2 301 0)
			(layer "F.Fab")
			(hide yes)
			(effects
				(font
					(size 1 1)
					(thickness 0.15)
				)
			)
		)
		(property "Manufacturer" "Bourns"
			(at -72.2 301 0)
			(layer "F.Fab")
			(hide yes)
			(effects
				(font
					(size 1 1)
					(thickness 0.15)
				)
			)
		)
		(property "Tolerance" "1%"
			(at -72.2 301 0)
			(layer "F.Fab")
			(hide yes)
			(effects
				(font
					(size 1 1)
					(thickness 0.15)
				)
			)
		)
		(property "Val" "22R"
			(at -72.2 301 0)
			(layer "F.Fab")
			(hide yes)
			(effects
				(font
					(size 1 1)
					(thickness 0.15)
				)
			)
		)
		(sheetname "/HyperRAM + QSPI Flash/")
		(sheetfile "hyperram-flash.kicad_sch")
		(attr smd)
		(fp_rect
			(start -0.93 -0.47)
			(end 0.93 0.47)
			(stroke
				(width 0.05)
				(type solid)
			)
			(fill no)
			(layer "F.CrtYd")
		)
		(fp_rect
			(start -0.5 -0.25)
			(end 0.5 0.25)
			(stroke
				(width 0.15)
				(type solid)
			)
			(fill no)
			(layer "F.Fab")
		)
		(pad "1" smd roundrect
			(at -0.485 0 270)
			(size 0.59 0.64)
			(layers "F.Cu" "F.Mask" "F.Paste")
			(roundrect_rratio 0.25)
			(net 362 "/HyperRAM + QSPI Flash/IO0")
			(pintype "passive")
		)
		(pad "2" smd roundrect
			(at 0.485 0 270)
			(size 0.59 0.64)
			(layers "F.Cu" "F.Mask" "F.Paste")
			(roundrect_rratio 0.25)
			(net 626 "/FPGA Config/FLASH.IO0")
			(pintype "passive")
		)
	)
	(footprint "antmicro-footprints:USB-C_Receptacle_GCT_USB4105-GF-A"
		(layer "F.Cu")
		(at 71.700501 155.316 -90)
		(property "Reference" "J3"
			(at 6.084 2.600501 0)
			(layer "F.SilkS")
			(effects
				(font
					(size 0.7 0.7)
					(thickness 0.15)
				)
				(justify left bottom)
			)
		)
		(property "Value" "USB-C_GCT_USB4105-GF-A"
			(at 0 5 270)
			(layer "F.Fab")
			(effects
				(font
					(size 0.7 0.7)
					(thickness 0.15)
				)
				(justify left bottom)
			)
		)
		(property "Datasheet" "https://gct.co/files/drawings/usb4105.pdf"
			(at 0 0 270)
			(layer "F.Fab")
			(hide yes)
			(effects
				(font
					(size 1.27 1.27)
					(thickness 0.15)
				)
			)
		)
		(property "Author" "Antmicro"
			(at -83.615499 227.016501 0)
			(layer "F.Fab")
			(hide yes)
			(effects
				(font
					(size 1 1)
					(thickness 0.15)
				)
			)
		)
		(property "License" "Apache-2.0"
			(at -83.615499 227.016501 0)
			(layer "F.Fab")
			(hide yes)
			(effects
				(font
					(size 1 1)
					(thickness 0.15)
				)
			)
		)
		(property "MPN" "USB4105-GF-A"
			(at -83.615499 227.016501 0)
			(layer "F.Fab")
			(hide yes)
			(effects
				(font
					(size 1 1)
					(thickness 0.15)
				)
			)
		)
		(property "Manufacturer" "GCT"
			(at -83.615499 227.016501 0)
			(layer "F.Fab")
			(hide yes)
			(effects
				(font
					(size 1 1)
					(thickness 0.15)
				)
			)
		)
		(property "VSD_Class" "USB-C"
			(at -83.615499 227.016501 0)
			(layer "F.Fab")
			(hide yes)
			(effects
				(font
					(size 1 1)
					(thickness 0.15)
				)
			)
		)
		(sheetname "/Debug FTDI/")
		(sheetfile "debug-ftdi.kicad_sch")
		(attr smd)
		(fp_line
			(start -4.79 3.854)
			(end 4.788 3.854)
			(stroke
				(width 0.15)
				(type solid)
			)
			(layer "F.SilkS")
		)
		(fp_line
			(start 4.788 3.854)
			(end 4.788 2.575)
			(stroke
				(width 0.15)
				(type solid)
			)
			(layer "F.SilkS")
		)
		(fp_line
			(start -4.79 2.575)
			(end -4.79 3.854)
			(stroke
				(width 0.15)
				(type solid)
			)
			(layer "F.SilkS")
		)
		(fp_line
			(start -4.79 -1.395)
			(end -4.79 -0.145)
			(stroke
				(width 0.15)
				(type solid)
			)
			(layer "F.SilkS")
		)
		(fp_line
			(start 4.788 -1.395)
			(end 4.788 -0.145)
			(stroke
				(width 0.15)
				(type solid)
			)
			(layer "F.SilkS")
		)
		(fp_circle
			(center -3.8 -4.27071)
			(end -3.75 -4.22071)
			(stroke
				(width 0.15)
				(type solid)
			)
			(fill yes)
			(layer "F.SilkS")
		)
		(fp_rect
			(start -5.1 -4.4)
			(end 5.1 3.9)
			(stroke
				(width 0.05)
				(type solid)
			)
			(fill no)
			(layer "F.CrtYd")
		)
		(fp_line
			(start -4.79 3.854)
			(end -4.79 -3.676)
			(stroke
				(width 0.15)
				(type solid)
			)
			(layer "F.Fab")
		)
		(fp_line
			(start -4.702 3.854)
			(end 4.788 3.854)
			(stroke
				(width 0.15)
				(type solid)
			)
			(layer "F.Fab")
		)
		(fp_line
			(start 4.788 3.854)
			(end -4.79 3.854)
			(stroke
				(width 0.15)
				(type solid)
			)
			(layer "F.Fab")
		)
		(fp_line
			(start -4.79 -3.676)
			(end 4.788 -3.676)
			(stroke
				(width 0.15)
				(type solid)
			)
			(layer "F.Fab")
		)
		(fp_line
			(start 4.788 -3.676)
			(end 4.788 3.854)
			(stroke
				(width 0.15)
				(type solid)
			)
			(layer "F.Fab")
		)
		(pad "" np_thru_hole circle
			(at -2.891 -2.426 270)
			(size 0.65 0.65)
			(drill 0.65)
			(layers "*.Cu" "*.Mask")
		)
		(pad "" np_thru_hole circle
			(at 2.89 -2.426 270)
			(size 0.65 0.65)
			(drill 0.65)
			(layers "*.Cu" "*.Mask")
		)
		(pad "A1" smd roundrect
			(at -3.202 -3.5 270)
			(size 0.6 1.15)
			(layers "F.Cu" "F.Mask" "F.Paste")
			(roundrect_rratio 0.25)
			(net 1 "GND")
			(pinfunction "GND")
			(pintype "power_in")
		)
		(pad "A4" smd roundrect
			(at -2.4 -3.5 270)
			(size 0.6 1.15)
			(layers "F.Cu" "F.Mask" "F.Paste")
			(roundrect_rratio 0.25)
			(net 2 "/Debug FTDI/VBUS")
			(pinfunction "VBUS")
			(pintype "passive")
		)
		(pad "A5" smd roundrect
			(at -1.25 -3.5 270)
			(size 0.3 1.15)
			(layers "F.Cu" "F.Mask" "F.Paste")
			(roundrect_rratio 0.25)
			(net 321 "Net-(J3-CC_{1})")
			(pinfunction "CC_{1}")
			(pintype "bidirectional")
		)
		(pad "A6" smd roundrect
			(at -0.25 -3.5 270)
			(size 0.3 1.15)
			(layers "F.Cu" "F.Mask" "F.Paste")
			(roundrect_rratio 0.25)
			(net 290 "/Debug FTDI/DBG_USB_P")
			(pinfunction "D_{A}+")
			(pintype "bidirectional")
		)
		(pad "A7" smd roundrect
			(at 0.248 -3.5 270)
			(size 0.3 1.15)
			(layers "F.Cu" "F.Mask" "F.Paste")
			(roundrect_rratio 0.25)
			(net 291 "/Debug FTDI/DBG_USB_N")
			(pinfunction "D_{A}-")
			(pintype "bidirectional")
		)
		(pad "A8" smd roundrect
			(at 1.249 -3.5 270)
			(size 0.3 1.15)
			(layers "F.Cu" "F.Mask" "F.Paste")
			(roundrect_rratio 0.25)
			(net 322 "unconnected-(J3-SBU_{1}-PadA8)")
			(pinfunction "SBU_{1}")
			(pintype "bidirectional+no_connect")
		)
		(pad "A9" smd roundrect
			(at 2.398 -3.5 270)
			(size 0.6 1.15)
			(layers "F.Cu" "F.Mask" "F.Paste")
			(roundrect_rratio 0.25)
			(net 2 "/Debug FTDI/VBUS")
			(pinfunction "VBUS")
			(pintype "passive")
		)
		(pad "A12" smd roundrect
			(at 3.2 -3.5 270)
			(size 0.6 1.15)
			(layers "F.Cu" "F.Mask" "F.Paste")
			(roundrect_rratio 0.25)
			(net 1 "GND")
			(pinfunction "GND")
			(pintype "passive")
		)
		(pad "B1" smd roundrect
			(at 3.2 -3.5 270)
			(size 0.6 1.15)
			(layers "F.Cu" "F.Mask" "F.Paste")
			(roundrect_rratio 0.25)
			(net 1 "GND")
			(pinfunction "GND")
			(pintype "passive")
		)
		(pad "B4" smd roundrect
			(at 2.398 -3.5 270)
			(size 0.6 1.15)
			(layers "F.Cu" "F.Mask" "F.Paste")
			(roundrect_rratio 0.25)
			(net 2 "/Debug FTDI/VBUS")
			(pinfunction "VBUS")
			(pintype "passive")
		)
		(pad "B5" smd roundrect
			(at 1.749 -3.5 270)
			(size 0.3 1.15)
			(layers "F.Cu" "F.Mask" "F.Paste")
			(roundrect_rratio 0.25)
			(net 323 "Net-(J3-CC_{2})")
			(pinfunction "CC_{2}")
			(pintype "bidirectional")
		)
		(pad "B6" smd roundrect
			(at 0.748 -3.5 270)
			(size 0.3 1.15)
			(layers "F.Cu" "F.Mask" "F.Paste")
			(roundrect_rratio 0.25)
			(net 290 "/Debug FTDI/DBG_USB_P")
			(pinfunction "D_{B}+")
			(pintype "bidirectional")
		)
		(pad "B7" smd roundrect
			(at -0.75 -3.5 270)
			(size 0.3 1.15)
			(layers "F.Cu" "F.Mask" "F.Paste")
			(roundrect_rratio 0.25)
			(net 291 "/Debug FTDI/DBG_USB_N")
			(pinfunction "D_{B}-")
			(pintype "bidirectional")
		)
		(pad "B8" smd roundrect
			(at -1.75 -3.5 270)
			(size 0.3 1.15)
			(layers "F.Cu" "F.Mask" "F.Paste")
			(roundrect_rratio 0.25)
			(net 324 "unconnected-(J3-SBU_{2}-PadB8)")
			(pinfunction "SBU_{2}")
			(pintype "bidirectional+no_connect")
		)
		(pad "B9" smd roundrect
			(at -2.4 -3.5 270)
			(size 0.6 1.15)
			(layers "F.Cu" "F.Mask" "F.Paste")
			(roundrect_rratio 0.25)
			(net 2 "/Debug FTDI/VBUS")
			(pinfunction "VBUS")
			(pintype "passive")
		)
		(pad "B12" smd roundrect
			(at -3.202 -3.5 270)
			(size 0.6 1.15)
			(layers "F.Cu" "F.Mask" "F.Paste")
			(roundrect_rratio 0.25)
			(net 1 "GND")
			(pinfunction "GND")
			(pintype "passive")
		)
		(pad "SH" thru_hole oval
			(at -4.321 -2.926 270)
			(size 1.05 2.1)
			(drill oval 0.6 1.7)
			(layers "*.Cu" "*.Mask")
			(remove_unused_layers no)
			(net 593 "Net-(C133-Pad1)")
			(pinfunction "SH")
			(pintype "passive")
		)
		(pad "SH" thru_hole oval
			(at -4.321 1.255 270)
			(size 1 2)
			(drill oval 0.6 1.4)
			(layers "*.Cu" "*.Mask")
			(remove_unused_layers no)
			(net 593 "Net-(C133-Pad1)")
			(pinfunction "SH")
			(pintype "passive")
		)
		(pad "SH" thru_hole oval
			(at 4.32 -2.926 270)
			(size 1.05 2.1)
			(drill oval 0.6 1.7)
			(layers "*.Cu" "*.Mask")
			(remove_unused_layers no)
			(net 593 "Net-(C133-Pad1)")
			(pinfunction "SH")
			(pintype "passive")
		)
		(pad "SH" thru_hole oval
			(at 4.32 1.255 270)
			(size 1 2)
			(drill oval 0.6 1.4)
			(layers "*.Cu" "*.Mask")
			(remove_unused_layers no)
			(net 593 "Net-(C133-Pad1)")
			(pinfunction "SH")
			(pintype "passive")
		)
	)
	(footprint "antmicro-footprints:DHVQFN-14-1EP_2.5x3mm"
		(layer "F.Cu")
		(at 93.9 181.7 -90)
		(property "Reference" "U7"
			(at 1.9 3.4 0)
			(layer "F.SilkS")
			(effects
				(font
					(size 0.7 0.7)
					(thickness 0.15)
				)
				(justify left bottom)
			)
		)
		(property "Value" "TXU0304BQAR"
			(at 0 2.898 270)
			(layer "F.Fab")
			(effects
				(font
					(size 0.7 0.7)
					(thickness 0.15)
				)
				(justify left bottom)
			)
		)
		(property "Datasheet" "https://www.ti.com/lit/ds/symlink/txu0304.pdf?ts=1637748643258&ref_url=https%253A%252F%252Fwww.ti.com%252Fproduct%252FTXU0304"
			(at 0 0 270)
			(layer "F.Fab")
			(hide yes)
			(effects
				(font
					(size 1.27 1.27)
					(thickness 0.15)
				)
			)
		)
		(property "Author" "Antmicro"
			(at -87.8 275.6 0)
			(layer "F.Fab")
			(hide yes)
			(effects
				(font
					(size 1 1)
					(thickness 0.15)
				)
			)
		)
		(property "License" "Apache-2.0"
			(at -87.8 275.6 0)
			(layer "F.Fab")
			(hide yes)
			(effects
				(font
					(size 1 1)
					(thickness 0.15)
				)
			)
		)
		(property "MPN" "TXU0304BQAR"
			(at -87.8 275.6 0)
			(layer "F.Fab")
			(hide yes)
			(effects
				(font
					(size 1 1)
					(thickness 0.15)
				)
			)
		)
		(property "Manufacturer" "Texas Instruments"
			(at -87.8 275.6 0)
			(layer "F.Fab")
			(hide yes)
			(effects
				(font
					(size 1 1)
					(thickness 0.15)
				)
			)
		)
		(sheetname "/Debug FTDI/")
		(sheetfile "debug-ftdi.kicad_sch")
		(attr smd)
		(fp_line
			(start -1.351 1.6)
			(end -0.5 1.6)
			(stroke
				(width 0.15)
				(type solid)
			)
			(layer "F.SilkS")
		)
		(fp_line
			(start -1.351 1.6)
			(end -1.351 1.249)
			(stroke
				(width 0.15)
				(type solid)
			)
			(layer "F.SilkS")
		)
		(fp_line
			(start 0.494 1.6)
			(end 1.35 1.6)
			(stroke
				(width 0.15)
				(type solid)
			)
			(layer "F.SilkS")
		)
		(fp_line
			(start 1.35 1.6)
			(end 1.35 1.249)
			(stroke
				(width 0.15)
				(type solid)
			)
			(layer "F.SilkS")
		)
		(fp_line
			(start -1.351 -1.601)
			(end -0.5 -1.601)
			(stroke
				(width 0.15)
				(type solid)
			)
			(layer "F.SilkS")
		)
		(fp_line
			(start -1.35 -1.601)
			(end -1.35 -1.25)
			(stroke
				(width 0.15)
				(type solid)
			)
			(layer "F.SilkS")
		)
		(fp_line
			(start 1.35 -1.601)
			(end 1.35 -1.25)
			(stroke
				(width 0.15)
				(type solid)
			)
			(layer "F.SilkS")
		)
		(fp_line
			(start 1.35 -1.601)
			(end 0.494 -1.601)
			(stroke
				(width 0.15)
				(type solid)
			)
			(layer "F.SilkS")
		)
		(fp_circle
			(center -0.7 -1.85)
			(end -0.653 -1.85)
			(stroke
				(width 0.15)
				(type solid)
			)
			(fill yes)
			(layer "F.SilkS")
		)
		(fp_rect
			(start -1.85 -2)
			(end 1.8 1.95)
			(stroke
				(width 0.05)
				(type solid)
			)
			(fill no)
			(layer "F.CrtYd")
		)
		(fp_line
			(start -1.25 1.499)
			(end -1.25 -1.25)
			(stroke
				(width 0.15)
				(type solid)
			)
			(layer "F.Fab")
		)
		(fp_line
			(start 1.249 1.499)
			(end -1.25 1.499)
			(stroke
				(width 0.15)
				(type solid)
			)
			(layer "F.Fab")
		)
		(fp_line
			(start -1.25 -1.25)
			(end -1 -1.5)
			(stroke
				(width 0.15)
				(type solid)
			)
			(layer "F.Fab")
		)
		(fp_line
			(start -1 -1.5)
			(end 1.249 -1.5)
			(stroke
				(width 0.15)
				(type solid)
			)
			(layer "F.Fab")
		)
		(fp_line
			(start 1.249 -1.5)
			(end 1.249 1.499)
			(stroke
				(width 0.15)
				(type solid)
			)
			(layer "F.Fab")
		)
		(pad "1" smd oval
			(at -0.25 -1.5 270)
			(size 0.3 0.8)
			(layers "F.Cu" "F.Mask" "F.Paste")
			(net 6 "/Debug FTDI/FTDI_3V3")
			(pinfunction "VCCA")
			(pintype "power_in")
		)
		(pad "2" smd oval
			(at -1.25 -1)
			(size 0.3 0.8)
			(layers "F.Cu" "F.Mask" "F.Paste")
			(net 742 "/Debug FTDI/FTDI_JTAG_TMS")
			(pinfunction "A1")
			(pintype "input")
		)
		(pad "3" smd oval
			(at -1.25 -0.5)
			(size 0.3 0.8)
			(layers "F.Cu" "F.Mask" "F.Paste")
			(net 739 "/Debug FTDI/FTDI_JTAG_TCK")
			(pinfunction "A2")
			(pintype "input")
		)
		(pad "4" smd oval
			(at -1.25 0)
			(size 0.3 0.8)
			(layers "F.Cu" "F.Mask" "F.Paste")
			(net 740 "/Debug FTDI/FTDI_JTAG_TDI")
			(pinfunction "A3")
			(pintype "input")
		)
		(pad "5" smd oval
			(at -1.25 0.494)
			(size 0.3 0.8)
			(layers "F.Cu" "F.Mask" "F.Paste")
			(net 741 "/Debug FTDI/FTDI_JTAG_TDO")
			(pinfunction "A4Y")
			(pintype "output")
		)
		(pad "6" smd oval
			(at -1.25 0.994)
			(size 0.3 0.8)
			(layers "F.Cu" "F.Mask" "F.Paste")
			(net 710 "unconnected-(U7-NC-Pad6)")
			(pinfunction "NC")
			(pintype "no_connect")
		)
		(pad "7" smd oval
			(at -0.25 1.499 270)
			(size 0.3 0.8)
			(layers "F.Cu" "F.Mask" "F.Paste")
			(net 1 "GND")
			(pinfunction "GND")
			(pintype "passive")
		)
		(pad "8" smd oval
			(at 0.244 1.499 270)
			(size 0.3 0.8)
			(layers "F.Cu" "F.Mask" "F.Paste")
			(net 263 "FTDI_DIS")
			(pinfunction "OE")
			(pintype "tri_state")
		)
		(pad "9" smd oval
			(at 1.249 0.994)
			(size 0.3 0.8)
			(layers "F.Cu" "F.Mask" "F.Paste")
			(net 711 "unconnected-(U7-NC-Pad9)")
			(pinfunction "NC")
			(pintype "no_connect")
		)
		(pad "10" smd oval
			(at 1.249 0.494)
			(size 0.3 0.8)
			(layers "F.Cu" "F.Mask" "F.Paste")
			(net 382 "Net-(U7-B4)")
			(pinfunction "B4")
			(pintype "input")
		)
		(pad "11" smd oval
			(at 1.249 0)
			(size 0.3 0.8)
			(layers "F.Cu" "F.Mask" "F.Paste")
			(net 381 "Net-(U7-B3Y)")
			(pinfunction "B3Y")
			(pintype "output")
		)
		(pad "12" smd oval
			(at 1.249 -0.5)
			(size 0.3 0.8)
			(layers "F.Cu" "F.Mask" "F.Paste")
			(net 380 "Net-(U7-B2Y)")
			(pinfunction "B2Y")
			(pintype "output")
		)
		(pad "13" smd oval
			(at 1.249 -1)
			(size 0.3 0.8)
			(layers "F.Cu" "F.Mask" "F.Paste")
			(net 378 "Net-(U7-B1Y)")
			(pinfunction "B1Y")
			(pintype "output")
		)
		(pad "14" smd oval
			(at 0.244 -1.5 270)
			(size 0.3 0.8)
			(layers "F.Cu" "F.Mask" "F.Paste")
			(net 200 "+3V3")
			(pinfunction "VCCB")
			(pintype "power_in")
		)
		(pad "15" smd rect
			(at 0 0 270)
			(size 1 1.5)
			(layers "F.Cu" "F.Mask" "F.Paste")
			(net 1 "GND")
			(pinfunction "GND")
			(pintype "power_in")
		)
	)
	(footprint "antmicro-footprints:R_0402_1005Metric"
		(layer "F.Cu")
		(at 91 181.715 90)
		(descr "Resistor SMD 0402")
		(tags "resistor SMD 0402")
		(property "Reference" "R51"
			(at -1.122484 -0.772697 90)
			(layer "F.SilkS")
			(hide yes)
			(effects
				(font
					(size 0.7 0.7)
					(thickness 0.15)
				)
				(justify left bottom)
			)
		)
		(property "Value" "R_47k_0402"
			(at -1.011843 1.772047 90)
			(layer "F.Fab")
			(effects
				(font
					(size 0.7 0.7)
					(thickness 0.15)
				)
				(justify left bottom)
			)
		)
		(property "Datasheet" "https://www.bourns.com/docs/product-datasheets/cr.pdf"
			(at 0 0 90)
			(layer "F.Fab")
			(hide yes)
			(effects
				(font
					(size 1.27 1.27)
					(thickness 0.15)
				)
			)
		)
		(property "Author" "Antmicro"
			(at 272.715 90.715 0)
			(layer "F.Fab")
			(hide yes)
			(effects
				(font
					(size 1 1)
					(thickness 0.15)
				)
			)
		)
		(property "License" "Apache-2.0"
			(at 272.715 90.715 0)
			(layer "F.Fab")
			(hide yes)
			(effects
				(font
					(size 1 1)
					(thickness 0.15)
				)
			)
		)
		(property "MPN" "CR0402-FX-4702GLF"
			(at 272.715 90.715 0)
			(layer "F.Fab")
			(hide yes)
			(effects
				(font
					(size 1 1)
					(thickness 0.15)
				)
			)
		)
		(property "Manufacturer" "Bourns"
			(at 272.715 90.715 0)
			(layer "F.Fab")
			(hide yes)
			(effects
				(font
					(size 1 1)
					(thickness 0.15)
				)
			)
		)
		(property "Tolerance" "1%"
			(at 272.715 90.715 0)
			(layer "F.Fab")
			(hide yes)
			(effects
				(font
					(size 1 1)
					(thickness 0.15)
				)
			)
		)
		(property "Val" "47k"
			(at 272.715 90.715 0)
			(layer "F.Fab")
			(hide yes)
			(effects
				(font
					(size 1 1)
					(thickness 0.15)
				)
			)
		)
		(sheetname "/Debug FTDI/")
		(sheetfile "debug-ftdi.kicad_sch")
		(attr smd)
		(fp_rect
			(start -0.93 -0.47)
			(end 0.93 0.47)
			(stroke
				(width 0.05)
				(type solid)
			)
			(fill no)
			(layer "F.CrtYd")
		)
		(fp_rect
			(start -0.5 -0.25)
			(end 0.5 0.25)
			(stroke
				(width 0.15)
				(type solid)
			)
			(fill no)
			(layer "F.Fab")
		)
		(pad "1" smd roundrect
			(at -0.485 0 90)
			(size 0.59 0.64)
			(layers "F.Cu" "F.Mask" "F.Paste")
			(roundrect_rratio 0.25)
			(net 263 "FTDI_DIS")
			(pintype "passive")
		)
		(pad "2" smd roundrect
			(at 0.485 0 90)
			(size 0.59 0.64)
			(layers "F.Cu" "F.Mask" "F.Paste")
			(roundrect_rratio 0.25)
			(net 200 "+3V3")
			(pintype "passive")
		)
	)
	(footprint "antmicro-footprints:C_0402_1005Metric"
		(layer "F.Cu")
		(at 121.5 205 180)
		(descr "Capacitor SMD 0402")
		(tags "capacitor SMD 0402")
		(property "Reference" "C176"
			(at 0 -0.699 180)
			(layer "F.SilkS")
			(hide yes)
			(effects
				(font
					(size 0.7 0.7)
					(thickness 0.15)
				)
				(justify left bottom)
			)
		)
		(property "Value" "C_100n_0402"
			(at -1.022927 2.155213 180)
			(layer "F.Fab")
			(effects
				(font
					(size 0.7 0.7)
					(thickness 0.15)
				)
				(justify left bottom)
			)
		)
		(property "Datasheet" "https://www.murata.com/products/productdetail?partno=GRM155R61H104KE14%23"
			(at 0 0 180)
			(layer "F.Fab")
			(hide yes)
			(effects
				(font
					(size 1.27 1.27)
					(thickness 0.15)
				)
			)
		)
		(property "Author" "Antmicro"
			(at 243 410 0)
			(layer "F.Fab")
			(hide yes)
			(effects
				(font
					(size 1 1)
					(thickness 0.15)
				)
			)
		)
		(property "Dielectric" "X5R"
			(at 243 410 0)
			(layer "F.Fab")
			(hide yes)
			(effects
				(font
					(size 1 1)
					(thickness 0.15)
				)
			)
		)
		(property "License" "Apache-2.0"
			(at 243 410 0)
			(layer "F.Fab")
			(hide yes)
			(effects
				(font
					(size 1 1)
					(thickness 0.15)
				)
			)
		)
		(property "MPN" "GRM155R61H104KE14D"
			(at 243 410 0)
			(layer "F.Fab")
			(hide yes)
			(effects
				(font
					(size 1 1)
					(thickness 0.15)
				)
			)
		)
		(property "Manufacturer" "Murata"
			(at 243 410 0)
			(layer "F.Fab")
			(hide yes)
			(effects
				(font
					(size 1 1)
					(thickness 0.15)
				)
			)
		)
		(property "Val" "100n"
			(at 243 410 0)
			(layer "F.Fab")
			(hide yes)
			(effects
				(font
					(size 1 1)
					(thickness 0.15)
				)
			)
		)
		(property "Voltage" "50V"
			(at 243 410 0)
			(layer "F.Fab")
			(hide yes)
			(effects
				(font
					(size 1 1)
					(thickness 0.15)
				)
			)
		)
		(sheetname "/Supply/")
		(sheetfile "supply.kicad_sch")
		(attr smd)
		(fp_rect
			(start -0.9659 -0.481258)
			(end 0.9649 0.458742)
			(stroke
				(width 0.05)
				(type solid)
			)
			(fill no)
			(layer "F.CrtYd")
		)
		(fp_line
			(start 0.499 0.248)
			(end -0.499 0.248)
			(stroke
				(width 0.15)
				(type solid)
			)
			(layer "F.Fab")
		)
		(fp_line
			(start 0.499 -0.25)
			(end 0.499 0.248)
			(stroke
				(width 0.15)
				(type solid)
			)
			(layer "F.Fab")
		)
		(fp_line
			(start -0.499 0.248)
			(end -0.499 -0.25)
			(stroke
				(width 0.15)
				(type solid)
			)
			(layer "F.Fab")
		)
		(fp_line
			(start -0.499 -0.25)
			(end 0.499 -0.25)
			(stroke
				(width 0.15)
				(type solid)
			)
			(layer "F.Fab")
		)
		(pad "1" smd roundrect
			(at -0.484 0 180)
			(size 0.59 0.64)
			(layers "F.Cu" "F.Mask" "F.Paste")
			(roundrect_rratio 0.25)
			(net 1 "GND")
			(pintype "passive")
		)
		(pad "2" smd roundrect
			(at 0.484 0 180)
			(size 0.59 0.64)
			(layers "F.Cu" "F.Mask" "F.Paste")
			(roundrect_rratio 0.25)
			(net 596 "/Supply/12V_PCIE_fused")
			(pintype "passive")
		)
	)
	(footprint "antmicro-footprints:SOT-23-6"
		(layer "F.Cu")
		(at 184.391759 133.2071 180)
		(property "Reference" "U17"
			(at 1.765759 -0.1429 270)
			(layer "F.SilkS")
			(effects
				(font
					(size 0.7 0.7)
					(thickness 0.15)
				)
				(justify left bottom)
			)
		)
		(property "Value" "LTC4412IS6"
			(at -1.75 2.75 180)
			(layer "F.Fab")
			(effects
				(font
					(size 0.7 0.7)
					(thickness 0.15)
				)
				(justify left bottom)
			)
		)
		(property "Datasheet" "https://www.mouser.com/datasheet/2/308/NCV8187_D-1813214.pdf"
			(at 0 0 180)
			(layer "F.Fab")
			(hide yes)
			(effects
				(font
					(size 1.27 1.27)
					(thickness 0.15)
				)
			)
		)
		(property "Author" "Antmicro"
			(at 368.783518 266.4142 0)
			(layer "F.Fab")
			(hide yes)
			(effects
				(font
					(size 1 1)
					(thickness 0.15)
				)
			)
		)
		(property "License" "Apache-2.0"
			(at 368.783518 266.4142 0)
			(layer "F.Fab")
			(hide yes)
			(effects
				(font
					(size 1 1)
					(thickness 0.15)
				)
			)
		)
		(property "MPN" "LTC4412IS6#TRMPBF"
			(at 368.783518 266.4142 0)
			(layer "F.Fab")
			(hide yes)
			(effects
				(font
					(size 1 1)
					(thickness 0.15)
				)
			)
		)
		(property "Manufacturer" "Analog Devices"
			(at 368.783518 266.4142 0)
			(layer "F.Fab")
			(hide yes)
			(effects
				(font
					(size 1 1)
					(thickness 0.15)
				)
			)
		)
		(sheetname "/Supply/")
		(sheetfile "supply.kicad_sch")
		(attr smd)
		(fp_line
			(start 1.45 0.7)
			(end 1.45 0.4)
			(stroke
				(width 0.12)
				(type solid)
			)
			(layer "F.SilkS")
		)
		(fp_line
			(start 1.45 -0.7)
			(end 1.45 -0.4)
			(stroke
				(width 0.12)
				(type solid)
			)
			(layer "F.SilkS")
		)
		(fp_line
			(start 1.3 0.7)
			(end 1.45 0.7)
			(stroke
				(width 0.12)
				(type solid)
			)
			(layer "F.SilkS")
		)
		(fp_line
			(start 1.3 -0.7)
			(end 1.45 -0.7)
			(stroke
				(width 0.12)
				(type solid)
			)
			(layer "F.SilkS")
		)
		(fp_line
			(start -1.3 -0.7)
			(end -1.45 -0.7)
			(stroke
				(width 0.12)
				(type solid)
			)
			(layer "F.SilkS")
		)
		(fp_line
			(start -1.45 0.7)
			(end -1.45 0.4)
			(stroke
				(width 0.12)
				(type solid)
			)
			(layer "F.SilkS")
		)
		(fp_line
			(start -1.45 -0.7)
			(end -1.45 -0.4)
			(stroke
				(width 0.12)
				(type solid)
			)
			(layer "F.SilkS")
		)
		(fp_rect
			(start -1.55 -1.85)
			(end 1.55 1.75)
			(stroke
				(width 0.05)
				(type solid)
			)
			(fill no)
			(layer "F.CrtYd")
		)
		(fp_line
			(start 1.5 0.7)
			(end -1.5 0.7)
			(stroke
				(width 0.1)
				(type solid)
			)
			(layer "F.Fab")
		)
		(fp_line
			(start 1.5 -0.7)
			(end 1.5 0.7)
			(stroke
				(width 0.1)
				(type solid)
			)
			(layer "F.Fab")
		)
		(fp_line
			(start -1.5 0.7)
			(end -1.5 -0.7)
			(stroke
				(width 0.1)
				(type solid)
			)
			(layer "F.Fab")
		)
		(fp_line
			(start -1.5 -0.7)
			(end 1.5 -0.7)
			(stroke
				(width 0.1)
				(type solid)
			)
			(layer "F.Fab")
		)
		(fp_text user "."
			(at -1.4 1.2 0)
			(layer "F.SilkS")
			(effects
				(font
					(size 1 1)
					(thickness 0.15)
				)
			)
		)
		(pad "1" smd roundrect
			(at -0.954 1.1 180)
			(size 0.55 1)
			(layers "F.Cu" "F.Mask" "F.Paste")
			(roundrect_rratio 0.15)
			(net 595 "/Supply/12V_aux_fused")
			(pinfunction "IN")
			(pintype "power_in")
		)
		(pad "2" smd roundrect
			(at -0.003 1.1 180)
			(size 0.55 1)
			(layers "F.Cu" "F.Mask" "F.Paste")
			(roundrect_rratio 0.15)
			(net 1 "GND")
			(pinfunction "GND")
			(pintype "power_in")
		)
		(pad "3" smd roundrect
			(at 0.947 1.1 180)
			(size 0.55 1)
			(layers "F.Cu" "F.Mask" "F.Paste")
			(roundrect_rratio 0.15)
			(net 1 "GND")
			(pinfunction "CTL")
			(pintype "input")
		)
		(pad "4" smd roundrect
			(at 0.947 -1.214 180)
			(size 0.55 1)
			(layers "F.Cu" "F.Mask" "F.Paste")
			(roundrect_rratio 0.15)
			(net 724 "unconnected-(U17-STAT-Pad4)")
			(pinfunction "STAT")
			(pintype "output+no_connect")
		)
		(pad "5" smd roundrect
			(at -0.003 -1.214 180)
			(size 0.55 1)
			(layers "F.Cu" "F.Mask" "F.Paste")
			(roundrect_rratio 0.15)
			(net 365 "Net-(Q12-G)")
			(pinfunction "GATE")
			(pintype "output")
		)
		(pad "6" smd roundrect
			(at -0.954 -1.214 180)
			(size 0.55 1)
			(layers "F.Cu" "F.Mask" "F.Paste")
			(roundrect_rratio 0.15)
			(net 38 "VDC")
			(pinfunction "SENSE")
			(pintype "input")
		)
	)
	(footprint "antmicro-footprints:C_0603_1608Metric"
		(layer "F.Cu")
		(at 184.491759 135.907099)
		(descr "Capacitor SMD 0603")
		(tags "capacitor 0603")
		(property "Reference" "C179"
			(at -1.42757 -1.000252 0)
			(layer "F.SilkS")
			(hide yes)
			(effects
				(font
					(size 0.7 0.7)
					(thickness 0.15)
				)
				(justify left bottom)
			)
		)
		(property "Value" "C_1u_25V_0603"
			(at -1.42757 1.770288 0)
			(layer "F.Fab")
			(effects
				(font
					(size 0.7 0.7)
					(thickness 0.15)
				)
				(justify left bottom)
			)
		)
		(property "Datasheet" "https://product.samsungsem.com/mlcc/CL10A105KA8NNN.do"
			(at 0 0 0)
			(layer "F.Fab")
			(hide yes)
			(effects
				(font
					(size 1.27 1.27)
					(thickness 0.15)
				)
			)
		)
		(property "Author" "Antmicro"
			(at 0 0 0)
			(layer "F.Fab")
			(hide yes)
			(effects
				(font
					(size 1 1)
					(thickness 0.15)
				)
			)
		)
		(property "Dielectric" ""
			(at 0 0 0)
			(layer "F.Fab")
			(hide yes)
			(effects
				(font
					(size 1 1)
					(thickness 0.15)
				)
			)
		)
		(property "License" "Apache-2.0"
			(at 0 0 0)
			(layer "F.Fab")
			(hide yes)
			(effects
				(font
					(size 1 1)
					(thickness 0.15)
				)
			)
		)
		(property "MPN" "CL10A105KA8NNNC"
			(at 0 0 0)
			(layer "F.Fab")
			(hide yes)
			(effects
				(font
					(size 1 1)
					(thickness 0.15)
				)
			)
		)
		(property "Manufacturer" "Samsung Electro-Mechanics"
			(at 0 0 0)
			(layer "F.Fab")
			(hide yes)
			(effects
				(font
					(size 1 1)
					(thickness 0.15)
				)
			)
		)
		(property "Val" "1u/25V"
			(at 0 0 0)
			(layer "F.Fab")
			(hide yes)
			(effects
				(font
					(size 1 1)
					(thickness 0.15)
				)
			)
		)
		(property "Voltage" ""
			(at 0 0 0)
			(layer "F.Fab")
			(hide yes)
			(effects
				(font
					(size 1 1)
					(thickness 0.15)
				)
			)
		)
		(sheetname "/Supply/")
		(sheetfile "supply.kicad_sch")
		(attr smd)
		(fp_line
			(start -0.3 -0.3)
			(end 0.3 -0.3)
			(stroke
				(width 0.15)
				(type solid)
			)
			(layer "F.SilkS")
		)
		(fp_line
			(start -0.3 0.3)
			(end 0.3 0.3)
			(stroke
				(width 0.15)
				(type solid)
			)
			(layer "F.SilkS")
		)
		(fp_rect
			(start -1.24 -0.7)
			(end 1.24 0.7)
			(stroke
				(width 0.05)
				(type solid)
			)
			(fill no)
			(layer "F.CrtYd")
		)
		(fp_rect
			(start -0.8 -0.4)
			(end 0.8 0.4)
			(stroke
				(width 0.15)
				(type solid)
			)
			(fill no)
			(layer "F.Fab")
		)
		(pad "1" smd roundrect
			(at -0.7 0)
			(size 0.6 0.8)
			(layers "F.Cu" "F.Mask" "F.Paste")
			(roundrect_rratio 0.2)
			(net 1 "GND")
			(pintype "passive")
		)
		(pad "2" smd roundrect
			(at 0.7 0)
			(size 0.6 0.8)
			(layers "F.Cu" "F.Mask" "F.Paste")
			(roundrect_rratio 0.2)
			(net 38 "VDC")
			(pintype "passive")
		)
	)
	(footprint "antmicro-footprints:C_0805_2012Metric"
		(layer "F.Cu")
		(at 205.281001 166.922 90)
		(descr "Capacitor SMD 0805")
		(tags "capacitor SMD 0805")
		(property "Reference" "C173"
			(at -2.10551 -1.198678 90)
			(layer "F.SilkS")
			(hide yes)
			(effects
				(font
					(size 0.7 0.7)
					(thickness 0.15)
				)
				(justify left bottom)
			)
		)
		(property "Value" "C_22u_25V_0805"
			(at -2.055717 1.963152 90)
			(layer "F.Fab")
			(effects
				(font
					(size 0.7 0.7)
					(thickness 0.15)
				)
				(justify left bottom)
			)
		)
		(property "Datasheet" "https://product.samsungsem.com/mlcc/CL21A226MAYNNN.do"
			(at 0 0 90)
			(layer "F.Fab")
			(hide yes)
			(effects
				(font
					(size 1.27 1.27)
					(thickness 0.15)
				)
			)
		)
		(property "Author" "Antmicro"
			(at 372.203001 -38.359001 0)
			(layer "F.Fab")
			(hide yes)
			(effects
				(font
					(size 1 1)
					(thickness 0.15)
				)
			)
		)
		(property "Dielectric" ""
			(at 372.203001 -38.359001 0)
			(layer "F.Fab")
			(hide yes)
			(effects
				(font
					(size 1 1)
					(thickness 0.15)
				)
			)
		)
		(property "License" "Apache-2.0"
			(at 372.203001 -38.359001 0)
			(layer "F.Fab")
			(hide yes)
			(effects
				(font
					(size 1 1)
					(thickness 0.15)
				)
			)
		)
		(property "MPN" "CL21A226MAYNNNE"
			(at 372.203001 -38.359001 0)
			(layer "F.Fab")
			(hide yes)
			(effects
				(font
					(size 1 1)
					(thickness 0.15)
				)
			)
		)
		(property "Manufacturer" "Samsung Electro-Mechanics"
			(at 372.203001 -38.359001 0)
			(layer "F.Fab")
			(hide yes)
			(effects
				(font
					(size 1 1)
					(thickness 0.15)
				)
			)
		)
		(property "Val" "22u_25V"
			(at 372.203001 -38.359001 0)
			(layer "F.Fab")
			(hide yes)
			(effects
				(font
					(size 1 1)
					(thickness 0.15)
				)
			)
		)
		(property "Voltage" ""
			(at 372.203001 -38.359001 0)
			(layer "F.Fab")
			(hide yes)
			(effects
				(font
					(size 1 1)
					(thickness 0.15)
				)
			)
		)
		(sheetname "/Supply/")
		(sheetfile "supply.kicad_sch")
		(attr smd)
		(fp_line
			(start -0.3 -0.8)
			(end 0.3 -0.8)
			(stroke
				(width 0.15)
				(type solid)
			)
			(layer "F.SilkS")
		)
		(fp_line
			(start -0.3 0.8)
			(end 0.3 0.8)
			(stroke
				(width 0.15)
				(type solid)
			)
			(layer "F.SilkS")
		)
		(fp_rect
			(start -1.9 -0.93)
			(end 1.9 0.93)
			(stroke
				(width 0.05)
				(type solid)
			)
			(fill no)
			(layer "F.CrtYd")
		)
		(fp_rect
			(start -0.95 -0.675)
			(end 0.95 0.675)
			(stroke
				(width 0.15)
				(type solid)
			)
			(fill no)
			(layer "F.Fab")
		)
		(pad "1" smd rect
			(at -1.05 0 90)
			(size 1.2 1.2)
			(layers "F.Cu" "F.Mask" "F.Paste")
			(net 1 "GND")
			(pintype "passive")
		)
		(pad "2" smd rect
			(at 1.05 0 90)
			(size 1.2 1.2)
			(layers "F.Cu" "F.Mask" "F.Paste")
			(net 38 "VDC")
			(pintype "passive")
		)
	)
	(footprint "antmicro-footprints:C_0603_1608Metric"
		(layer "F.Cu")
		(at 168.655502 195.614502 180)
		(descr "Capacitor SMD 0603")
		(tags "capacitor 0603")
		(property "Reference" "C217"
			(at -1.42757 -1.000252 180)
			(layer "F.SilkS")
			(hide yes)
			(effects
				(font
					(size 0.7 0.7)
					(thickness 0.15)
				)
				(justify left bottom)
			)
		)
		(property "Value" "C_22u_0603"
			(at -1.42757 1.770288 180)
			(layer "F.Fab")
			(effects
				(font
					(size 0.7 0.7)
					(thickness 0.15)
				)
				(justify left bottom)
			)
		)
		(property "Datasheet" "https://www.murata.com/products/productdetail?partno=GRM188R60J226MEA0%23"
			(at 0 0 180)
			(layer "F.Fab")
			(hide yes)
			(effects
				(font
					(size 1.27 1.27)
					(thickness 0.15)
				)
			)
		)
		(property "Author" "Antmicro"
			(at 337.311004 391.229004 0)
			(layer "F.Fab")
			(hide yes)
			(effects
				(font
					(size 1 1)
					(thickness 0.15)
				)
			)
		)
		(property "Dielectric" ""
			(at 337.311004 391.229004 0)
			(layer "F.Fab")
			(hide yes)
			(effects
				(font
					(size 1 1)
					(thickness 0.15)
				)
			)
		)
		(property "License" "Apache-2.0"
			(at 337.311004 391.229004 0)
			(layer "F.Fab")
			(hide yes)
			(effects
				(font
					(size 1 1)
					(thickness 0.15)
				)
			)
		)
		(property "MPN" "GRM188R60J226MEA0D"
			(at 337.311004 391.229004 0)
			(layer "F.Fab")
			(hide yes)
			(effects
				(font
					(size 1 1)
					(thickness 0.15)
				)
			)
		)
		(property "Manufacturer" "Murata"
			(at 337.311004 391.229004 0)
			(layer "F.Fab")
			(hide yes)
			(effects
				(font
					(size 1 1)
					(thickness 0.15)
				)
			)
		)
		(property "Val" "22u"
			(at 337.311004 391.229004 0)
			(layer "F.Fab")
			(hide yes)
			(effects
				(font
					(size 1 1)
					(thickness 0.15)
				)
			)
		)
		(property "Voltage" ""
			(at 337.311004 391.229004 0)
			(layer "F.Fab")
			(hide yes)
			(effects
				(font
					(size 1 1)
					(thickness 0.15)
				)
			)
		)
		(sheetname "/Supply/")
		(sheetfile "supply.kicad_sch")
		(attr smd)
		(fp_line
			(start -0.3 0.3)
			(end 0.3 0.3)
			(stroke
				(width 0.15)
				(type solid)
			)
			(layer "F.SilkS")
		)
		(fp_line
			(start -0.3 -0.3)
			(end 0.3 -0.3)
			(stroke
				(width 0.15)
				(type solid)
			)
			(layer "F.SilkS")
		)
		(fp_rect
			(start -1.24 -0.7)
			(end 1.24 0.7)
			(stroke
				(width 0.05)
				(type solid)
			)
			(fill no)
			(layer "F.CrtYd")
		)
		(fp_rect
			(start -0.8 -0.4)
			(end 0.8 0.4)
			(stroke
				(width 0.15)
				(type solid)
			)
			(fill no)
			(layer "F.Fab")
		)
		(pad "1" smd roundrect
			(at -0.7 0 180)
			(size 0.6 0.8)
			(layers "F.Cu" "F.Mask" "F.Paste")
			(roundrect_rratio 0.2)
			(net 1 "GND")
			(pintype "passive")
		)
		(pad "2" smd roundrect
			(at 0.7 0 180)
			(size 0.6 0.8)
			(layers "F.Cu" "F.Mask" "F.Paste")
			(roundrect_rratio 0.2)
			(net 78 "/Supply/1V0_REG")
			(pintype "passive")
		)
	)
	(footprint "antmicro-footprints:C_0603_1608Metric"
		(layer "F.Cu")
		(at 192.745501 185.523 -90)
		(descr "Capacitor SMD 0603")
		(tags "capacitor 0603")
		(property "Reference" "C182"
			(at -1.42757 -1.000252 270)
			(layer "F.SilkS")
			(hide yes)
			(effects
				(font
					(size 0.7 0.7)
					(thickness 0.15)
				)
				(justify left bottom)
			)
		)
		(property "Value" "C_22u_0603"
			(at -1.42757 1.770288 270)
			(layer "F.Fab")
			(effects
				(font
					(size 0.7 0.7)
					(thickness 0.15)
				)
				(justify left bottom)
			)
		)
		(property "Datasheet" "https://www.murata.com/products/productdetail?partno=GRM188R60J226MEA0%23"
			(at 0 0 270)
			(layer "F.Fab")
			(hide yes)
			(effects
				(font
					(size 1.27 1.27)
					(thickness 0.15)
				)
			)
		)
		(property "Author" "Antmicro"
			(at 7.222501 378.268501 0)
			(layer "F.Fab")
			(hide yes)
			(effects
				(font
					(size 1 1)
					(thickness 0.15)
				)
			)
		)
		(property "Dielectric" ""
			(at 7.222501 378.268501 0)
			(layer "F.Fab")
			(hide yes)
			(effects
				(font
					(size 1 1)
					(thickness 0.15)
				)
			)
		)
		(property "License" "Apache-2.0"
			(at 7.222501 378.268501 0)
			(layer "F.Fab")
			(hide yes)
			(effects
				(font
					(size 1 1)
					(thickness 0.15)
				)
			)
		)
		(property "MPN" "GRM188R60J226MEA0D"
			(at 7.222501 378.268501 0)
			(layer "F.Fab")
			(hide yes)
			(effects
				(font
					(size 1 1)
					(thickness 0.15)
				)
			)
		)
		(property "Manufacturer" "Murata"
			(at 7.222501 378.268501 0)
			(layer "F.Fab")
			(hide yes)
			(effects
				(font
					(size 1 1)
					(thickness 0.15)
				)
			)
		)
		(property "Val" "22u"
			(at 7.222501 378.268501 0)
			(layer "F.Fab")
			(hide yes)
			(effects
				(font
					(size 1 1)
					(thickness 0.15)
				)
			)
		)
		(property "Voltage" ""
			(at 7.222501 378.268501 0)
			(layer "F.Fab")
			(hide yes)
			(effects
				(font
					(size 1 1)
					(thickness 0.15)
				)
			)
		)
		(sheetname "/Supply/")
		(sheetfile "supply.kicad_sch")
		(attr smd)
		(fp_line
			(start -0.3 0.3)
			(end 0.3 0.3)
			(stroke
				(width 0.15)
				(type solid)
			)
			(layer "F.SilkS")
		)
		(fp_line
			(start -0.3 -0.3)
			(end 0.3 -0.3)
			(stroke
				(width 0.15)
				(type solid)
			)
			(layer "F.SilkS")
		)
		(fp_rect
			(start -1.24 -0.7)
			(end 1.24 0.7)
			(stroke
				(width 0.05)
				(type solid)
			)
			(fill no)
			(layer "F.CrtYd")
		)
		(fp_rect
			(start -0.8 -0.4)
			(end 0.8 0.4)
			(stroke
				(width 0.15)
				(type solid)
			)
			(fill no)
			(layer "F.Fab")
		)
		(pad "1" smd roundrect
			(at -0.7 0 270)
			(size 0.6 0.8)
			(layers "F.Cu" "F.Mask" "F.Paste")
			(roundrect_rratio 0.2)
			(net 1 "GND")
			(pintype "passive")
		)
		(pad "2" smd roundrect
			(at 0.7 0 270)
			(size 0.6 0.8)
			(layers "F.Cu" "F.Mask" "F.Paste")
			(roundrect_rratio 0.2)
			(net 42 "/Supply/MGTAVCC_local")
			(pintype "passive")
		)
	)
	(footprint "antmicro-footprints:C_0402_1005Metric"
		(layer "F.Cu")
		(at 78.225 160.115 -90)
		(descr "Capacitor SMD 0402")
		(tags "capacitor SMD 0402")
		(property "Reference" "C133"
			(at 0 -0.699 270)
			(layer "F.SilkS")
			(hide yes)
			(effects
				(font
					(size 0.7 0.7)
					(thickness 0.15)
				)
				(justify left bottom)
			)
		)
		(property "Value" "C_100n_0402"
			(at -1.022927 2.155213 270)
			(layer "F.Fab")
			(effects
				(font
					(size 0.7 0.7)
					(thickness 0.15)
				)
				(justify left bottom)
			)
		)
		(property "Datasheet" "https://www.murata.com/products/productdetail?partno=GRM155R61H104KE14%23"
			(at 0 0 270)
			(layer "F.Fab")
			(hide yes)
			(effects
				(font
					(size 1.27 1.27)
					(thickness 0.15)
				)
			)
		)
		(property "Author" "Antmicro"
			(at -81.89 238.34 0)
			(layer "F.Fab")
			(hide yes)
			(effects
				(font
					(size 1 1)
					(thickness 0.15)
				)
			)
		)
		(property "Dielectric" "X5R"
			(at -81.89 238.34 0)
			(layer "F.Fab")
			(hide yes)
			(effects
				(font
					(size 1 1)
					(thickness 0.15)
				)
			)
		)
		(property "License" "Apache-2.0"
			(at -81.89 238.34 0)
			(layer "F.Fab")
			(hide yes)
			(effects
				(font
					(size 1 1)
					(thickness 0.15)
				)
			)
		)
		(property "MPN" "GRM155R61H104KE14D"
			(at -81.89 238.34 0)
			(layer "F.Fab")
			(hide yes)
			(effects
				(font
					(size 1 1)
					(thickness 0.15)
				)
			)
		)
		(property "Manufacturer" "Murata"
			(at -81.89 238.34 0)
			(layer "F.Fab")
			(hide yes)
			(effects
				(font
					(size 1 1)
					(thickness 0.15)
				)
			)
		)
		(property "Val" "100n"
			(at -81.89 238.34 0)
			(layer "F.Fab")
			(hide yes)
			(effects
				(font
					(size 1 1)
					(thickness 0.15)
				)
			)
		)
		(property "Voltage" "50V"
			(at -81.89 238.34 0)
			(layer "F.Fab")
			(hide yes)
			(effects
				(font
					(size 1 1)
					(thickness 0.15)
				)
			)
		)
		(sheetname "/Debug FTDI/")
		(sheetfile "debug-ftdi.kicad_sch")
		(attr smd)
		(fp_rect
			(start -0.9659 -0.481258)
			(end 0.9649 0.458742)
			(stroke
				(width 0.05)
				(type solid)
			)
			(fill no)
			(layer "F.CrtYd")
		)
		(fp_line
			(start -0.499 0.248)
			(end -0.499 -0.25)
			(stroke
				(width 0.15)
				(type solid)
			)
			(layer "F.Fab")
		)
		(fp_line
			(start 0.499 0.248)
			(end -0.499 0.248)
			(stroke
				(width 0.15)
				(type solid)
			)
			(layer "F.Fab")
		)
		(fp_line
			(start -0.499 -0.25)
			(end 0.499 -0.25)
			(stroke
				(width 0.15)
				(type solid)
			)
			(layer "F.Fab")
		)
		(fp_line
			(start 0.499 -0.25)
			(end 0.499 0.248)
			(stroke
				(width 0.15)
				(type solid)
			)
			(layer "F.Fab")
		)
		(pad "1" smd roundrect
			(at -0.484 0 270)
			(size 0.59 0.64)
			(layers "F.Cu" "F.Mask" "F.Paste")
			(roundrect_rratio 0.25)
			(net 593 "Net-(C133-Pad1)")
			(pintype "passive")
		)
		(pad "2" smd roundrect
			(at 0.484 0 270)
			(size 0.59 0.64)
			(layers "F.Cu" "F.Mask" "F.Paste")
			(roundrect_rratio 0.25)
			(net 1 "GND")
			(pintype "passive")
		)
	)
	(footprint "antmicro-footprints:LED_0603_1608Metric_G"
		(layer "F.Cu")
		(at 92.699 197.1 -90)
		(descr "LED SMD 0603 Green")
		(tags "LED SMD 0603 Green")
		(property "Reference" "D10"
			(at -0.001 -0.901 270)
			(layer "F.SilkS")
			(hide yes)
			(effects
				(font
					(size 0.7 0.7)
					(thickness 0.15)
				)
				(justify left bottom)
			)
		)
		(property "Value" "LED_G_0603_KP-1608CGCK"
			(at -0.001 1.599 270)
			(layer "F.Fab")
			(effects
				(font
					(size 0.7 0.7)
					(thickness 0.15)
				)
				(justify left bottom)
			)
		)
		(property "Datasheet" "http://www.farnell.com/datasheets/2045956.pdf"
			(at 0 0 270)
			(layer "F.Fab")
			(hide yes)
			(effects
				(font
					(size 1.27 1.27)
					(thickness 0.15)
				)
			)
		)
		(property "Author" "Antmicro"
			(at -104.401 289.799 0)
			(layer "F.Fab")
			(hide yes)
			(effects
				(font
					(size 1 1)
					(thickness 0.15)
				)
			)
		)
		(property "License" "Apache-2.0"
			(at -104.401 289.799 0)
			(layer "F.Fab")
			(hide yes)
			(effects
				(font
					(size 1 1)
					(thickness 0.15)
				)
			)
		)
		(property "MPN" "KP-1608CGCK"
			(at -104.401 289.799 0)
			(layer "F.Fab")
			(hide yes)
			(effects
				(font
					(size 1 1)
					(thickness 0.15)
				)
			)
		)
		(property "Manufacturer" "Kingbright"
			(at -104.401 289.799 0)
			(layer "F.Fab")
			(hide yes)
			(effects
				(font
					(size 1 1)
					(thickness 0.15)
				)
			)
		)
		(sheetname "/Debug FTDI/")
		(sheetfile "debug-ftdi.kicad_sch")
		(attr smd)
		(fp_line
			(start -0.271 0.348)
			(end 0.269 0.348)
			(stroke
				(width 0.15)
				(type solid)
			)
			(layer "F.SilkS")
		)
		(fp_line
			(start 1.249 0.319)
			(end 1.249 -0.321)
			(stroke
				(width 0.15)
				(type solid)
			)
			(layer "F.SilkS")
		)
		(fp_line
			(start -0.107 -0.001)
			(end -0.291 -0.001)
			(stroke
				(width 0.1)
				(type solid)
			)
			(layer "F.SilkS")
		)
		(fp_line
			(start 0.092 -0.001)
			(end -0.107 0.198)
			(stroke
				(width 0.1)
				(type solid)
			)
			(layer "F.SilkS")
		)
		(fp_line
			(start 0.092 -0.001)
			(end 0.292 -0.001)
			(stroke
				(width 0.1)
				(type solid)
			)
			(layer "F.SilkS")
		)
		(fp_line
			(start -0.107 -0.201)
			(end -0.107 0.198)
			(stroke
				(width 0.1)
				(type solid)
			)
			(layer "F.SilkS")
		)
		(fp_line
			(start -0.107 -0.201)
			(end 0.092 -0.001)
			(stroke
				(width 0.1)
				(type solid)
			)
			(layer "F.SilkS")
		)
		(fp_line
			(start 0.092 -0.201)
			(end 0.092 0.198)
			(stroke
				(width 0.1)
				(type solid)
			)
			(layer "F.SilkS")
		)
		(fp_line
			(start -0.271 -0.349)
			(end 0.269 -0.349)
			(stroke
				(width 0.15)
				(type solid)
			)
			(layer "F.SilkS")
		)
		(fp_rect
			(start -1.2192 -0.6096)
			(end 1.27 0.6016)
			(stroke
				(width 0.05)
				(type solid)
			)
			(fill no)
			(layer "F.CrtYd")
		)
		(fp_line
			(start -0.202 0.201)
			(end 0.1 -0.001)
			(stroke
				(width 0.15)
				(type solid)
			)
			(layer "F.Fab")
		)
		(fp_line
			(start 0.198 0.201)
			(end 0.198 -0.101)
			(stroke
				(width 0.15)
				(type solid)
			)
			(layer "F.Fab")
		)
		(fp_line
			(start -0.849 0.025)
			(end -0.442 0.381)
			(stroke
				(width 0.15)
				(type solid)
			)
			(layer "F.Fab")
		)
		(fp_line
			(start -0.6 -0.001)
			(end -0.202 -0.001)
			(stroke
				(width 0.15)
				(type solid)
			)
			(layer "F.Fab")
		)
		(fp_line
			(start -0.202 -0.001)
			(end -0.202 0.201)
			(stroke
				(width 0.15)
				(type solid)
			)
			(layer "F.Fab")
		)
		(fp_line
			(start 0.1 -0.001)
			(end -0.202 -0.201)
			(stroke
				(width 0.15)
				(type solid)
			)
			(layer "F.Fab")
		)
		(fp_line
			(start 0.198 -0.001)
			(end 0.596 -0.001)
			(stroke
				(width 0.15)
				(type solid)
			)
			(layer "F.Fab")
		)
		(fp_line
			(start -0.202 -0.201)
			(end -0.202 -0.001)
			(stroke
				(width 0.15)
				(type solid)
			)
			(layer "F.Fab")
		)
		(fp_line
			(start 0.198 -0.201)
			(end 0.198 -0.101)
			(stroke
				(width 0.15)
				(type solid)
			)
			(layer "F.Fab")
		)
		(fp_rect
			(start -0.849 -0.401)
			(end 0.849 0.401)
			(stroke
				(width 0.15)
				(type solid)
			)
			(fill no)
			(layer "F.Fab")
		)
		(pad "1" smd rect
			(at -0.751 -0.001 90)
			(size 0.8 0.8)
			(layers "F.Cu" "F.Mask" "F.Paste")
			(net 315 "Net-(D10-Pad1)")
			(pinfunction "1")
			(pintype "passive")
		)
		(pad "2" smd rect
			(at 0.749 -0.001 90)
			(size 0.8 0.8)
			(layers "F.Cu" "F.Mask" "F.Paste")
			(net 1 "GND")
			(pinfunction "2")
			(pintype "passive")
		)
	)
	(footprint "antmicro-footprints:C_0402_1005Metric"
		(layer "F.Cu")
		(at 174.900501 191.076 -90)
		(descr "Capacitor SMD 0402")
		(tags "capacitor SMD 0402")
		(property "Reference" "C208"
			(at 0 -0.699 270)
			(layer "F.SilkS")
			(hide yes)
			(effects
				(font
					(size 0.7 0.7)
					(thickness 0.15)
				)
				(justify left bottom)
			)
		)
		(property "Value" "C_100n_0402"
			(at -1.022927 2.155213 270)
			(layer "F.Fab")
			(effects
				(font
					(size 0.7 0.7)
					(thickness 0.15)
				)
				(justify left bottom)
			)
		)
		(property "Datasheet" "https://www.murata.com/products/productdetail?partno=GRM155R61H104KE14%23"
			(at 0 0 270)
			(layer "F.Fab")
			(hide yes)
			(effects
				(font
					(size 1.27 1.27)
					(thickness 0.15)
				)
			)
		)
		(property "Author" "Antmicro"
			(at -16.175499 365.976501 0)
			(layer "F.Fab")
			(hide yes)
			(effects
				(font
					(size 1 1)
					(thickness 0.15)
				)
			)
		)
		(property "Dielectric" "X5R"
			(at -16.175499 365.976501 0)
			(layer "F.Fab")
			(hide yes)
			(effects
				(font
					(size 1 1)
					(thickness 0.15)
				)
			)
		)
		(property "License" "Apache-2.0"
			(at -16.175499 365.976501 0)
			(layer "F.Fab")
			(hide yes)
			(effects
				(font
					(size 1 1)
					(thickness 0.15)
				)
			)
		)
		(property "MPN" "GRM155R61H104KE14D"
			(at -16.175499 365.976501 0)
			(layer "F.Fab")
			(hide yes)
			(effects
				(font
					(size 1 1)
					(thickness 0.15)
				)
			)
		)
		(property "Manufacturer" "Murata"
			(at -16.175499 365.976501 0)
			(layer "F.Fab")
			(hide yes)
			(effects
				(font
					(size 1 1)
					(thickness 0.15)
				)
			)
		)
		(property "Val" "100n"
			(at -16.175499 365.976501 0)
			(layer "F.Fab")
			(hide yes)
			(effects
				(font
					(size 1 1)
					(thickness 0.15)
				)
			)
		)
		(property "Voltage" "50V"
			(at -16.175499 365.976501 0)
			(layer "F.Fab")
			(hide yes)
			(effects
				(font
					(size 1 1)
					(thickness 0.15)
				)
			)
		)
		(sheetname "/Supply/")
		(sheetfile "supply.kicad_sch")
		(attr smd)
		(fp_rect
			(start -0.9659 -0.481258)
			(end 0.9649 0.458742)
			(stroke
				(width 0.05)
				(type solid)
			)
			(fill no)
			(layer "F.CrtYd")
		)
		(fp_line
			(start -0.499 0.248)
			(end -0.499 -0.25)
			(stroke
				(width 0.15)
				(type solid)
			)
			(layer "F.Fab")
		)
		(fp_line
			(start 0.499 0.248)
			(end -0.499 0.248)
			(stroke
				(width 0.15)
				(type solid)
			)
			(layer "F.Fab")
		)
		(fp_line
			(start -0.499 -0.25)
			(end 0.499 -0.25)
			(stroke
				(width 0.15)
				(type solid)
			)
			(layer "F.Fab")
		)
		(fp_line
			(start 0.499 -0.25)
			(end 0.499 0.248)
			(stroke
				(width 0.15)
				(type solid)
			)
			(layer "F.Fab")
		)
		(pad "1" smd roundrect
			(at -0.484 0 270)
			(size 0.59 0.64)
			(layers "F.Cu" "F.Mask" "F.Paste")
			(roundrect_rratio 0.25)
			(net 66 "/Supply/1V0_SW")
			(pintype "passive")
		)
		(pad "2" smd roundrect
			(at 0.484 0 270)
			(size 0.59 0.64)
			(layers "F.Cu" "F.Mask" "F.Paste")
			(roundrect_rratio 0.25)
			(net 67 "/Supply/1V0_BS")
			(pintype "passive")
		)
	)
	(footprint "antmicro-footprints:R_0402_1005Metric"
		(layer "F.Cu")
		(at 196.481001 171.722 180)
		(descr "Resistor SMD 0402")
		(tags "resistor SMD 0402")
		(property "Reference" "R155"
			(at 3.731001 -0.328 180)
			(layer "F.SilkS")
			(effects
				(font
					(size 0.7 0.7)
					(thickness 0.15)
				)
				(justify left bottom)
			)
		)
		(property "Value" "R_0R_0402"
			(at -1.011843 1.772047 180)
			(layer "F.Fab")
			(effects
				(font
					(size 0.7 0.7)
					(thickness 0.15)
				)
				(justify left bottom)
			)
		)
		(property "Datasheet" "https://industrial.panasonic.com/cdbs/www-data/pdf/RDA0000/AOA0000C301.pdf"
			(at 0 0 180)
			(layer "F.Fab")
			(hide yes)
			(effects
				(font
					(size 1.27 1.27)
					(thickness 0.15)
				)
			)
		)
		(property "Author" "Antmicro"
			(at 392.962002 343.444 0)
			(layer "F.Fab")
			(hide yes)
			(effects
				(font
					(size 1 1)
					(thickness 0.15)
				)
			)
		)
		(property "Current" "1A"
			(at 392.962002 343.444 0)
			(layer "F.Fab")
			(hide yes)
			(effects
				(font
					(size 1 1)
					(thickness 0.15)
				)
			)
		)
		(property "License" "Apache-2.0"
			(at 392.962002 343.444 0)
			(layer "F.Fab")
			(hide yes)
			(effects
				(font
					(size 1 1)
					(thickness 0.15)
				)
			)
		)
		(property "MPN" "ERJ2GE0R00X"
			(at 392.962002 343.444 0)
			(layer "F.Fab")
			(hide yes)
			(effects
				(font
					(size 1 1)
					(thickness 0.15)
				)
			)
		)
		(property "Manufacturer" "Panasonic"
			(at 392.962002 343.444 0)
			(layer "F.Fab")
			(hide yes)
			(effects
				(font
					(size 1 1)
					(thickness 0.15)
				)
			)
		)
		(property "Tolerance" ""
			(at 392.962002 343.444 0)
			(layer "F.Fab")
			(hide yes)
			(effects
				(font
					(size 1 1)
					(thickness 0.15)
				)
			)
		)
		(property "Val" "0R"
			(at 392.962002 343.444 0)
			(layer "F.Fab")
			(hide yes)
			(effects
				(font
					(size 1 1)
					(thickness 0.15)
				)
			)
		)
		(sheetname "/Supply/")
		(sheetfile "supply.kicad_sch")
		(attr smd)
		(fp_rect
			(start -0.93 -0.47)
			(end 0.93 0.47)
			(stroke
				(width 0.05)
				(type solid)
			)
			(fill no)
			(layer "F.CrtYd")
		)
		(fp_rect
			(start -0.5 -0.25)
			(end 0.5 0.25)
			(stroke
				(width 0.15)
				(type solid)
			)
			(fill no)
			(layer "F.Fab")
		)
		(pad "1" smd roundrect
			(at -0.485 0 180)
			(size 0.59 0.64)
			(layers "F.Cu" "F.Mask" "F.Paste")
			(roundrect_rratio 0.25)
			(net 209 "/Supply/FB5")
			(pintype "passive")
		)
		(pad "2" smd roundrect
			(at 0.485 0 180)
			(size 0.59 0.64)
			(layers "F.Cu" "F.Mask" "F.Paste")
			(roundrect_rratio 0.25)
			(net 52 "/Supply/3V3_local")
			(pintype "passive")
		)
	)
	(footprint "antmicro-footprints:R_0402_1005Metric"
		(layer "F.Cu")
		(at 97.7 190 90)
		(descr "Resistor SMD 0402")
		(tags "resistor SMD 0402")
		(property "Reference" "R79"
			(at -1.122484 -0.772697 90)
			(layer "F.SilkS")
			(hide yes)
			(effects
				(font
					(size 0.7 0.7)
					(thickness 0.15)
				)
				(justify left bottom)
			)
		)
		(property "Value" "R_10k_0402"
			(at -1.011843 1.772047 90)
			(layer "F.Fab")
			(effects
				(font
					(size 0.7 0.7)
					(thickness 0.15)
				)
				(justify left bottom)
			)
		)
		(property "Datasheet" "https://www.bourns.com/docs/product-datasheets/cr.pdf"
			(at 0 0 90)
			(layer "F.Fab")
			(hide yes)
			(effects
				(font
					(size 1.27 1.27)
					(thickness 0.15)
				)
			)
		)
		(property "Author" "Antmicro"
			(at 287.7 92.3 0)
			(layer "F.Fab")
			(hide yes)
			(effects
				(font
					(size 1 1)
					(thickness 0.15)
				)
			)
		)
		(property "License" "Apache-2.0"
			(at 287.7 92.3 0)
			(layer "F.Fab")
			(hide yes)
			(effects
				(font
					(size 1 1)
					(thickness 0.15)
				)
			)
		)
		(property "MPN" "CR0402-FX-1002GLF"
			(at 287.7 92.3 0)
			(layer "F.Fab")
			(hide yes)
			(effects
				(font
					(size 1 1)
					(thickness 0.15)
				)
			)
		)
		(property "Manufacturer" "Bourns"
			(at 287.7 92.3 0)
			(layer "F.Fab")
			(hide yes)
			(effects
				(font
					(size 1 1)
					(thickness 0.15)
				)
			)
		)
		(property "Tolerance" "1%"
			(at 287.7 92.3 0)
			(layer "F.Fab")
			(hide yes)
			(effects
				(font
					(size 1 1)
					(thickness 0.15)
				)
			)
		)
		(property "Val" "10k"
			(at 287.7 92.3 0)
			(layer "F.Fab")
			(hide yes)
			(effects
				(font
					(size 1 1)
					(thickness 0.15)
				)
			)
		)
		(sheetname "/Debug FTDI/")
		(sheetfile "debug-ftdi.kicad_sch")
		(attr smd)
		(fp_rect
			(start -0.93 -0.47)
			(end 0.93 0.47)
			(stroke
				(width 0.05)
				(type solid)
			)
			(fill no)
			(layer "F.CrtYd")
		)
		(fp_rect
			(start -0.5 -0.25)
			(end 0.5 0.25)
			(stroke
				(width 0.15)
				(type solid)
			)
			(fill no)
			(layer "F.Fab")
		)
		(pad "1" smd roundrect
			(at -0.485 0 90)
			(size 0.59 0.64)
			(layers "F.Cu" "F.Mask" "F.Paste")
			(roundrect_rratio 0.25)
			(net 6 "/Debug FTDI/FTDI_3V3")
			(pintype "passive")
		)
		(pad "2" smd roundrect
			(at 0.485 0 90)
			(size 0.59 0.64)
			(layers "F.Cu" "F.Mask" "F.Paste")
			(roundrect_rratio 0.25)
			(net 668 "/Debug FTDI/FTDI_PWREN")
			(pintype "passive")
		)
	)
	(footprint "antmicro-footprints:R_0402_1005Metric"
		(layer "F.Cu")
		(at 99.8 136.07 -90)
		(descr "Resistor SMD 0402")
		(tags "resistor SMD 0402")
		(property "Reference" "R125"
			(at -1.122484 -0.772697 270)
			(layer "F.SilkS")
			(hide yes)
			(effects
				(font
					(size 0.7 0.7)
					(thickness 0.15)
				)
				(justify left bottom)
			)
		)
		(property "Value" "R_4k7_0402"
			(at -1.011843 1.772047 270)
			(layer "F.Fab")
			(effects
				(font
					(size 0.7 0.7)
					(thickness 0.15)
				)
				(justify left bottom)
			)
		)
		(property "Datasheet" "https://www.bourns.com/docs/product-datasheets/cr.pdf"
			(at 0 0 270)
			(layer "F.Fab")
			(hide yes)
			(effects
				(font
					(size 1.27 1.27)
					(thickness 0.15)
				)
			)
		)
		(property "Author" "Antmicro"
			(at -36.27 235.87 0)
			(layer "F.Fab")
			(hide yes)
			(effects
				(font
					(size 1 1)
					(thickness 0.15)
				)
			)
		)
		(property "License" "Apache-2.0"
			(at -36.27 235.87 0)
			(layer "F.Fab")
			(hide yes)
			(effects
				(font
					(size 1 1)
					(thickness 0.15)
				)
			)
		)
		(property "MPN" "CR0402-FX-4701GLF"
			(at -36.27 235.87 0)
			(layer "F.Fab")
			(hide yes)
			(effects
				(font
					(size 1 1)
					(thickness 0.15)
				)
			)
		)
		(property "Manufacturer" "Bourns"
			(at -36.27 235.87 0)
			(layer "F.Fab")
			(hide yes)
			(effects
				(font
					(size 1 1)
					(thickness 0.15)
				)
			)
		)
		(property "Tolerance" "1%"
			(at -36.27 235.87 0)
			(layer "F.Fab")
			(hide yes)
			(effects
				(font
					(size 1 1)
					(thickness 0.15)
				)
			)
		)
		(property "Val" "4k7"
			(at -36.27 235.87 0)
			(layer "F.Fab")
			(hide yes)
			(effects
				(font
					(size 1 1)
					(thickness 0.15)
				)
			)
		)
		(sheetname "/I^{2}C/")
		(sheetfile "i2c.kicad_sch")
		(attr smd)
		(fp_rect
			(start -0.93 -0.47)
			(end 0.93 0.47)
			(stroke
				(width 0.05)
				(type solid)
			)
			(fill no)
			(layer "F.CrtYd")
		)
		(fp_rect
			(start -0.5 -0.25)
			(end 0.5 0.25)
			(stroke
				(width 0.15)
				(type solid)
			)
			(fill no)
			(layer "F.Fab")
		)
		(pad "1" smd roundrect
			(at -0.485 0 270)
			(size 0.59 0.64)
			(layers "F.Cu" "F.Mask" "F.Paste")
			(roundrect_rratio 0.25)
			(net 267 "VDDSPD")
			(pintype "passive")
		)
		(pad "2" smd roundrect
			(at 0.485 0 270)
			(size 0.59 0.64)
			(layers "F.Cu" "F.Mask" "F.Paste")
			(roundrect_rratio 0.25)
			(net 50 "/DDR5 SODIMM/DDR.SCL")
			(pintype "passive")
		)
	)
	(footprint "antmicro-footprints:R_0402_1005Metric"
		(layer "F.Cu")
		(at 177.100501 197.776 90)
		(descr "Resistor SMD 0402")
		(tags "resistor SMD 0402")
		(property "Reference" "R186"
			(at -3.624 0.299499 90)
			(layer "F.SilkS")
			(effects
				(font
					(size 0.7 0.7)
					(thickness 0.15)
				)
				(justify left bottom)
			)
		)
		(property "Value" "R_205k_0402"
			(at -1.011843 1.772047 90)
			(layer "F.Fab")
			(effects
				(font
					(size 0.7 0.7)
					(thickness 0.15)
				)
				(justify left bottom)
			)
		)
		(property "Datasheet" "https://www.bourns.com/docs/product-datasheets/cr.pdf"
			(at 0 0 90)
			(layer "F.Fab")
			(hide yes)
			(effects
				(font
					(size 1.27 1.27)
					(thickness 0.15)
				)
			)
		)
		(property "Author" "Antmicro"
			(at 374.876501 20.675499 0)
			(layer "F.Fab")
			(hide yes)
			(effects
				(font
					(size 1 1)
					(thickness 0.15)
				)
			)
		)
		(property "License" "Apache-2.0"
			(at 374.876501 20.675499 0)
			(layer "F.Fab")
			(hide yes)
			(effects
				(font
					(size 1 1)
					(thickness 0.15)
				)
			)
		)
		(property "MPN" "CR0402-FX-2053GLF"
			(at 374.876501 20.675499 0)
			(layer "F.Fab")
			(hide yes)
			(effects
				(font
					(size 1 1)
					(thickness 0.15)
				)
			)
		)
		(property "Manufacturer" "Bourns"
			(at 374.876501 20.675499 0)
			(layer "F.Fab")
			(hide yes)
			(effects
				(font
					(size 1 1)
					(thickness 0.15)
				)
			)
		)
		(property "Tolerance" "1%"
			(at 374.876501 20.675499 0)
			(layer "F.Fab")
			(hide yes)
			(effects
				(font
					(size 1 1)
					(thickness 0.15)
				)
			)
		)
		(property "Val" "205k"
			(at 374.876501 20.675499 0)
			(layer "F.Fab")
			(hide yes)
			(effects
				(font
					(size 1 1)
					(thickness 0.15)
				)
			)
		)
		(sheetname "/Supply/")
		(sheetfile "supply.kicad_sch")
		(attr smd)
		(fp_rect
			(start -0.93 -0.47)
			(end 0.93 0.47)
			(stroke
				(width 0.05)
				(type solid)
			)
			(fill no)
			(layer "F.CrtYd")
		)
		(fp_rect
			(start -0.5 -0.25)
			(end 0.5 0.25)
			(stroke
				(width 0.15)
				(type solid)
			)
			(fill no)
			(layer "F.Fab")
		)
		(pad "1" smd roundrect
			(at -0.485 0 90)
			(size 0.59 0.64)
			(layers "F.Cu" "F.Mask" "F.Paste")
			(roundrect_rratio 0.25)
			(net 1 "GND")
			(pintype "passive")
		)
		(pad "2" smd roundrect
			(at 0.485 0 90)
			(size 0.59 0.64)
			(layers "F.Cu" "F.Mask" "F.Paste")
			(roundrect_rratio 0.25)
			(net 303 "Net-(C221-Pad1)")
			(pintype "passive")
		)
	)
	(footprint "antmicro-footprints:C_0603_1608Metric"
		(layer "F.Cu")
		(at 191.245501 185.523 -90)
		(descr "Capacitor SMD 0603")
		(tags "capacitor 0603")
		(property "Reference" "C186"
			(at -1.42757 -1.000252 270)
			(layer "F.SilkS")
			(hide yes)
			(effects
				(font
					(size 0.7 0.7)
					(thickness 0.15)
				)
				(justify left bottom)
			)
		)
		(property "Value" "C_22u_0603"
			(at -1.42757 1.770288 270)
			(layer "F.Fab")
			(effects
				(font
					(size 0.7 0.7)
					(thickness 0.15)
				)
				(justify left bottom)
			)
		)
		(property "Datasheet" "https://www.murata.com/products/productdetail?partno=GRM188R60J226MEA0%23"
			(at 0 0 270)
			(layer "F.Fab")
			(hide yes)
			(effects
				(font
					(size 1.27 1.27)
					(thickness 0.15)
				)
			)
		)
		(property "Author" "Antmicro"
			(at 5.722501 376.768501 0)
			(layer "F.Fab")
			(hide yes)
			(effects
				(font
					(size 1 1)
					(thickness 0.15)
				)
			)
		)
		(property "Dielectric" ""
			(at 5.722501 376.768501 0)
			(layer "F.Fab")
			(hide yes)
			(effects
				(font
					(size 1 1)
					(thickness 0.15)
				)
			)
		)
		(property "License" "Apache-2.0"
			(at 5.722501 376.768501 0)
			(layer "F.Fab")
			(hide yes)
			(effects
				(font
					(size 1 1)
					(thickness 0.15)
				)
			)
		)
		(property "MPN" "GRM188R60J226MEA0D"
			(at 5.722501 376.768501 0)
			(layer "F.Fab")
			(hide yes)
			(effects
				(font
					(size 1 1)
					(thickness 0.15)
				)
			)
		)
		(property "Manufacturer" "Murata"
			(at 5.722501 376.768501 0)
			(layer "F.Fab")
			(hide yes)
			(effects
				(font
					(size 1 1)
					(thickness 0.15)
				)
			)
		)
		(property "Val" "22u"
			(at 5.722501 376.768501 0)
			(layer "F.Fab")
			(hide yes)
			(effects
				(font
					(size 1 1)
					(thickness 0.15)
				)
			)
		)
		(property "Voltage" ""
			(at 5.722501 376.768501 0)
			(layer "F.Fab")
			(hide yes)
			(effects
				(font
					(size 1 1)
					(thickness 0.15)
				)
			)
		)
		(sheetname "/Supply/")
		(sheetfile "supply.kicad_sch")
		(attr smd)
		(fp_line
			(start -0.3 0.3)
			(end 0.3 0.3)
			(stroke
				(width 0.15)
				(type solid)
			)
			(layer "F.SilkS")
		)
		(fp_line
			(start -0.3 -0.3)
			(end 0.3 -0.3)
			(stroke
				(width 0.15)
				(type solid)
			)
			(layer "F.SilkS")
		)
		(fp_rect
			(start -1.24 -0.7)
			(end 1.24 0.7)
			(stroke
				(width 0.05)
				(type solid)
			)
			(fill no)
			(layer "F.CrtYd")
		)
		(fp_rect
			(start -0.8 -0.4)
			(end 0.8 0.4)
			(stroke
				(width 0.15)
				(type solid)
			)
			(fill no)
			(layer "F.Fab")
		)
		(pad "1" smd roundrect
			(at -0.7 0 270)
			(size 0.6 0.8)
			(layers "F.Cu" "F.Mask" "F.Paste")
			(roundrect_rratio 0.2)
			(net 1 "GND")
			(pintype "passive")
		)
		(pad "2" smd roundrect
			(at 0.7 0 270)
			(size 0.6 0.8)
			(layers "F.Cu" "F.Mask" "F.Paste")
			(roundrect_rratio 0.2)
			(net 42 "/Supply/MGTAVCC_local")
			(pintype "passive")
		)
	)
	(footprint "antmicro-footprints:C_0603_1608Metric"
		(layer "F.Cu")
		(at 192.668501 168.072 -90)
		(descr "Capacitor SMD 0603")
		(tags "capacitor 0603")
		(property "Reference" "C190"
			(at -1.42757 -1.000252 270)
			(layer "F.SilkS")
			(hide yes)
			(effects
				(font
					(size 0.7 0.7)
					(thickness 0.15)
				)
				(justify left bottom)
			)
		)
		(property "Value" "C_22u_0603"
			(at -1.42757 1.770288 270)
			(layer "F.Fab")
			(effects
				(font
					(size 0.7 0.7)
					(thickness 0.15)
				)
				(justify left bottom)
			)
		)
		(property "Datasheet" "https://www.murata.com/products/productdetail?partno=GRM188R60J226MEA0%23"
			(at 0 0 270)
			(layer "F.Fab")
			(hide yes)
			(effects
				(font
					(size 1.27 1.27)
					(thickness 0.15)
				)
			)
		)
		(property "Author" "Antmicro"
			(at 24.596501 360.740501 0)
			(layer "F.Fab")
			(hide yes)
			(effects
				(font
					(size 1 1)
					(thickness 0.15)
				)
			)
		)
		(property "Dielectric" ""
			(at 24.596501 360.740501 0)
			(layer "F.Fab")
			(hide yes)
			(effects
				(font
					(size 1 1)
					(thickness 0.15)
				)
			)
		)
		(property "License" "Apache-2.0"
			(at 24.596501 360.740501 0)
			(layer "F.Fab")
			(hide yes)
			(effects
				(font
					(size 1 1)
					(thickness 0.15)
				)
			)
		)
		(property "MPN" "GRM188R60J226MEA0D"
			(at 24.596501 360.740501 0)
			(layer "F.Fab")
			(hide yes)
			(effects
				(font
					(size 1 1)
					(thickness 0.15)
				)
			)
		)
		(property "Manufacturer" "Murata"
			(at 24.596501 360.740501 0)
			(layer "F.Fab")
			(hide yes)
			(effects
				(font
					(size 1 1)
					(thickness 0.15)
				)
			)
		)
		(property "Val" "22u"
			(at 24.596501 360.740501 0)
			(layer "F.Fab")
			(hide yes)
			(effects
				(font
					(size 1 1)
					(thickness 0.15)
				)
			)
		)
		(property "Voltage" ""
			(at 24.596501 360.740501 0)
			(layer "F.Fab")
			(hide yes)
			(effects
				(font
					(size 1 1)
					(thickness 0.15)
				)
			)
		)
		(sheetname "/Supply/")
		(sheetfile "supply.kicad_sch")
		(attr smd)
		(fp_line
			(start -0.3 0.3)
			(end 0.3 0.3)
			(stroke
				(width 0.15)
				(type solid)
			)
			(layer "F.SilkS")
		)
		(fp_line
			(start -0.3 -0.3)
			(end 0.3 -0.3)
			(stroke
				(width 0.15)
				(type solid)
			)
			(layer "F.SilkS")
		)
		(fp_rect
			(start -1.24 -0.7)
			(end 1.24 0.7)
			(stroke
				(width 0.05)
				(type solid)
			)
			(fill no)
			(layer "F.CrtYd")
		)
		(fp_rect
			(start -0.8 -0.4)
			(end 0.8 0.4)
			(stroke
				(width 0.15)
				(type solid)
			)
			(fill no)
			(layer "F.Fab")
		)
		(pad "1" smd roundrect
			(at -0.7 0 270)
			(size 0.6 0.8)
			(layers "F.Cu" "F.Mask" "F.Paste")
			(roundrect_rratio 0.2)
			(net 1 "GND")
			(pintype "passive")
		)
		(pad "2" smd roundrect
			(at 0.7 0 270)
			(size 0.6 0.8)
			(layers "F.Cu" "F.Mask" "F.Paste")
			(roundrect_rratio 0.2)
			(net 52 "/Supply/3V3_local")
			(pintype "passive")
		)
	)
	(footprint "antmicro-footprints:R_0402_1005Metric"
		(layer "F.Cu")
		(at 177.9 180.215)
		(descr "Resistor SMD 0402")
		(tags "resistor SMD 0402")
		(property "Reference" "R138"
			(at -1.122484 -0.772697 0)
			(layer "F.SilkS")
			(hide yes)
			(effects
				(font
					(size 0.7 0.7)
					(thickness 0.15)
				)
				(justify left bottom)
			)
		)
		(property "Value" "R_0R_0402"
			(at -1.011843 1.772047 0)
			(layer "F.Fab")
			(effects
				(font
					(size 0.7 0.7)
					(thickness 0.15)
				)
				(justify left bottom)
			)
		)
		(property "Datasheet" "https://industrial.panasonic.com/cdbs/www-data/pdf/RDA0000/AOA0000C301.pdf"
			(at 0 0 0)
			(layer "F.Fab")
			(hide yes)
			(effects
				(font
					(size 1.27 1.27)
					(thickness 0.15)
				)
			)
		)
		(property "Author" "Antmicro"
			(at 0 0 0)
			(layer "F.Fab")
			(hide yes)
			(effects
				(font
					(size 1 1)
					(thickness 0.15)
				)
			)
		)
		(property "Current" "1A"
			(at 0 0 0)
			(layer "F.Fab")
			(hide yes)
			(effects
				(font
					(size 1 1)
					(thickness 0.15)
				)
			)
		)
		(property "License" "Apache-2.0"
			(at 0 0 0)
			(layer "F.Fab")
			(hide yes)
			(effects
				(font
					(size 1 1)
					(thickness 0.15)
				)
			)
		)
		(property "MPN" "ERJ2GE0R00X"
			(at 0 0 0)
			(layer "F.Fab")
			(hide yes)
			(effects
				(font
					(size 1 1)
					(thickness 0.15)
				)
			)
		)
		(property "Manufacturer" "Panasonic"
			(at 0 0 0)
			(layer "F.Fab")
			(hide yes)
			(effects
				(font
					(size 1 1)
					(thickness 0.15)
				)
			)
		)
		(property "Tolerance" ""
			(at 0 0 0)
			(layer "F.Fab")
			(hide yes)
			(effects
				(font
					(size 1 1)
					(thickness 0.15)
				)
			)
		)
		(property "Val" "0R"
			(at 0 0 0)
			(layer "F.Fab")
			(hide yes)
			(effects
				(font
					(size 1 1)
					(thickness 0.15)
				)
			)
		)
		(sheetname "/Supply/")
		(sheetfile "supply.kicad_sch")
		(attr smd)
		(fp_rect
			(start -0.93 -0.47)
			(end 0.93 0.47)
			(stroke
				(width 0.05)
				(type solid)
			)
			(fill no)
			(layer "F.CrtYd")
		)
		(fp_rect
			(start -0.5 -0.25)
			(end 0.5 0.25)
			(stroke
				(width 0.15)
				(type solid)
			)
			(fill no)
			(layer "F.Fab")
		)
		(pad "1" smd roundrect
			(at -0.485 0)
			(size 0.59 0.64)
			(layers "F.Cu" "F.Mask" "F.Paste")
			(roundrect_rratio 0.25)
			(net 240 "POWER")
			(pintype "passive")
		)
		(pad "2" smd roundrect
			(at 0.485 0)
			(size 0.59 0.64)
			(layers "F.Cu" "F.Mask" "F.Paste")
			(roundrect_rratio 0.25)
			(net 282 "/Supply/PG3")
			(pintype "passive")
		)
	)
	(footprint "antmicro-footprints:R_0402_1005Metric"
		(layer "F.Cu")
		(at 176.619501 194.214502)
		(descr "Resistor SMD 0402")
		(tags "resistor SMD 0402")
		(property "Reference" "R181"
			(at -1.069501 1.385498 0)
			(layer "F.SilkS")
			(effects
				(font
					(size 0.7 0.7)
					(thickness 0.15)
				)
				(justify left bottom)
			)
		)
		(property "Value" "R_10k_0402"
			(at -1.011843 1.772047 0)
			(layer "F.Fab")
			(effects
				(font
					(size 0.7 0.7)
					(thickness 0.15)
				)
				(justify left bottom)
			)
		)
		(property "Datasheet" "https://www.bourns.com/docs/product-datasheets/cr.pdf"
			(at 0 0 0)
			(layer "F.Fab")
			(hide yes)
			(effects
				(font
					(size 1.27 1.27)
					(thickness 0.15)
				)
			)
		)
		(property "Author" "Antmicro"
			(at 0 0 0)
			(layer "F.Fab")
			(hide yes)
			(effects
				(font
					(size 1 1)
					(thickness 0.15)
				)
			)
		)
		(property "License" "Apache-2.0"
			(at 0 0 0)
			(layer "F.Fab")
			(hide yes)
			(effects
				(font
					(size 1 1)
					(thickness 0.15)
				)
			)
		)
		(property "MPN" "CR0402-FX-1002GLF"
			(at 0 0 0)
			(layer "F.Fab")
			(hide yes)
			(effects
				(font
					(size 1 1)
					(thickness 0.15)
				)
			)
		)
		(property "Manufacturer" "Bourns"
			(at 0 0 0)
			(layer "F.Fab")
			(hide yes)
			(effects
				(font
					(size 1 1)
					(thickness 0.15)
				)
			)
		)
		(property "Tolerance" "1%"
			(at 0 0 0)
			(layer "F.Fab")
			(hide yes)
			(effects
				(font
					(size 1 1)
					(thickness 0.15)
				)
			)
		)
		(property "Val" "10k"
			(at 0 0 0)
			(layer "F.Fab")
			(hide yes)
			(effects
				(font
					(size 1 1)
					(thickness 0.15)
				)
			)
		)
		(sheetname "/Supply/")
		(sheetfile "supply.kicad_sch")
		(attr smd)
		(fp_rect
			(start -0.93 -0.47)
			(end 0.93 0.47)
			(stroke
				(width 0.05)
				(type solid)
			)
			(fill no)
			(layer "F.CrtYd")
		)
		(fp_rect
			(start -0.5 -0.25)
			(end 0.5 0.25)
			(stroke
				(width 0.15)
				(type solid)
			)
			(fill no)
			(layer "F.Fab")
		)
		(pad "1" smd roundrect
			(at -0.485 0)
			(size 0.59 0.64)
			(layers "F.Cu" "F.Mask" "F.Paste")
			(roundrect_rratio 0.25)
			(net 225 "/Supply/1V0_FB")
			(pintype "passive")
		)
		(pad "2" smd roundrect
			(at 0.485 0)
			(size 0.59 0.64)
			(layers "F.Cu" "F.Mask" "F.Paste")
			(roundrect_rratio 0.25)
			(net 303 "Net-(C221-Pad1)")
			(pintype "passive")
		)
	)
	(footprint "antmicro-footprints:NetTie-2_SMD_Pad0.127mm"
		(layer "F.Cu")
		(at 198.675 177.174 180)
		(descr "Net tie, 2 pin, 0.127mm  SMD pads")
		(tags "net tie")
		(property "Reference" "NT11"
			(at -0.128 -1.345 180)
			(layer "F.SilkS")
			(hide yes)
			(effects
				(font
					(size 0.7 0.7)
					(thickness 0.15)
				)
				(justify left bottom)
			)
		)
		(property "Value" "Net-Tie_P0.127mm"
			(at 0 1.199 180)
			(layer "F.Fab")
			(effects
				(font
					(size 0.7 0.7)
					(thickness 0.15)
				)
				(justify left bottom)
			)
		)
		(property "Author" "Antmicro"
			(at 397.35 354.348 0)
			(layer "F.Fab")
			(hide yes)
			(effects
				(font
					(size 1 1)
					(thickness 0.15)
				)
			)
		)
		(property "License" "Apache-2.0"
			(at 397.35 354.348 0)
			(layer "F.Fab")
			(hide yes)
			(effects
				(font
					(size 1 1)
					(thickness 0.15)
				)
			)
		)
		(property "MPN" ""
			(at 397.35 354.348 0)
			(layer "F.Fab")
			(hide yes)
			(effects
				(font
					(size 1 1)
					(thickness 0.15)
				)
			)
		)
		(property "Manufacturer" ""
			(at 397.35 354.348 0)
			(layer "F.Fab")
			(hide yes)
			(effects
				(font
					(size 1 1)
					(thickness 0.15)
				)
			)
		)
		(property ki_fp_filters "Net*Tie*")
		(sheetname "/Supply/")
		(sheetfile "supply.kicad_sch")
		(attr smd exclude_from_pos_files exclude_from_bom)
		(net_tie_pad_groups "1, 2")
		(fp_poly
			(pts
				(xy -0.0635 -0.0635) (xy 0.0625 -0.0635) (xy 0.0625 0.0635) (xy -0.0635 0.0635)
			)
			(stroke
				(width 0)
				(type solid)
			)
			(fill yes)
			(layer "F.Cu")
		)
		(pad "1" smd roundrect
			(at -0.127 0)
			(size 0.127 0.127)
			(layers "F.Cu")
			(roundrect_rratio 0.5)
			(chamfer_ratio 0)
			(chamfer top_left bottom_left)
			(net 237 "/Supply/sp_SEN_-")
			(pinfunction "1")
			(pintype "passive")
		)
		(pad "2" smd roundrect
			(at 0.126 0 180)
			(size 0.127 0.127)
			(layers "F.Cu")
			(roundrect_rratio 0.5)
			(chamfer_ratio 0)
			(chamfer top_left bottom_left)
			(net 239 "/Supply/spare")
			(pinfunction "2")
			(pintype "passive")
		)
	)
	(footprint "antmicro-footprints:TP_1206_SMD_RCW-0C"
		(layer "F.Cu")
		(at 204.789501 173.401 90)
		(property "Reference" "TP21"
			(at -2.29 -1.4 90)
			(layer "F.SilkS")
			(hide yes)
			(effects
				(font
					(size 0.7 0.7)
					(thickness 0.15)
				)
				(justify left bottom)
			)
		)
		(property "Value" "TP_1206_SMD_RCW-0C"
			(at -4.68 2.25 90)
			(layer "F.Fab")
			(effects
				(font
					(size 0.7 0.7)
					(thickness 0.15)
				)
				(justify left bottom)
			)
		)
		(property "Datasheet" "https://www.te.com/commerce/DocumentDelivery/DDEController?Action=srchrtrv&DocNm=1773266&DocType=DS&DocLang=English"
			(at 0 0 90)
			(layer "F.Fab")
			(hide yes)
			(effects
				(font
					(size 1.27 1.27)
					(thickness 0.15)
				)
			)
		)
		(property "Author" "Antmicro"
			(at 378.190501 -31.388501 0)
			(layer "F.Fab")
			(hide yes)
			(effects
				(font
					(size 1 1)
					(thickness 0.15)
				)
			)
		)
		(property "License" "Apache-2.0"
			(at 378.190501 -31.388501 0)
			(layer "F.Fab")
			(hide yes)
			(effects
				(font
					(size 1 1)
					(thickness 0.15)
				)
			)
		)
		(property "MPN" "RCW-0C"
			(at 378.190501 -31.388501 0)
			(layer "F.Fab")
			(hide yes)
			(effects
				(font
					(size 1 1)
					(thickness 0.15)
				)
			)
		)
		(property "Manufacturer" "TE Connectivity"
			(at 378.190501 -31.388501 0)
			(layer "F.Fab")
			(hide yes)
			(effects
				(font
					(size 1 1)
					(thickness 0.15)
				)
			)
		)
		(sheetname "/Supply/")
		(sheetfile "supply.kicad_sch")
		(attr smd)
		(fp_line
			(start 1.78 -0.981)
			(end 1.281 -0.981)
			(stroke
				(width 0.15)
				(type solid)
			)
			(layer "F.SilkS")
		)
		(fp_line
			(start 1.78 -0.981)
			(end 1.78 -0.479)
			(stroke
				(width 0.15)
				(type solid)
			)
			(layer "F.SilkS")
		)
		(fp_line
			(start -1.779 -0.981)
			(end -1.279 -0.981)
			(stroke
				(width 0.15)
				(type solid)
			)
			(layer "F.SilkS")
		)
		(fp_line
			(start -1.779 -0.981)
			(end -1.779 -0.479)
			(stroke
				(width 0.15)
				(type solid)
			)
			(layer "F.SilkS")
		)
		(fp_line
			(start -1.779 0.482)
			(end -1.779 0.98)
			(stroke
				(width 0.15)
				(type solid)
			)
			(layer "F.SilkS")
		)
		(fp_line
			(start -1.779 0.98)
			(end -1.279 0.98)
			(stroke
				(width 0.15)
				(type solid)
			)
			(layer "F.SilkS")
		)
		(fp_line
			(start 1.78 0.982)
			(end 1.78 0.482)
			(stroke
				(width 0.15)
				(type solid)
			)
			(layer "F.SilkS")
		)
		(fp_line
			(start 1.78 0.982)
			(end 1.281 0.982)
			(stroke
				(width 0.15)
				(type solid)
			)
			(layer "F.SilkS")
		)
		(fp_rect
			(start -2.101 -1.314)
			(end 2.1 1.312)
			(stroke
				(width 0.05)
				(type solid)
			)
			(fill no)
			(layer "F.CrtYd")
		)
		(fp_rect
			(start -1.601 -0.814)
			(end 1.6 0.812)
			(stroke
				(width 0.15)
				(type solid)
			)
			(fill no)
			(layer "F.Fab")
		)
		(pad "1" smd rect
			(at 0 0 90)
			(size 3.4 1.8)
			(layers "F.Cu" "F.Mask" "F.Paste")
			(net 1 "GND")
			(pinfunction "1")
			(pintype "passive")
		)
	)
	(footprint "antmicro-footprints:SOD-523"
		(layer "F.Cu")
		(at 104.650001 184.485 180)
		(property "Reference" "D15"
			(at 0 -0.75 180)
			(layer "F.SilkS")
			(hide yes)
			(effects
				(font
					(size 0.7 0.7)
					(thickness 0.15)
				)
				(justify left bottom)
			)
		)
		(property "Value" "BAT54-02V-G3-08"
			(at 0 1.499 180)
			(layer "F.Fab")
			(effects
				(font
					(size 0.7 0.7)
					(thickness 0.15)
				)
				(justify left bottom)
			)
		)
		(property "Datasheet" "https://www.vishay.com/docs/85633/bat5402v.pdf"
			(at 0 0 180)
			(layer "F.Fab")
			(hide yes)
			(effects
				(font
					(size 1.27 1.27)
					(thickness 0.15)
				)
			)
		)
		(property "Description" "Small Signal Schottky Diode, Single, 30 V, 200 mA, 800 mV, 600 mA, 125 °C"
			(at 0 0 180)
			(layer "F.Fab")
			(hide yes)
			(effects
				(font
					(size 1.27 1.27)
					(thickness 0.15)
				)
			)
		)
		(property "Author" "Antmicro"
			(at 209.300002 368.97 0)
			(layer "F.Fab")
			(hide yes)
			(effects
				(font
					(size 1 1)
					(thickness 0.15)
				)
			)
		)
		(property "License" "Apache-2.0"
			(at 209.300002 368.97 0)
			(layer "F.Fab")
			(hide yes)
			(effects
				(font
					(size 1 1)
					(thickness 0.15)
				)
			)
		)
		(property "MPN" "BAT54-02V-G3-08"
			(at 209.300002 368.97 0)
			(layer "F.Fab")
			(hide yes)
			(effects
				(font
					(size 1 1)
					(thickness 0.15)
				)
			)
		)
		(property "Manufacturer" "Vishay"
			(at 209.300002 368.97 0)
			(layer "F.Fab")
			(hide yes)
			(effects
				(font
					(size 1 1)
					(thickness 0.15)
				)
			)
		)
		(sheetname "/Debug FTDI/")
		(sheetfile "debug-ftdi.kicad_sch")
		(attr smd)
		(fp_line
			(start -0.35 -0.5)
			(end -0.35 0.5)
			(stroke
				(width 0.15)
				(type solid)
			)
			(layer "F.SilkS")
		)
		(fp_rect
			(start -1 -0.6)
			(end 1 0.6)
			(stroke
				(width 0.05)
				(type solid)
			)
			(fill no)
			(layer "F.CrtYd")
		)
		(fp_line
			(start 0.65 -0.425)
			(end 0.65 0.423)
			(stroke
				(width 0.15)
				(type solid)
			)
			(layer "F.Fab")
		)
		(fp_line
			(start -0.35 -0.4)
			(end -0.35 0.4)
			(stroke
				(width 0.15)
				(type solid)
			)
			(layer "F.Fab")
		)
		(fp_line
			(start -0.652 0.423)
			(end 0.65 0.423)
			(stroke
				(width 0.15)
				(type solid)
			)
			(layer "F.Fab")
		)
		(fp_line
			(start -0.652 0.423)
			(end -0.652 -0.425)
			(stroke
				(width 0.15)
				(type solid)
			)
			(layer "F.Fab")
		)
		(fp_line
			(start -0.652 -0.425)
			(end 0.65 -0.425)
			(stroke
				(width 0.15)
				(type solid)
			)
			(layer "F.Fab")
		)
		(pad "1" smd roundrect
			(at -0.701 0 180)
			(size 0.5 0.6)
			(layers "F.Cu" "F.Mask" "F.Paste")
			(roundrect_rratio 0.25)
			(net 37 "/Debug FTDI/FTDI_SDA_OUT")
			(pinfunction "C")
			(pintype "passive")
		)
		(pad "2" smd roundrect
			(at 0.699 0 180)
			(size 0.5 0.6)
			(layers "F.Cu" "F.Mask" "F.Paste")
			(roundrect_rratio 0.25)
			(net 43 "/Debug FTDI/FTDI_SDA_IN")
			(pinfunction "A")
			(pintype "passive")
		)
	)
	(footprint "antmicro-footprints:SC70-3"
		(layer "F.Cu")
		(at 102.100501 118.176 180)
		(property "Reference" "Q11"
			(at 0 -1.6 180)
			(layer "F.SilkS")
			(hide yes)
			(effects
				(font
					(size 0.7 0.7)
					(thickness 0.15)
				)
				(justify left bottom)
			)
		)
		(property "Value" "BSS138PW,115"
			(at 0 2.3 180)
			(layer "F.Fab")
			(effects
				(font
					(size 0.7 0.7)
					(thickness 0.15)
				)
				(justify left bottom)
			)
		)
		(property "Datasheet" "https://assets.nexperia.com/documents/data-sheet/BSS138PW.pdf"
			(at 0 0 180)
			(layer "F.Fab")
			(hide yes)
			(effects
				(font
					(size 1.27 1.27)
					(thickness 0.15)
				)
			)
		)
		(property "Description" "Power MOSFET, N Channel, 60 V, 320 mA, 0.9 ohm, SOT-323, Surface Mount"
			(at 0 0 180)
			(layer "F.Fab")
			(hide yes)
			(effects
				(font
					(size 1.27 1.27)
					(thickness 0.15)
				)
			)
		)
		(property "Author" "Antmicro"
			(at 204.201002 236.352 0)
			(layer "F.Fab")
			(hide yes)
			(effects
				(font
					(size 1 1)
					(thickness 0.15)
				)
			)
		)
		(property "License" "Apache-2.0"
			(at 204.201002 236.352 0)
			(layer "F.Fab")
			(hide yes)
			(effects
				(font
					(size 1 1)
					(thickness 0.15)
				)
			)
		)
		(property "MPN" "BSS138PW,115"
			(at 204.201002 236.352 0)
			(layer "F.Fab")
			(hide yes)
			(effects
				(font
					(size 1 1)
					(thickness 0.15)
				)
			)
		)
		(property "Manufacturer" "Nexperia"
			(at 204.201002 236.352 0)
			(layer "F.Fab")
			(hide yes)
			(effects
				(font
					(size 1 1)
					(thickness 0.15)
				)
			)
		)
		(sheetname "/DDR5 SODIMM/")
		(sheetfile "ddr5-sodimm.kicad_sch")
		(attr smd)
		(fp_line
			(start 0.627 0.6)
			(end 0.627 1.001)
			(stroke
				(width 0.15)
				(type solid)
			)
			(layer "F.SilkS")
		)
		(fp_line
			(start 0.627 -0.6)
			(end 0.627 -0.999)
			(stroke
				(width 0.15)
				(type solid)
			)
			(layer "F.SilkS")
		)
		(fp_line
			(start -0.3 1)
			(end 0.627 1.001)
			(stroke
				(width 0.15)
				(type solid)
			)
			(layer "F.SilkS")
		)
		(fp_line
			(start -0.3 -1)
			(end 0.627 -0.999)
			(stroke
				(width 0.15)
				(type solid)
			)
			(layer "F.SilkS")
		)
		(fp_line
			(start 1.4 0.4)
			(end 0.9 0.4)
			(stroke
				(width 0.05)
				(type solid)
			)
			(layer "F.CrtYd")
		)
		(fp_line
			(start 1.4 -0.4)
			(end 1.4 0.4)
			(stroke
				(width 0.05)
				(type solid)
			)
			(layer "F.CrtYd")
		)
		(fp_line
			(start 0.9 1.3)
			(end -0.9 1.3)
			(stroke
				(width 0.05)
				(type solid)
			)
			(layer "F.CrtYd")
		)
		(fp_line
			(start 0.9 0.4)
			(end 0.9 1.3)
			(stroke
				(width 0.05)
				(type solid)
			)
			(layer "F.CrtYd")
		)
		(fp_line
			(start 0.9 -0.4)
			(end 1.4 -0.4)
			(stroke
				(width 0.05)
				(type solid)
			)
			(layer "F.CrtYd")
		)
		(fp_line
			(start 0.9 -1.3)
			(end 0.9 -0.4)
			(stroke
				(width 0.05)
				(type solid)
			)
			(layer "F.CrtYd")
		)
		(fp_line
			(start -0.9 1.3)
			(end -0.9 1)
			(stroke
				(width 0.05)
				(type solid)
			)
			(layer "F.CrtYd")
		)
		(fp_line
			(start -0.9 1)
			(end -1.4 1)
			(stroke
				(width 0.05)
				(type solid)
			)
			(layer "F.CrtYd")
		)
		(fp_line
			(start -0.9 -1)
			(end -1.4 -1)
			(stroke
				(width 0.05)
				(type solid)
			)
			(layer "F.CrtYd")
		)
		(fp_line
			(start -0.9 -1.3)
			(end 0.9 -1.3)
			(stroke
				(width 0.05)
				(type solid)
			)
			(layer "F.CrtYd")
		)
		(fp_line
			(start -0.9 -1.3)
			(end -0.9 -1)
			(stroke
				(width 0.05)
				(type solid)
			)
			(layer "F.CrtYd")
		)
		(fp_line
			(start -1.4 1)
			(end -1.4 -1)
			(stroke
				(width 0.05)
				(type solid)
			)
			(layer "F.CrtYd")
		)
		(fp_rect
			(start -0.623 -0.999)
			(end 0.627 1.001)
			(stroke
				(width 0.15)
				(type solid)
			)
			(fill no)
			(layer "F.Fab")
		)
		(pad "1" smd rect
			(at -1.051 -0.65 270)
			(size 0.6 0.6)
			(layers "F.Cu" "F.Mask" "F.Paste")
			(net 236 "HOT_SWAP_RED")
			(pinfunction "G")
			(pintype "input")
		)
		(pad "2" smd rect
			(at -1.051 0.65 270)
			(size 0.6 0.6)
			(layers "F.Cu" "F.Mask" "F.Paste")
			(net 1 "GND")
			(pinfunction "S")
			(pintype "passive")
		)
		(pad "3" smd rect
			(at 1.05 0 270)
			(size 0.6 0.6)
			(layers "F.Cu" "F.Mask" "F.Paste")
			(net 364 "Net-(Q11-D)")
			(pinfunction "D")
			(pintype "passive")
		)
	)
	(footprint "antmicro-footprints:R_0402_1005Metric"
		(layer "F.Cu")
		(at 100.260501 146.556 180)
		(descr "Resistor SMD 0402")
		(tags "resistor SMD 0402")
		(property "Reference" "R122"
			(at -1.122484 -0.772697 180)
			(layer "F.SilkS")
			(hide yes)
			(effects
				(font
					(size 0.7 0.7)
					(thickness 0.15)
				)
				(justify left bottom)
			)
		)
		(property "Value" "R_4k7_0402"
			(at -1.011843 1.772047 180)
			(layer "F.Fab")
			(effects
				(font
					(size 0.7 0.7)
					(thickness 0.15)
				)
				(justify left bottom)
			)
		)
		(property "Datasheet" "https://www.bourns.com/docs/product-datasheets/cr.pdf"
			(at 0 0 180)
			(layer "F.Fab")
			(hide yes)
			(effects
				(font
					(size 1.27 1.27)
					(thickness 0.15)
				)
			)
		)
		(property "Author" "Antmicro"
			(at 200.521002 293.112 0)
			(layer "F.Fab")
			(hide yes)
			(effects
				(font
					(size 1 1)
					(thickness 0.15)
				)
			)
		)
		(property "License" "Apache-2.0"
			(at 200.521002 293.112 0)
			(layer "F.Fab")
			(hide yes)
			(effects
				(font
					(size 1 1)
					(thickness 0.15)
				)
			)
		)
		(property "MPN" "CR0402-FX-4701GLF"
			(at 200.521002 293.112 0)
			(layer "F.Fab")
			(hide yes)
			(effects
				(font
					(size 1 1)
					(thickness 0.15)
				)
			)
		)
		(property "Manufacturer" "Bourns"
			(at 200.521002 293.112 0)
			(layer "F.Fab")
			(hide yes)
			(effects
				(font
					(size 1 1)
					(thickness 0.15)
				)
			)
		)
		(property "Tolerance" "1%"
			(at 200.521002 293.112 0)
			(layer "F.Fab")
			(hide yes)
			(effects
				(font
					(size 1 1)
					(thickness 0.15)
				)
			)
		)
		(property "Val" "4k7"
			(at 200.521002 293.112 0)
			(layer "F.Fab")
			(hide yes)
			(effects
				(font
					(size 1 1)
					(thickness 0.15)
				)
			)
		)
		(sheetname "/I^{2}C/")
		(sheetfile "i2c.kicad_sch")
		(attr smd)
		(fp_rect
			(start -0.93 -0.47)
			(end 0.93 0.47)
			(stroke
				(width 0.05)
				(type solid)
			)
			(fill no)
			(layer "F.CrtYd")
		)
		(fp_rect
			(start -0.5 -0.25)
			(end 0.5 0.25)
			(stroke
				(width 0.15)
				(type solid)
			)
			(fill no)
			(layer "F.Fab")
		)
		(pad "1" smd roundrect
			(at -0.485 0 180)
			(size 0.59 0.64)
			(layers "F.Cu" "F.Mask" "F.Paste")
			(roundrect_rratio 0.25)
			(net 200 "+3V3")
			(pintype "passive")
		)
		(pad "2" smd roundrect
			(at 0.485 0 180)
			(size 0.59 0.64)
			(layers "F.Cu" "F.Mask" "F.Paste")
			(roundrect_rratio 0.25)
			(net 682 "/FPGA bank 14/FPGA_DDR.SCL")
			(pintype "passive")
		)
	)
	(footprint "antmicro-footprints:LED_0603_1608Metric_G"
		(layer "F.Cu")
		(at 86.350501 116.426 -90)
		(descr "LED SMD 0603 Green")
		(tags "LED SMD 0603 Green")
		(property "Reference" "D6"
			(at -0.001 -0.901 270)
			(layer "F.SilkS")
			(hide yes)
			(effects
				(font
					(size 0.7 0.7)
					(thickness 0.15)
				)
				(justify left bottom)
			)
		)
		(property "Value" "LED_G_0603_KP-1608CGCK"
			(at -0.001 1.599 270)
			(layer "F.Fab")
			(effects
				(font
					(size 0.7 0.7)
					(thickness 0.15)
				)
				(justify left bottom)
			)
		)
		(property "Datasheet" "http://www.farnell.com/datasheets/2045956.pdf"
			(at 0 0 270)
			(layer "F.Fab")
			(hide yes)
			(effects
				(font
					(size 1.27 1.27)
					(thickness 0.15)
				)
			)
		)
		(property "Author" "Antmicro"
			(at -30.075499 202.776501 0)
			(layer "F.Fab")
			(hide yes)
			(effects
				(font
					(size 1 1)
					(thickness 0.15)
				)
			)
		)
		(property "License" "Apache-2.0"
			(at -30.075499 202.776501 0)
			(layer "F.Fab")
			(hide yes)
			(effects
				(font
					(size 1 1)
					(thickness 0.15)
				)
			)
		)
		(property "MPN" "KP-1608CGCK"
			(at -30.075499 202.776501 0)
			(layer "F.Fab")
			(hide yes)
			(effects
				(font
					(size 1 1)
					(thickness 0.15)
				)
			)
		)
		(property "Manufacturer" "Kingbright"
			(at -30.075499 202.776501 0)
			(layer "F.Fab")
			(hide yes)
			(effects
				(font
					(size 1 1)
					(thickness 0.15)
				)
			)
		)
		(sheetname "/FPGA bank 14/")
		(sheetfile "fpga-bank-14.kicad_sch")
		(attr smd)
		(fp_line
			(start -0.271 0.348)
			(end 0.269 0.348)
			(stroke
				(width 0.15)
				(type solid)
			)
			(layer "F.SilkS")
		)
		(fp_line
			(start 1.249 0.319)
			(end 1.249 -0.321)
			(stroke
				(width 0.15)
				(type solid)
			)
			(layer "F.SilkS")
		)
		(fp_line
			(start -0.107 -0.001)
			(end -0.291 -0.001)
			(stroke
				(width 0.1)
				(type solid)
			)
			(layer "F.SilkS")
		)
		(fp_line
			(start 0.092 -0.001)
			(end -0.107 0.198)
			(stroke
				(width 0.1)
				(type solid)
			)
			(layer "F.SilkS")
		)
		(fp_line
			(start 0.092 -0.001)
			(end 0.292 -0.001)
			(stroke
				(width 0.1)
				(type solid)
			)
			(layer "F.SilkS")
		)
		(fp_line
			(start -0.107 -0.201)
			(end -0.107 0.198)
			(stroke
				(width 0.1)
				(type solid)
			)
			(layer "F.SilkS")
		)
		(fp_line
			(start -0.107 -0.201)
			(end 0.092 -0.001)
			(stroke
				(width 0.1)
				(type solid)
			)
			(layer "F.SilkS")
		)
		(fp_line
			(start 0.092 -0.201)
			(end 0.092 0.198)
			(stroke
				(width 0.1)
				(type solid)
			)
			(layer "F.SilkS")
		)
		(fp_line
			(start -0.271 -0.349)
			(end 0.269 -0.349)
			(stroke
				(width 0.15)
				(type solid)
			)
			(layer "F.SilkS")
		)
		(fp_rect
			(start -1.2192 -0.6096)
			(end 1.27 0.6016)
			(stroke
				(width 0.05)
				(type solid)
			)
			(fill no)
			(layer "F.CrtYd")
		)
		(fp_line
			(start -0.202 0.201)
			(end 0.1 -0.001)
			(stroke
				(width 0.15)
				(type solid)
			)
			(layer "F.Fab")
		)
		(fp_line
			(start 0.198 0.201)
			(end 0.198 -0.101)
			(stroke
				(width 0.15)
				(type solid)
			)
			(layer "F.Fab")
		)
		(fp_line
			(start -0.849 0.025)
			(end -0.442 0.381)
			(stroke
				(width 0.15)
				(type solid)
			)
			(layer "F.Fab")
		)
		(fp_line
			(start -0.6 -0.001)
			(end -0.202 -0.001)
			(stroke
				(width 0.15)
				(type solid)
			)
			(layer "F.Fab")
		)
		(fp_line
			(start -0.202 -0.001)
			(end -0.202 0.201)
			(stroke
				(width 0.15)
				(type solid)
			)
			(layer "F.Fab")
		)
		(fp_line
			(start 0.1 -0.001)
			(end -0.202 -0.201)
			(stroke
				(width 0.15)
				(type solid)
			)
			(layer "F.Fab")
		)
		(fp_line
			(start 0.198 -0.001)
			(end 0.596 -0.001)
			(stroke
				(width 0.15)
				(type solid)
			)
			(layer "F.Fab")
		)
		(fp_line
			(start -0.202 -0.201)
			(end -0.202 -0.001)
			(stroke
				(width 0.15)
				(type solid)
			)
			(layer "F.Fab")
		)
		(fp_line
			(start 0.198 -0.201)
			(end 0.198 -0.101)
			(stroke
				(width 0.15)
				(type solid)
			)
			(layer "F.Fab")
		)
		(fp_rect
			(start -0.849 -0.401)
			(end 0.849 0.401)
			(stroke
				(width 0.15)
				(type solid)
			)
			(fill no)
			(layer "F.Fab")
		)
		(pad "1" smd rect
			(at -0.751 -0.001 90)
			(size 0.8 0.8)
			(layers "F.Cu" "F.Mask" "F.Paste")
			(net 200 "+3V3")
			(pinfunction "1")
			(pintype "passive")
		)
		(pad "2" smd rect
			(at 0.749 -0.001 90)
			(size 0.8 0.8)
			(layers "F.Cu" "F.Mask" "F.Paste")
			(net 309 "Net-(D6-Pad2)")
			(pinfunction "2")
			(pintype "passive")
		)
	)
	(footprint "antmicro-footprints:SC70-3"
		(layer "F.Cu")
		(at 156.700501 177.476)
		(property "Reference" "Q15"
			(at 0 -1.6 0)
			(layer "F.SilkS")
			(hide yes)
			(effects
				(font
					(size 0.7 0.7)
					(thickness 0.15)
				)
				(justify left bottom)
			)
		)
		(property "Value" "BSS138PW,115"
			(at 0 2.3 0)
			(layer "F.Fab")
			(effects
				(font
					(size 0.7 0.7)
					(thickness 0.15)
				)
				(justify left bottom)
			)
		)
		(property "Datasheet" "https://assets.nexperia.com/documents/data-sheet/BSS138PW.pdf"
			(at 0 0 0)
			(layer "F.Fab")
			(hide yes)
			(effects
				(font
					(size 1.27 1.27)
					(thickness 0.15)
				)
			)
		)
		(property "Description" "Power MOSFET, N Channel, 60 V, 320 mA, 0.9 ohm, SOT-323, Surface Mount"
			(at 0 0 0)
			(layer "F.Fab")
			(hide yes)
			(effects
				(font
					(size 1.27 1.27)
					(thickness 0.15)
				)
			)
		)
		(property "Author" "Antmicro"
			(at 0 0 0)
			(layer "F.Fab")
			(hide yes)
			(effects
				(font
					(size 1 1)
					(thickness 0.15)
				)
			)
		)
		(property "License" "Apache-2.0"
			(at 0 0 0)
			(layer "F.Fab")
			(hide yes)
			(effects
				(font
					(size 1 1)
					(thickness 0.15)
				)
			)
		)
		(property "MPN" "BSS138PW,115"
			(at 0 0 0)
			(layer "F.Fab")
			(hide yes)
			(effects
				(font
					(size 1 1)
					(thickness 0.15)
				)
			)
		)
		(property "Manufacturer" "Nexperia"
			(at 0 0 0)
			(layer "F.Fab")
			(hide yes)
			(effects
				(font
					(size 1 1)
					(thickness 0.15)
				)
			)
		)
		(sheetname "/Supply/")
		(sheetfile "supply.kicad_sch")
		(attr smd)
		(fp_line
			(start -0.3 -1)
			(end 0.627 -0.999)
			(stroke
				(width 0.15)
				(type solid)
			)
			(layer "F.SilkS")
		)
		(fp_line
			(start -0.3 1)
			(end 0.627 1.001)
			(stroke
				(width 0.15)
				(type solid)
			)
			(layer "F.SilkS")
		)
		(fp_line
			(start 0.627 -0.6)
			(end 0.627 -0.999)
			(stroke
				(width 0.15)
				(type solid)
			)
			(layer "F.SilkS")
		)
		(fp_line
			(start 0.627 0.6)
			(end 0.627 1.001)
			(stroke
				(width 0.15)
				(type solid)
			)
			(layer "F.SilkS")
		)
		(fp_line
			(start -1.4 1)
			(end -1.4 -1)
			(stroke
				(width 0.05)
				(type solid)
			)
			(layer "F.CrtYd")
		)
		(fp_line
			(start -0.9 -1.3)
			(end -0.9 -1)
			(stroke
				(width 0.05)
				(type solid)
			)
			(layer "F.CrtYd")
		)
		(fp_line
			(start -0.9 -1.3)
			(end 0.9 -1.3)
			(stroke
				(width 0.05)
				(type solid)
			)
			(layer "F.CrtYd")
		)
		(fp_line
			(start -0.9 -1)
			(end -1.4 -1)
			(stroke
				(width 0.05)
				(type solid)
			)
			(layer "F.CrtYd")
		)
		(fp_line
			(start -0.9 1)
			(end -1.4 1)
			(stroke
				(width 0.05)
				(type solid)
			)
			(layer "F.CrtYd")
		)
		(fp_line
			(start -0.9 1.3)
			(end -0.9 1)
			(stroke
				(width 0.05)
				(type solid)
			)
			(layer "F.CrtYd")
		)
		(fp_line
			(start 0.9 -1.3)
			(end 0.9 -0.4)
			(stroke
				(width 0.05)
				(type solid)
			)
			(layer "F.CrtYd")
		)
		(fp_line
			(start 0.9 -0.4)
			(end 1.4 -0.4)
			(stroke
				(width 0.05)
				(type solid)
			)
			(layer "F.CrtYd")
		)
		(fp_line
			(start 0.9 0.4)
			(end 0.9 1.3)
			(stroke
				(width 0.05)
				(type solid)
			)
			(layer "F.CrtYd")
		)
		(fp_line
			(start 0.9 1.3)
			(end -0.9 1.3)
			(stroke
				(width 0.05)
				(type solid)
			)
			(layer "F.CrtYd")
		)
		(fp_line
			(start 1.4 -0.4)
			(end 1.4 0.4)
			(stroke
				(width 0.05)
				(type solid)
			)
			(layer "F.CrtYd")
		)
		(fp_line
			(start 1.4 0.4)
			(end 0.9 0.4)
			(stroke
				(width 0.05)
				(type solid)
			)
			(layer "F.CrtYd")
		)
		(fp_rect
			(start -0.623 -0.999)
			(end 0.627 1.001)
			(stroke
				(width 0.15)
				(type solid)
			)
			(fill no)
			(layer "F.Fab")
		)
		(pad "1" smd rect
			(at -1.051 -0.65 90)
			(size 0.6 0.6)
			(layers "F.Cu" "F.Mask" "F.Paste")
			(net 272 "FAN_PWM")
			(pinfunction "G")
			(pintype "input")
		)
		(pad "2" smd rect
			(at -1.051 0.65 90)
			(size 0.6 0.6)
			(layers "F.Cu" "F.Mask" "F.Paste")
			(net 1 "GND")
			(pinfunction "S")
			(pintype "passive")
		)
		(pad "3" smd rect
			(at 1.05 0 90)
			(size 0.6 0.6)
			(layers "F.Cu" "F.Mask" "F.Paste")
			(net 332 "Net-(J8-Pin_4)")
			(pinfunction "D")
			(pintype "passive")
		)
	)
	(footprint "antmicro-footprints:MP_Pad6mm_Drill3mm"
		(layer "F.Cu")
		(at 76.375501 204.951)
		(property "Reference" "MP2"
			(at 0 -3.2 0)
			(layer "F.SilkS")
			(hide yes)
			(effects
				(font
					(size 0.7 0.7)
					(thickness 0.15)
				)
				(justify left bottom)
			)
		)
		(property "Value" "MP_Pad6mm_Drill3mm"
			(at 0 3.9 0)
			(layer "F.Fab")
			(effects
				(font
					(size 0.7 0.7)
					(thickness 0.15)
				)
				(justify left bottom)
			)
		)
		(attr board_only exclude_from_pos_files exclude_from_bom)
		(pad "1" thru_hole circle
			(at 0 0)
			(size 6 6)
			(drill 3)
			(layers "*.Cu" "*.Mask")
			(remove_unused_layers no)
			(net 1 "GND")
		)
	)
	(footprint "antmicro-footprints:Fiducial_1mm_Mask2mm"
		(layer "F.Cu")
		(at 197.010501 197.696 180)
		(descr "Circular Fiducial, 1mm bare copper, 3mm soldermask opening")
		(tags "fiducial")
		(property "Reference" "FID1005"
			(at 0 -1.4 0)
			(layer "F.SilkS")
			(hide yes)
			(effects
				(font
					(size 0.7 0.7)
					(thickness 0.15)
				)
				(justify right bottom)
			)
		)
		(property "Value" "Fiducial_1mm_Mask2mm"
			(at 0 2.2 0)
			(layer "F.Fab")
			(effects
				(font
					(size 0.7 0.7)
					(thickness 0.15)
				)
				(justify right bottom)
			)
		)
		(property "Author" "Antmicro"
			(at 394.021002 395.392 0)
			(layer "F.Fab")
			(hide yes)
			(effects
				(font
					(size 1 1)
					(thickness 0.15)
				)
			)
		)
		(property "License" "Apache-2.0"
			(at 394.021002 395.392 0)
			(layer "F.Fab")
			(hide yes)
			(effects
				(font
					(size 1 1)
					(thickness 0.15)
				)
			)
		)
		(property "MPN" ""
			(at 394.021002 395.392 0)
			(layer "F.Fab")
			(hide yes)
			(effects
				(font
					(size 1 1)
					(thickness 0.15)
				)
			)
		)
		(property "Manufacturer" ""
			(at 394.021002 395.392 0)
			(layer "F.Fab")
			(hide yes)
			(effects
				(font
					(size 1 1)
					(thickness 0.15)
				)
			)
		)
		(sheetfile "sodimm-ddr5-tester.kicad_sch")
		(attr board_only exclude_from_pos_files exclude_from_bom)
		(fp_circle
			(center 0 0)
			(end 1.24 0)
			(stroke
				(width 0.05)
				(type solid)
			)
			(fill no)
			(layer "F.CrtYd")
		)
		(fp_circle
			(center 0 0)
			(end 0.999 0)
			(stroke
				(width 0.15)
				(type solid)
			)
			(fill no)
			(layer "F.Fab")
		)
		(pad "" smd circle
			(at 0 0 180)
			(size 1 1)
			(layers "F.Cu" "F.Mask")
			(solder_mask_margin 0.5)
			(clearance 0.5)
		)
	)
	(footprint "antmicro-footprints:QFN-56-1EP_8x8mm_P0.5mm"
		(layer "F.Cu")
		(at 98.559501 174.386)
		(descr "QFN 56 Pin")
		(tags "QFN")
		(property "Reference" "U6"
			(at 2.940499 5.314 0)
			(layer "F.SilkS")
			(effects
				(font
					(size 0.7 0.7)
					(thickness 0.15)
				)
				(justify left bottom)
			)
		)
		(property "Value" "FT4232H_VQFN"
			(at 0 5.32 0)
			(layer "F.Fab")
			(effects
				(font
					(size 0.7 0.7)
					(thickness 0.15)
				)
				(justify left bottom)
			)
		)
		(property "Datasheet" "https://www.ftdichip.com/Support/Documents/DataSheets/ICs/DS_FT4232H.pdf"
			(at 0 0 0)
			(layer "F.Fab")
			(hide yes)
			(effects
				(font
					(size 1.27 1.27)
					(thickness 0.15)
				)
			)
		)
		(property "Author" "Antmicro"
			(at 0 0 0)
			(layer "F.Fab")
			(hide yes)
			(effects
				(font
					(size 1 1)
					(thickness 0.15)
				)
			)
		)
		(property "License" "Apache-2.0"
			(at 0 0 0)
			(layer "F.Fab")
			(hide yes)
			(effects
				(font
					(size 1 1)
					(thickness 0.15)
				)
			)
		)
		(property "MPN" "FT4232H-56Q-REEL"
			(at 0 0 0)
			(layer "F.Fab")
			(hide yes)
			(effects
				(font
					(size 1 1)
					(thickness 0.15)
				)
			)
		)
		(property "Manufacturer" "FTDI Chip"
			(at 0 0 0)
			(layer "F.Fab")
			(hide yes)
			(effects
				(font
					(size 1 1)
					(thickness 0.15)
				)
			)
		)
		(sheetname "/Debug FTDI/")
		(sheetfile "debug-ftdi.kicad_sch")
		(attr smd)
		(fp_line
			(start -4.111 -3.635)
			(end -4.111 -4.111)
			(stroke
				(width 0.15)
				(type solid)
			)
			(layer "F.SilkS")
		)
		(fp_line
			(start -4.111 4.11)
			(end -4.111 3.634)
			(stroke
				(width 0.15)
				(type solid)
			)
			(layer "F.SilkS")
		)
		(fp_line
			(start -3.635 -4.111)
			(end -4.111 -4.111)
			(stroke
				(width 0.15)
				(type solid)
			)
			(layer "F.SilkS")
		)
		(fp_line
			(start -3.635 4.11)
			(end -4.111 4.11)
			(stroke
				(width 0.15)
				(type solid)
			)
			(layer "F.SilkS")
		)
		(fp_line
			(start 3.634 -4.111)
			(end 4.11 -4.111)
			(stroke
				(width 0.15)
				(type solid)
			)
			(layer "F.SilkS")
		)
		(fp_line
			(start 3.634 4.11)
			(end 4.11 4.11)
			(stroke
				(width 0.15)
				(type solid)
			)
			(layer "F.SilkS")
		)
		(fp_line
			(start 4.11 -4.111)
			(end 4.11 -3.635)
			(stroke
				(width 0.15)
				(type solid)
			)
			(layer "F.SilkS")
		)
		(fp_line
			(start 4.11 4.11)
			(end 4.11 3.634)
			(stroke
				(width 0.15)
				(type solid)
			)
			(layer "F.SilkS")
		)
		(fp_circle
			(center -4.35 -3.6)
			(end -4.3 -3.6)
			(stroke
				(width 0.15)
				(type solid)
			)
			(fill yes)
			(layer "F.SilkS")
		)
		(fp_rect
			(start 4.4 4.4)
			(end -4.4 -4.4)
			(stroke
				(width 0.05)
				(type solid)
			)
			(fill no)
			(layer "F.CrtYd")
		)
		(fp_line
			(start -4 -3)
			(end -3 -4)
			(stroke
				(width 0.15)
				(type solid)
			)
			(layer "F.Fab")
		)
		(fp_rect
			(start 4 4)
			(end -4 -4)
			(stroke
				(width 0.15)
				(type solid)
			)
			(fill no)
			(layer "F.Fab")
		)
		(pad "" smd roundrect
			(at -2.101 -2.101)
			(size 1.13 1.13)
			(layers "F.Paste")
			(roundrect_rratio 0.221239)
		)
		(pad "" smd roundrect
			(at -2.101 -0.7)
			(size 1.13 1.13)
			(layers "F.Paste")
			(roundrect_rratio 0.221239)
		)
		(pad "" smd roundrect
			(at -2.101 0.699)
			(size 1.13 1.13)
			(layers "F.Paste")
			(roundrect_rratio 0.221239)
		)
		(pad "" smd roundrect
			(at -2.101 2.1)
			(size 1.13 1.13)
			(layers "F.Paste")
			(roundrect_rratio 0.221239)
		)
		(pad "" smd roundrect
			(at -0.7 -2.101)
			(size 1.13 1.13)
			(layers "F.Paste")
			(roundrect_rratio 0.221239)
		)
		(pad "" smd roundrect
			(at -0.7 -0.7)
			(size 1.13 1.13)
			(layers "F.Paste")
			(roundrect_rratio 0.221239)
		)
		(pad "" smd roundrect
			(at -0.7 0.699)
			(size 1.13 1.13)
			(layers "F.Paste")
			(roundrect_rratio 0.221239)
		)
		(pad "" smd roundrect
			(at -0.7 2.1)
			(size 1.13 1.13)
			(layers "F.Paste")
			(roundrect_rratio 0.221239)
		)
		(pad "" smd roundrect
			(at 0.699 -2.101)
			(size 1.13 1.13)
			(layers "F.Paste")
			(roundrect_rratio 0.221239)
		)
		(pad "" smd roundrect
			(at 0.699 -0.7)
			(size 1.13 1.13)
			(layers "F.Paste")
			(roundrect_rratio 0.221239)
		)
		(pad "" smd roundrect
			(at 0.699 0.699)
			(size 1.13 1.13)
			(layers "F.Paste")
			(roundrect_rratio 0.221239)
		)
		(pad "" smd roundrect
			(at 0.699 2.1)
			(size 1.13 1.13)
			(layers "F.Paste")
			(roundrect_rratio 0.221239)
		)
		(pad "" smd roundrect
			(at 2.1 -2.101)
			(size 1.13 1.13)
			(layers "F.Paste")
			(roundrect_rratio 0.221239)
		)
		(pad "" smd roundrect
			(at 2.1 -0.7)
			(size 1.13 1.13)
			(layers "F.Paste")
			(roundrect_rratio 0.221239)
		)
		(pad "" smd roundrect
			(at 2.1 0.699)
			(size 1.13 1.13)
			(layers "F.Paste")
			(roundrect_rratio 0.221239)
		)
		(pad "" smd roundrect
			(at 2.1 2.1)
			(size 1.13 1.13)
			(layers "F.Paste")
			(roundrect_rratio 0.221239)
		)
		(pad "1" smd roundrect
			(at -3.938 -3.25)
			(size 0.875 0.3)
			(layers "F.Cu" "F.Mask" "F.Paste")
			(roundrect_rratio 0.25)
			(net 738 "/Debug FTDI/FTDI_EECS")
			(pinfunction "EECS")
			(pintype "bidirectional")
		)
		(pad "2" smd roundrect
			(at -3.938 -2.75)
			(size 0.875 0.3)
			(layers "F.Cu" "F.Mask" "F.Paste")
			(roundrect_rratio 0.25)
			(net 8 "/Debug FTDI/FTDI_VCORE")
			(pinfunction "V_{CORE}")
			(pintype "power_in")
		)
		(pad "3" smd roundrect
			(at -3.938 -2.25)
			(size 0.875 0.3)
			(layers "F.Cu" "F.Mask" "F.Paste")
			(roundrect_rratio 0.25)
			(net 4 "/Debug FTDI/FTDI_XI")
			(pinfunction "OSCI")
			(pintype "input")
		)
		(pad "4" smd roundrect
			(at -3.938 -1.75)
			(size 0.875 0.3)
			(layers "F.Cu" "F.Mask" "F.Paste")
			(roundrect_rratio 0.25)
			(net 7 "/Debug FTDI/FTDI_XO")
			(pinfunction "OSCO")
			(pintype "output")
		)
		(pad "5" smd roundrect
			(at -3.938 -1.25)
			(size 0.875 0.3)
			(layers "F.Cu" "F.Mask" "F.Paste")
			(roundrect_rratio 0.25)
			(net 5 "/Debug FTDI/FTDI_VPHY")
			(pinfunction "V_{PHY}")
			(pintype "power_in")
		)
		(pad "6" smd roundrect
			(at -3.938 -0.75)
			(size 0.875 0.3)
			(layers "F.Cu" "F.Mask" "F.Paste")
			(roundrect_rratio 0.25)
			(net 375 "Net-(U6-REF)")
			(pinfunction "REF")
			(pintype "input")
		)
		(pad "7" smd roundrect
			(at -3.938 -0.25)
			(size 0.875 0.3)
			(layers "F.Cu" "F.Mask" "F.Paste")
			(roundrect_rratio 0.25)
			(net 291 "/Debug FTDI/DBG_USB_N")
			(pinfunction "D-")
			(pintype "bidirectional")
		)
		(pad "8" smd roundrect
			(at -3.938 0.249)
			(size 0.875 0.3)
			(layers "F.Cu" "F.Mask" "F.Paste")
			(roundrect_rratio 0.25)
			(net 290 "/Debug FTDI/DBG_USB_P")
			(pinfunction "D+")
			(pintype "bidirectional")
		)
		(pad "9" smd roundrect
			(at -3.938 0.749)
			(size 0.875 0.3)
			(layers "F.Cu" "F.Mask" "F.Paste")
			(roundrect_rratio 0.25)
			(net 3 "/Debug FTDI/FTDI_VPLL")
			(pinfunction "V_{PLL}")
			(pintype "power_in")
		)
		(pad "10" smd roundrect
			(at -3.938 1.249)
			(size 0.875 0.3)
			(layers "F.Cu" "F.Mask" "F.Paste")
			(roundrect_rratio 0.25)
			(net 1 "GND")
			(pinfunction "TEST")
			(pintype "input")
		)
		(pad "11" smd roundrect
			(at -3.938 1.749)
			(size 0.875 0.3)
			(layers "F.Cu" "F.Mask" "F.Paste")
			(roundrect_rratio 0.25)
			(net 370 "Net-(U6-~{RESET})")
			(pinfunction "~{RESET}")
			(pintype "input")
		)
		(pad "12" smd roundrect
			(at -3.938 2.249)
			(size 0.875 0.3)
			(layers "F.Cu" "F.Mask" "F.Paste")
			(roundrect_rratio 0.25)
			(net 739 "/Debug FTDI/FTDI_JTAG_TCK")
			(pinfunction "ADBUS0")
			(pintype "bidirectional")
		)
		(pad "13" smd roundrect
			(at -3.938 2.749)
			(size 0.875 0.3)
			(layers "F.Cu" "F.Mask" "F.Paste")
			(roundrect_rratio 0.25)
			(net 740 "/Debug FTDI/FTDI_JTAG_TDI")
			(pinfunction "ADBUS1")
			(pintype "bidirectional")
		)
		(pad "14" smd roundrect
			(at -3.938 3.249)
			(size 0.875 0.3)
			(layers "F.Cu" "F.Mask" "F.Paste")
			(roundrect_rratio 0.25)
			(net 741 "/Debug FTDI/FTDI_JTAG_TDO")
			(pinfunction "ADBUS2")
			(pintype "bidirectional")
		)
		(pad "15" smd roundrect
			(at -3.25 3.937 90)
			(size 0.875 0.3)
			(layers "F.Cu" "F.Mask" "F.Paste")
			(roundrect_rratio 0.25)
			(net 742 "/Debug FTDI/FTDI_JTAG_TMS")
			(pinfunction "ADBUS3")
			(pintype "bidirectional")
		)
		(pad "16" smd roundrect
			(at -2.75 3.937 90)
			(size 0.875 0.3)
			(layers "F.Cu" "F.Mask" "F.Paste")
			(roundrect_rratio 0.25)
			(net 6 "/Debug FTDI/FTDI_3V3")
			(pinfunction "V_{CCIO}")
			(pintype "power_in")
		)
		(pad "17" smd roundrect
			(at -2.25 3.937 90)
			(size 0.875 0.3)
			(layers "F.Cu" "F.Mask" "F.Paste")
			(roundrect_rratio 0.25)
			(net 584 "unconnected-(U6-ADBUS4-Pad17)")
			(pinfunction "ADBUS4")
			(pintype "bidirectional+no_connect")
		)
		(pad "18" smd roundrect
			(at -1.75 3.937 90)
			(size 0.875 0.3)
			(layers "F.Cu" "F.Mask" "F.Paste")
			(roundrect_rratio 0.25)
			(net 692 "/Debug FTDI/FTDI_JTAG_RST")
			(pinfunction "ADBUS5")
			(pintype "bidirectional")
		)
		(pad "19" smd roundrect
			(at -1.25 3.937 90)
			(size 0.875 0.3)
			(layers "F.Cu" "F.Mask" "F.Paste")
			(roundrect_rratio 0.25)
			(net 585 "unconnected-(U6-ADBUS6-Pad19)")
			(pinfunction "ADBUS6")
			(pintype "bidirectional+no_connect")
		)
		(pad "20" smd roundrect
			(at -0.75 3.937 90)
			(size 0.875 0.3)
			(layers "F.Cu" "F.Mask" "F.Paste")
			(roundrect_rratio 0.25)
			(net 586 "unconnected-(U6-ADBUS7-Pad20)")
			(pinfunction "ADBUS7")
			(pintype "bidirectional+no_connect")
		)
		(pad "21" smd roundrect
			(at -0.25 3.937 90)
			(size 0.875 0.3)
			(layers "F.Cu" "F.Mask" "F.Paste")
			(roundrect_rratio 0.25)
			(net 1 "GND")
			(pinfunction "GND")
			(pintype "power_in")
		)
		(pad "22" smd roundrect
			(at 0.249 3.937 90)
			(size 0.875 0.3)
			(layers "F.Cu" "F.Mask" "F.Paste")
			(roundrect_rratio 0.25)
			(net 646 "/Debug FTDI/BDBUS0")
			(pinfunction "BDBUS0")
			(pintype "bidirectional")
		)
		(pad "23" smd roundrect
			(at 0.749 3.937 90)
			(size 0.875 0.3)
			(layers "F.Cu" "F.Mask" "F.Paste")
			(roundrect_rratio 0.25)
			(net 648 "/Debug FTDI/BDBUS1")
			(pinfunction "BDBUS1")
			(pintype "bidirectional")
		)
		(pad "24" smd roundrect
			(at 1.249 3.937 90)
			(size 0.875 0.3)
			(layers "F.Cu" "F.Mask" "F.Paste")
			(roundrect_rratio 0.25)
			(net 650 "/Debug FTDI/BDBUS2")
			(pinfunction "BDBUS2")
			(pintype "bidirectional")
		)
		(pad "25" smd roundrect
			(at 1.749 3.937 90)
			(size 0.875 0.3)
			(layers "F.Cu" "F.Mask" "F.Paste")
			(roundrect_rratio 0.25)
			(net 652 "/Debug FTDI/BDBUS3")
			(pinfunction "BDBUS3")
			(pintype "bidirectional")
		)
		(pad "26" smd roundrect
			(at 2.249 3.937 90)
			(size 0.875 0.3)
			(layers "F.Cu" "F.Mask" "F.Paste")
			(roundrect_rratio 0.25)
			(net 587 "unconnected-(U6-BDBUS4-Pad26)")
			(pinfunction "BDBUS4")
			(pintype "bidirectional+no_connect")
		)
		(pad "27" smd roundrect
			(at 2.749 3.937 90)
			(size 0.875 0.3)
			(layers "F.Cu" "F.Mask" "F.Paste")
			(roundrect_rratio 0.25)
			(net 654 "/Debug FTDI/I2C_EN")
			(pinfunction "BDBUS5")
			(pintype "bidirectional")
		)
		(pad "28" smd roundrect
			(at 3.249 3.937 90)
			(size 0.875 0.3)
			(layers "F.Cu" "F.Mask" "F.Paste")
			(roundrect_rratio 0.25)
			(net 588 "unconnected-(U6-BDBUS6-Pad28)")
			(pinfunction "BDBUS6")
			(pintype "bidirectional+no_connect")
		)
		(pad "29" smd roundrect
			(at 3.937 3.249)
			(size 0.875 0.3)
			(layers "F.Cu" "F.Mask" "F.Paste")
			(roundrect_rratio 0.25)
			(net 589 "unconnected-(U6-BDBUS7-Pad29)")
			(pinfunction "BDBUS7")
			(pintype "bidirectional+no_connect")
		)
		(pad "30" smd roundrect
			(at 3.937 2.749)
			(size 0.875 0.3)
			(layers "F.Cu" "F.Mask" "F.Paste")
			(roundrect_rratio 0.25)
			(net 590 "unconnected-(U6-~{SUSPEND}-Pad30)")
			(pinfunction "~{SUSPEND}")
			(pintype "output+no_connect")
		)
		(pad "31" smd roundrect
			(at 3.937 2.249)
			(size 0.875 0.3)
			(layers "F.Cu" "F.Mask" "F.Paste")
			(roundrect_rratio 0.25)
			(net 8 "/Debug FTDI/FTDI_VCORE")
			(pinfunction "V_{CORE}")
			(pintype "passive")
		)
		(pad "32" smd roundrect
			(at 3.937 1.749)
			(size 0.875 0.3)
			(layers "F.Cu" "F.Mask" "F.Paste")
			(roundrect_rratio 0.25)
			(net 638 "/Debug FTDI/FTDI_UART0_TX")
			(pinfunction "CDBUS0")
			(pintype "bidirectional")
		)
		(pad "33" smd roundrect
			(at 3.937 1.249)
			(size 0.875 0.3)
			(layers "F.Cu" "F.Mask" "F.Paste")
			(roundrect_rratio 0.25)
			(net 640 "/Debug FTDI/FTDI_UART0_RX")
			(pinfunction "CDBUS1")
			(pintype "bidirectional")
		)
		(pad "34" smd roundrect
			(at 3.937 0.749)
			(size 0.875 0.3)
			(layers "F.Cu" "F.Mask" "F.Paste")
			(roundrect_rratio 0.25)
			(net 591 "unconnected-(U6-CDBUS2-Pad34)")
			(pinfunction "CDBUS2")
			(pintype "bidirectional+no_connect")
		)
		(pad "35" smd roundrect
			(at 3.937 0.249)
			(size 0.875 0.3)
			(layers "F.Cu" "F.Mask" "F.Paste")
			(roundrect_rratio 0.25)
			(net 592 "unconnected-(U6-CDBUS3-Pad35)")
			(pinfunction "CDBUS3")
			(pintype "bidirectional+no_connect")
		)
		(pad "36" smd roundrect
			(at 3.937 -0.25)
			(size 0.875 0.3)
			(layers "F.Cu" "F.Mask" "F.Paste")
			(roundrect_rratio 0.25)
			(net 6 "/Debug FTDI/FTDI_3V3")
			(pinfunction "V_{CCIO}")
			(pintype "passive")
		)
		(pad "37" smd roundrect
			(at 3.937 -0.75)
			(size 0.875 0.3)
			(layers "F.Cu" "F.Mask" "F.Paste")
			(roundrect_rratio 0.25)
			(net 598 "unconnected-(U6-CDBUS4-Pad37)")
			(pinfunction "CDBUS4")
			(pintype "bidirectional+no_connect")
		)
		(pad "38" smd roundrect
			(at 3.937 -1.25)
			(size 0.875 0.3)
			(layers "F.Cu" "F.Mask" "F.Paste")
			(roundrect_rratio 0.25)
			(net 599 "unconnected-(U6-CDBUS5-Pad38)")
			(pinfunction "CDBUS5")
			(pintype "bidirectional+no_connect")
		)
		(pad "39" smd roundrect
			(at 3.937 -1.75)
			(size 0.875 0.3)
			(layers "F.Cu" "F.Mask" "F.Paste")
			(roundrect_rratio 0.25)
			(net 600 "unconnected-(U6-CDBUS6-Pad39)")
			(pinfunction "CDBUS6")
			(pintype "bidirectional+no_connect")
		)
		(pad "40" smd roundrect
			(at 3.937 -2.25)
			(size 0.875 0.3)
			(layers "F.Cu" "F.Mask" "F.Paste")
			(roundrect_rratio 0.25)
			(net 601 "unconnected-(U6-CDBUS7-Pad40)")
			(pinfunction "CDBUS7")
			(pintype "bidirectional+no_connect")
		)
		(pad "41" smd roundrect
			(at 3.937 -2.75)
			(size 0.875 0.3)
			(layers "F.Cu" "F.Mask" "F.Paste")
			(roundrect_rratio 0.25)
			(net 1 "GND")
			(pinfunction "GND")
			(pintype "passive")
		)
		(pad "42" smd roundrect
			(at 3.937 -3.25)
			(size 0.875 0.3)
			(layers "F.Cu" "F.Mask" "F.Paste")
			(roundrect_rratio 0.25)
			(net 642 "/Debug FTDI/FTDI_UART1_TX")
			(pinfunction "DDBUS0")
			(pintype "bidirectional")
		)
		(pad "43" smd roundrect
			(at 3.249 -3.938 90)
			(size 0.875 0.3)
			(layers "F.Cu" "F.Mask" "F.Paste")
			(roundrect_rratio 0.25)
			(net 8 "/Debug FTDI/FTDI_VCORE")
			(pinfunction "V_{REGOUT}")
			(pintype "power_out")
		)
		(pad "44" smd roundrect
			(at 2.749 -3.938 90)
			(size 0.875 0.3)
			(layers "F.Cu" "F.Mask" "F.Paste")
			(roundrect_rratio 0.25)
			(net 6 "/Debug FTDI/FTDI_3V3")
			(pinfunction "V_{REGIN}")
			(pintype "power_in")
		)
		(pad "45" smd roundrect
			(at 2.249 -3.938 90)
			(size 0.875 0.3)
			(layers "F.Cu" "F.Mask" "F.Paste")
			(roundrect_rratio 0.25)
			(net 1 "GND")
			(pinfunction "GND")
			(pintype "passive")
		)
		(pad "46" smd roundrect
			(at 1.749 -3.938 90)
			(size 0.875 0.3)
			(layers "F.Cu" "F.Mask" "F.Paste")
			(roundrect_rratio 0.25)
			(net 644 "/Debug FTDI/FTDI_UART1_RX")
			(pinfunction "DDBUS1")
			(pintype "bidirectional")
		)
		(pad "47" smd roundrect
			(at 1.249 -3.938 90)
			(size 0.875 0.3)
			(layers "F.Cu" "F.Mask" "F.Paste")
			(roundrect_rratio 0.25)
			(net 616 "unconnected-(U6-DDBUS2-Pad47)")
			(pinfunction "DDBUS2")
			(pintype "bidirectional+no_connect")
		)
		(pad "48" smd roundrect
			(at 0.749 -3.938 90)
			(size 0.875 0.3)
			(layers "F.Cu" "F.Mask" "F.Paste")
			(roundrect_rratio 0.25)
			(net 618 "unconnected-(U6-DDBUS3-Pad48)")
			(pinfunction "DDBUS3")
			(pintype "bidirectional+no_connect")
		)
		(pad "49" smd roundrect
			(at 0.249 -3.938 90)
			(size 0.875 0.3)
			(layers "F.Cu" "F.Mask" "F.Paste")
			(roundrect_rratio 0.25)
			(net 620 "unconnected-(U6-DDBUS4-Pad49)")
			(pinfunction "DDBUS4")
			(pintype "bidirectional+no_connect")
		)
		(pad "50" smd roundrect
			(at -0.25 -3.938 90)
			(size 0.875 0.3)
			(layers "F.Cu" "F.Mask" "F.Paste")
			(roundrect_rratio 0.25)
			(net 6 "/Debug FTDI/FTDI_3V3")
			(pinfunction "V_{CCIO}")
			(pintype "passive")
		)
		(pad "51" smd roundrect
			(at -0.75 -3.938 90)
			(size 0.875 0.3)
			(layers "F.Cu" "F.Mask" "F.Paste")
			(roundrect_rratio 0.25)
			(net 707 "unconnected-(U6-DDBUS5-Pad51)")
			(pinfunction "DDBUS5")
			(pintype "bidirectional+no_connect")
		)
		(pad "52" smd roundrect
			(at -1.25 -3.938 90)
			(size 0.875 0.3)
			(layers "F.Cu" "F.Mask" "F.Paste")
			(roundrect_rratio 0.25)
			(net 708 "unconnected-(U6-DDBUS6-Pad52)")
			(pinfunction "DDBUS6")
			(pintype "bidirectional+no_connect")
		)
		(pad "53" smd roundrect
			(at -1.75 -3.938 90)
			(size 0.875 0.3)
			(layers "F.Cu" "F.Mask" "F.Paste")
			(roundrect_rratio 0.25)
			(net 709 "unconnected-(U6-DDBUS7-Pad53)")
			(pinfunction "DDBUS7")
			(pintype "bidirectional+no_connect")
		)
		(pad "54" smd roundrect
			(at -2.25 -3.938 90)
			(size 0.875 0.3)
			(layers "F.Cu" "F.Mask" "F.Paste")
			(roundrect_rratio 0.25)
			(net 668 "/Debug FTDI/FTDI_PWREN")
			(pinfunction "~{PWR_{EN}}")
			(pintype "output")
		)
		(pad "55" smd roundrect
			(at -2.75 -3.938 90)
			(size 0.875 0.3)
			(layers "F.Cu" "F.Mask" "F.Paste")
			(roundrect_rratio 0.25)
			(net 744 "/Debug FTDI/FTDI_EEDAT")
			(pinfunction "EEDATA")
			(pintype "bidirectional")
		)
		(pad "56" smd roundrect
			(at -3.25 -3.938 90)
			(size 0.875 0.3)
			(layers "F.Cu" "F.Mask" "F.Paste")
			(roundrect_rratio 0.25)
			(net 745 "/Debug FTDI/FTDI_EECLK")
			(pinfunction "EECLK")
			(pintype "output")
		)
		(pad "57" smd rect
			(at 0 0)
			(size 5.9 5.9)
			(layers "F.Cu" "F.Mask")
			(net 1 "GND")
			(pinfunction "GND")
			(pintype "passive")
		)
	)
	(footprint "antmicro-footprints:PinHeader_2x7_P2mm_SMD_Shrouded_no-locator"
		(layer "F.Cu")
		(at 170.8 174.4 90)
		(descr "Pin Header 2x7 SMD Shrouded no-locator")
		(property "Reference" "J1"
			(at -9.7 2.3 180)
			(layer "F.SilkS")
			(effects
				(font
					(size 0.7 0.7)
					(thickness 0.15)
				)
				(justify left bottom)
			)
		)
		(property "Value" "PinHeader_2x7_P2mm_SMD_Shrouded_no-locator"
			(at 0 5.038 90)
			(layer "F.Fab")
			(effects
				(font
					(size 0.7 0.7)
					(thickness 0.15)
				)
				(justify left bottom)
			)
		)
		(property "Datasheet" "https://www.molex.com/pdm_docs/ps/PS-87831-027-001.pdf"
			(at 0 0 90)
			(layer "F.Fab")
			(hide yes)
			(effects
				(font
					(size 1.27 1.27)
					(thickness 0.15)
				)
			)
		)
		(property "Author" "Antmicro"
			(at 345.2 3.6 0)
			(layer "F.Fab")
			(hide yes)
			(effects
				(font
					(size 1 1)
					(thickness 0.15)
				)
			)
		)
		(property "License" "Apache-2.0"
			(at 345.2 3.6 0)
			(layer "F.Fab")
			(hide yes)
			(effects
				(font
					(size 1 1)
					(thickness 0.15)
				)
			)
		)
		(property "MPN" "878321412"
			(at 345.2 3.6 0)
			(layer "F.Fab")
			(hide yes)
			(effects
				(font
					(size 1 1)
					(thickness 0.15)
				)
			)
		)
		(property "Manufacturer" "Molex"
			(at 345.2 3.6 0)
			(layer "F.Fab")
			(hide yes)
			(effects
				(font
					(size 1 1)
					(thickness 0.15)
				)
			)
		)
		(sheetname "/FPGA Config/")
		(sheetfile "fpga-config.kicad_sch")
		(attr exclude_from_pos_files exclude_from_bom dnp)
		(fp_line
			(start 8.499 -3.301)
			(end 7.998 -3.301)
			(stroke
				(width 0.15)
				(type solid)
			)
			(layer "F.SilkS")
		)
		(fp_line
			(start 8.499 -3.301)
			(end 8.499 -2.801)
			(stroke
				(width 0.15)
				(type solid)
			)
			(layer "F.SilkS")
		)
		(fp_line
			(start -8.5 -3.301)
			(end -8 -3.301)
			(stroke
				(width 0.15)
				(type solid)
			)
			(layer "F.SilkS")
		)
		(fp_line
			(start -8.5 -3.301)
			(end -8.5 -2.801)
			(stroke
				(width 0.15)
				(type solid)
			)
			(layer "F.SilkS")
		)
		(fp_line
			(start -1.397 2.41)
			(end -0.9 2.41)
			(stroke
				(width 0.15)
				(type solid)
			)
			(layer "F.SilkS")
		)
		(fp_line
			(start -1.397 2.41)
			(end -1.397 2.91)
			(stroke
				(width 0.15)
				(type solid)
			)
			(layer "F.SilkS")
		)
		(fp_line
			(start 1.394 2.418)
			(end 0.897 2.418)
			(stroke
				(width 0.15)
				(type solid)
			)
			(layer "F.SilkS")
		)
		(fp_line
			(start 1.394 2.418)
			(end 1.394 2.918)
			(stroke
				(width 0.15)
				(type solid)
			)
			(layer "F.SilkS")
		)
		(fp_line
			(start 8.499 3.297)
			(end 8.499 2.797)
			(stroke
				(width 0.15)
				(type solid)
			)
			(layer "F.SilkS")
		)
		(fp_line
			(start 8.499 3.297)
			(end 7.998 3.297)
			(stroke
				(width 0.15)
				(type solid)
			)
			(layer "F.SilkS")
		)
		(fp_line
			(start -8.5 3.297)
			(end -8.5 2.797)
			(stroke
				(width 0.15)
				(type solid)
			)
			(layer "F.SilkS")
		)
		(fp_line
			(start -8.5 3.297)
			(end -8 3.297)
			(stroke
				(width 0.15)
				(type solid)
			)
			(layer "F.SilkS")
		)
		(fp_circle
			(center -6.8 3.4)
			(end -6.748 3.4)
			(stroke
				(width 0.15)
				(type solid)
			)
			(fill yes)
			(layer "F.SilkS")
		)
		(fp_rect
			(start -8.7 -3.7)
			(end 8.7 3.7)
			(stroke
				(width 0.05)
				(type solid)
			)
			(fill no)
			(layer "F.CrtYd")
		)
		(fp_line
			(start -8.325 -3.15)
			(end 8.323 -3.15)
			(stroke
				(width 0.15)
				(type solid)
			)
			(layer "F.Fab")
		)
		(fp_line
			(start 1.394 2.41)
			(end 1.394 3.14)
			(stroke
				(width 0.15)
				(type solid)
			)
			(layer "F.Fab")
		)
		(fp_line
			(start -1.397 2.41)
			(end 1.394 2.41)
			(stroke
				(width 0.15)
				(type solid)
			)
			(layer "F.Fab")
		)
		(fp_line
			(start -1.397 2.41)
			(end -1.397 3.14)
			(stroke
				(width 0.15)
				(type solid)
			)
			(layer "F.Fab")
		)
		(fp_line
			(start 8.323 3.148)
			(end 8.323 -3.15)
			(stroke
				(width 0.15)
				(type solid)
			)
			(layer "F.Fab")
		)
		(fp_line
			(start 1.394 3.148)
			(end 8.323 3.148)
			(stroke
				(width 0.15)
				(type solid)
			)
			(layer "F.Fab")
		)
		(fp_line
			(start -8.325 3.148)
			(end -8.325 -3.15)
			(stroke
				(width 0.15)
				(type solid)
			)
			(layer "F.Fab")
		)
		(fp_line
			(start -8.325 3.148)
			(end -1.397 3.148)
			(stroke
				(width 0.15)
				(type solid)
			)
			(layer "F.Fab")
		)
		(pad "1" smd rect
			(at -6 2.128 90)
			(size 1 2.75)
			(layers "F.Cu" "F.Mask" "F.Paste")
			(net 1 "GND")
			(pintype "passive")
		)
		(pad "2" smd rect
			(at -6 -2.13 90)
			(size 1 2.75)
			(layers "F.Cu" "F.Mask" "F.Paste")
			(net 200 "+3V3")
			(pintype "passive")
		)
		(pad "3" smd rect
			(at -4 2.128 90)
			(size 1 2.75)
			(layers "F.Cu" "F.Mask" "F.Paste")
			(net 1 "GND")
			(pintype "passive")
		)
		(pad "4" smd rect
			(at -4 -2.13 90)
			(size 1 2.75)
			(layers "F.Cu" "F.Mask" "F.Paste")
			(net 45 "/Debug FTDI/JTAG.TMS")
			(pintype "passive")
		)
		(pad "5" smd rect
			(at -2 2.128 90)
			(size 1 2.75)
			(layers "F.Cu" "F.Mask" "F.Paste")
			(net 1 "GND")
			(pintype "passive")
		)
		(pad "6" smd rect
			(at -2 -2.13 90)
			(size 1 2.75)
			(layers "F.Cu" "F.Mask" "F.Paste")
			(net 46 "/Debug FTDI/JTAG.TCK")
			(pintype "passive")
		)
		(pad "7" smd rect
			(at 0 2.128 90)
			(size 1 2.75)
			(layers "F.Cu" "F.Mask" "F.Paste")
			(net 1 "GND")
			(pintype "passive")
		)
		(pad "8" smd rect
			(at 0 -2.13 90)
			(size 1 2.75)
			(layers "F.Cu" "F.Mask" "F.Paste")
			(net 47 "/Debug FTDI/JTAG.TDO")
			(pintype "passive")
		)
		(pad "9" smd rect
			(at 1.999 2.128 90)
			(size 1 2.75)
			(layers "F.Cu" "F.Mask" "F.Paste")
			(net 1 "GND")
			(pintype "passive")
		)
		(pad "10" smd rect
			(at 1.999 -2.13 90)
			(size 1 2.75)
			(layers "F.Cu" "F.Mask" "F.Paste")
			(net 48 "/Debug FTDI/JTAG.TDI")
			(pintype "passive")
		)
		(pad "11" smd rect
			(at 3.999 2.128 90)
			(size 1 2.75)
			(layers "F.Cu" "F.Mask" "F.Paste")
			(net 1 "GND")
			(pintype "passive")
		)
		(pad "12" smd rect
			(at 3.999 -2.13 90)
			(size 1 2.75)
			(layers "F.Cu" "F.Mask" "F.Paste")
			(net 319 "unconnected-(J1-Pad12)")
			(pintype "passive+no_connect")
		)
		(pad "13" smd rect
			(at 5.998 2.128 90)
			(size 1 2.75)
			(layers "F.Cu" "F.Mask" "F.Paste")
			(net 1 "GND")
			(pintype "passive")
		)
		(pad "14" smd rect
			(at 5.998 -2.13 90)
			(size 1 2.75)
			(layers "F.Cu" "F.Mask" "F.Paste")
			(net 320 "unconnected-(J1-Pad14)")
			(pintype "passive+no_connect")
		)
	)
	(footprint "antmicro-footprints:R_0402_1005Metric"
		(layer "B.Cu")
		(at 98 180.95 -90)
		(descr "Resistor SMD 0402")
		(tags "resistor SMD 0402")
		(property "Reference" "R56"
			(at -1.122484 0.772697 90)
			(layer "B.SilkS")
			(hide yes)
			(effects
				(font
					(size 0.7 0.7)
					(thickness 0.15)
				)
				(justify left bottom mirror)
			)
		)
		(property "Value" "R_22R_0402"
			(at -1.011843 -1.772047 90)
			(layer "B.Fab")
			(effects
				(font
					(size 0.7 0.7)
					(thickness 0.15)
				)
				(justify left bottom mirror)
			)
		)
		(property "Datasheet" "https://www.bourns.com/docs/product-datasheets/cr.pdf"
			(at 0 0 270)
			(layer "F.Fab")
			(hide yes)
			(effects
				(font
					(size 1.27 1.27)
					(thickness 0.15)
				)
			)
		)
		(property "Author" "Antmicro"
			(at -82.95 278.95 0)
			(layer "B.Fab")
			(hide yes)
			(effects
				(font
					(size 1 1)
					(thickness 0.15)
				)
				(justify mirror)
			)
		)
		(property "License" "Apache-2.0"
			(at -82.95 278.95 0)
			(layer "B.Fab")
			(hide yes)
			(effects
				(font
					(size 1 1)
					(thickness 0.15)
				)
				(justify mirror)
			)
		)
		(property "MPN" "CR0402-FX-22R0GLF"
			(at -82.95 278.95 0)
			(layer "B.Fab")
			(hide yes)
			(effects
				(font
					(size 1 1)
					(thickness 0.15)
				)
				(justify mirror)
			)
		)
		(property "Manufacturer" "Bourns"
			(at -82.95 278.95 0)
			(layer "B.Fab")
			(hide yes)
			(effects
				(font
					(size 1 1)
					(thickness 0.15)
				)
				(justify mirror)
			)
		)
		(property "Tolerance" "1%"
			(at -82.95 278.95 0)
			(layer "B.Fab")
			(hide yes)
			(effects
				(font
					(size 1 1)
					(thickness 0.15)
				)
				(justify mirror)
			)
		)
		(property "Val" "22R"
			(at -82.95 278.95 0)
			(layer "B.Fab")
			(hide yes)
			(effects
				(font
					(size 1 1)
					(thickness 0.15)
				)
				(justify mirror)
			)
		)
		(sheetname "/Debug FTDI/")
		(sheetfile "debug-ftdi.kicad_sch")
		(attr exclude_from_pos_files exclude_from_bom dnp)
		(fp_rect
			(start -0.93 0.47)
			(end 0.93 -0.47)
			(stroke
				(width 0.05)
				(type solid)
			)
			(fill no)
			(layer "B.CrtYd")
		)
		(fp_rect
			(start -0.5 0.25)
			(end 0.5 -0.25)
			(stroke
				(width 0.15)
				(type solid)
			)
			(fill no)
			(layer "B.Fab")
		)
		(pad "1" smd roundrect
			(at -0.485 0 270)
			(size 0.59 0.64)
			(layers "B.Cu" "B.Mask" "B.Paste")
			(roundrect_rratio 0.25)
			(net 646 "/Debug FTDI/BDBUS0")
			(pintype "passive")
		)
		(pad "2" smd roundrect
			(at 0.485 0 270)
			(size 0.59 0.64)
			(layers "B.Cu" "B.Mask" "B.Paste")
			(roundrect_rratio 0.25)
			(net 647 "/Debug FTDI/AUX.TCK")
			(pintype "passive")
		)
	)
	(footprint "antmicro-footprints:R_0402_1005Metric"
		(layer "B.Cu")
		(at 99.05 180.95 -90)
		(descr "Resistor SMD 0402")
		(tags "resistor SMD 0402")
		(property "Reference" "R57"
			(at -1.122484 0.772697 90)
			(layer "B.SilkS")
			(hide yes)
			(effects
				(font
					(size 0.7 0.7)
					(thickness 0.15)
				)
				(justify left bottom mirror)
			)
		)
		(property "Value" "R_22R_0402"
			(at -1.011843 -1.772047 90)
			(layer "B.Fab")
			(effects
				(font
					(size 0.7 0.7)
					(thickness 0.15)
				)
				(justify left bottom mirror)
			)
		)
		(property "Datasheet" "https://www.bourns.com/docs/product-datasheets/cr.pdf"
			(at 0 0 270)
			(layer "F.Fab")
			(hide yes)
			(effects
				(font
					(size 1.27 1.27)
					(thickness 0.15)
				)
			)
		)
		(property "Author" "Antmicro"
			(at -81.9 280 0)
			(layer "B.Fab")
			(hide yes)
			(effects
				(font
					(size 1 1)
					(thickness 0.15)
				)
				(justify mirror)
			)
		)
		(property "License" "Apache-2.0"
			(at -81.9 280 0)
			(layer "B.Fab")
			(hide yes)
			(effects
				(font
					(size 1 1)
					(thickness 0.15)
				)
				(justify mirror)
			)
		)
		(property "MPN" "CR0402-FX-22R0GLF"
			(at -81.9 280 0)
			(layer "B.Fab")
			(hide yes)
			(effects
				(font
					(size 1 1)
					(thickness 0.15)
				)
				(justify mirror)
			)
		)
		(property "Manufacturer" "Bourns"
			(at -81.9 280 0)
			(layer "B.Fab")
			(hide yes)
			(effects
				(font
					(size 1 1)
					(thickness 0.15)
				)
				(justify mirror)
			)
		)
		(property "Tolerance" "1%"
			(at -81.9 280 0)
			(layer "B.Fab")
			(hide yes)
			(effects
				(font
					(size 1 1)
					(thickness 0.15)
				)
				(justify mirror)
			)
		)
		(property "Val" "22R"
			(at -81.9 280 0)
			(layer "B.Fab")
			(hide yes)
			(effects
				(font
					(size 1 1)
					(thickness 0.15)
				)
				(justify mirror)
			)
		)
		(sheetname "/Debug FTDI/")
		(sheetfile "debug-ftdi.kicad_sch")
		(attr exclude_from_pos_files exclude_from_bom dnp)
		(fp_rect
			(start -0.93 0.47)
			(end 0.93 -0.47)
			(stroke
				(width 0.05)
				(type solid)
			)
			(fill no)
			(layer "B.CrtYd")
		)
		(fp_rect
			(start -0.5 0.25)
			(end 0.5 -0.25)
			(stroke
				(width 0.15)
				(type solid)
			)
			(fill no)
			(layer "B.Fab")
		)
		(pad "1" smd roundrect
			(at -0.485 0 270)
			(size 0.59 0.64)
			(layers "B.Cu" "B.Mask" "B.Paste")
			(roundrect_rratio 0.25)
			(net 648 "/Debug FTDI/BDBUS1")
			(pintype "passive")
		)
		(pad "2" smd roundrect
			(at 0.485 0 270)
			(size 0.59 0.64)
			(layers "B.Cu" "B.Mask" "B.Paste")
			(roundrect_rratio 0.25)
			(net 649 "/Debug FTDI/AUX.TDI")
			(pintype "passive")
		)
	)
	(footprint "antmicro-footprints:R_0402_1005Metric"
		(layer "B.Cu")
		(at 100.1 180.95 -90)
		(descr "Resistor SMD 0402")
		(tags "resistor SMD 0402")
		(property "Reference" "R58"
			(at -1.122484 0.772697 90)
			(layer "B.SilkS")
			(hide yes)
			(effects
				(font
					(size 0.7 0.7)
					(thickness 0.15)
				)
				(justify left bottom mirror)
			)
		)
		(property "Value" "R_22R_0402"
			(at -1.011843 -1.772047 90)
			(layer "B.Fab")
			(effects
				(font
					(size 0.7 0.7)
					(thickness 0.15)
				)
				(justify left bottom mirror)
			)
		)
		(property "Datasheet" "https://www.bourns.com/docs/product-datasheets/cr.pdf"
			(at 0 0 270)
			(layer "F.Fab")
			(hide yes)
			(effects
				(font
					(size 1.27 1.27)
					(thickness 0.15)
				)
			)
		)
		(property "Author" "Antmicro"
			(at -80.85 281.05 0)
			(layer "B.Fab")
			(hide yes)
			(effects
				(font
					(size 1 1)
					(thickness 0.15)
				)
				(justify mirror)
			)
		)
		(property "License" "Apache-2.0"
			(at -80.85 281.05 0)
			(layer "B.Fab")
			(hide yes)
			(effects
				(font
					(size 1 1)
					(thickness 0.15)
				)
				(justify mirror)
			)
		)
		(property "MPN" "CR0402-FX-22R0GLF"
			(at -80.85 281.05 0)
			(layer "B.Fab")
			(hide yes)
			(effects
				(font
					(size 1 1)
					(thickness 0.15)
				)
				(justify mirror)
			)
		)
		(property "Manufacturer" "Bourns"
			(at -80.85 281.05 0)
			(layer "B.Fab")
			(hide yes)
			(effects
				(font
					(size 1 1)
					(thickness 0.15)
				)
				(justify mirror)
			)
		)
		(property "Tolerance" "1%"
			(at -80.85 281.05 0)
			(layer "B.Fab")
			(hide yes)
			(effects
				(font
					(size 1 1)
					(thickness 0.15)
				)
				(justify mirror)
			)
		)
		(property "Val" "22R"
			(at -80.85 281.05 0)
			(layer "B.Fab")
			(hide yes)
			(effects
				(font
					(size 1 1)
					(thickness 0.15)
				)
				(justify mirror)
			)
		)
		(sheetname "/Debug FTDI/")
		(sheetfile "debug-ftdi.kicad_sch")
		(attr exclude_from_pos_files exclude_from_bom dnp)
		(fp_rect
			(start -0.93 0.47)
			(end 0.93 -0.47)
			(stroke
				(width 0.05)
				(type solid)
			)
			(fill no)
			(layer "B.CrtYd")
		)
		(fp_rect
			(start -0.5 0.25)
			(end 0.5 -0.25)
			(stroke
				(width 0.15)
				(type solid)
			)
			(fill no)
			(layer "B.Fab")
		)
		(pad "1" smd roundrect
			(at -0.485 0 270)
			(size 0.59 0.64)
			(layers "B.Cu" "B.Mask" "B.Paste")
			(roundrect_rratio 0.25)
			(net 650 "/Debug FTDI/BDBUS2")
			(pintype "passive")
		)
		(pad "2" smd roundrect
			(at 0.485 0 270)
			(size 0.59 0.64)
			(layers "B.Cu" "B.Mask" "B.Paste")
			(roundrect_rratio 0.25)
			(net 651 "/Debug FTDI/AUX.TDO")
			(pintype "passive")
		)
	)
	(footprint "antmicro-footprints:R_0402_1005Metric"
		(layer "B.Cu")
		(at 102.2 180.95 -90)
		(descr "Resistor SMD 0402")
		(tags "resistor SMD 0402")
		(property "Reference" "R60"
			(at -1.122484 0.772697 90)
			(layer "B.SilkS")
			(hide yes)
			(effects
				(font
					(size 0.7 0.7)
					(thickness 0.15)
				)
				(justify left bottom mirror)
			)
		)
		(property "Value" "R_22R_0402"
			(at -1.011843 -1.772047 90)
			(layer "B.Fab")
			(effects
				(font
					(size 0.7 0.7)
					(thickness 0.15)
				)
				(justify left bottom mirror)
			)
		)
		(property "Datasheet" "https://www.bourns.com/docs/product-datasheets/cr.pdf"
			(at 0 0 270)
			(layer "F.Fab")
			(hide yes)
			(effects
				(font
					(size 1.27 1.27)
					(thickness 0.15)
				)
			)
		)
		(property "Author" "Antmicro"
			(at -78.75 283.15 0)
			(layer "B.Fab")
			(hide yes)
			(effects
				(font
					(size 1 1)
					(thickness 0.15)
				)
				(justify mirror)
			)
		)
		(property "License" "Apache-2.0"
			(at -78.75 283.15 0)
			(layer "B.Fab")
			(hide yes)
			(effects
				(font
					(size 1 1)
					(thickness 0.15)
				)
				(justify mirror)
			)
		)
		(property "MPN" "CR0402-FX-22R0GLF"
			(at -78.75 283.15 0)
			(layer "B.Fab")
			(hide yes)
			(effects
				(font
					(size 1 1)
					(thickness 0.15)
				)
				(justify mirror)
			)
		)
		(property "Manufacturer" "Bourns"
			(at -78.75 283.15 0)
			(layer "B.Fab")
			(hide yes)
			(effects
				(font
					(size 1 1)
					(thickness 0.15)
				)
				(justify mirror)
			)
		)
		(property "Tolerance" "1%"
			(at -78.75 283.15 0)
			(layer "B.Fab")
			(hide yes)
			(effects
				(font
					(size 1 1)
					(thickness 0.15)
				)
				(justify mirror)
			)
		)
		(property "Val" "22R"
			(at -78.75 283.15 0)
			(layer "B.Fab")
			(hide yes)
			(effects
				(font
					(size 1 1)
					(thickness 0.15)
				)
				(justify mirror)
			)
		)
		(sheetname "/Debug FTDI/")
		(sheetfile "debug-ftdi.kicad_sch")
		(attr exclude_from_pos_files exclude_from_bom dnp)
		(fp_rect
			(start -0.93 0.47)
			(end 0.93 -0.47)
			(stroke
				(width 0.05)
				(type solid)
			)
			(fill no)
			(layer "B.CrtYd")
		)
		(fp_rect
			(start -0.5 0.25)
			(end 0.5 -0.25)
			(stroke
				(width 0.15)
				(type solid)
			)
			(fill no)
			(layer "B.Fab")
		)
		(pad "1" smd roundrect
			(at -0.485 0 270)
			(size 0.59 0.64)
			(layers "B.Cu" "B.Mask" "B.Paste")
			(roundrect_rratio 0.25)
			(net 654 "/Debug FTDI/I2C_EN")
			(pintype "passive")
		)
		(pad "2" smd roundrect
			(at 0.485 0 270)
			(size 0.59 0.64)
			(layers "B.Cu" "B.Mask" "B.Paste")
			(roundrect_rratio 0.25)
			(net 655 "/Debug FTDI/AUX.RST")
			(pintype "passive")
		)
	)
	(footprint "antmicro-footprints:R_0402_1005Metric"
		(layer "B.Cu")
		(at 101.15 180.95 -90)
		(descr "Resistor SMD 0402")
		(tags "resistor SMD 0402")
		(property "Reference" "R59"
			(at -1.122484 0.772697 90)
			(layer "B.SilkS")
			(hide yes)
			(effects
				(font
					(size 0.7 0.7)
					(thickness 0.15)
				)
				(justify left bottom mirror)
			)
		)
		(property "Value" "R_22R_0402"
			(at -1.011843 -1.772047 90)
			(layer "B.Fab")
			(effects
				(font
					(size 0.7 0.7)
					(thickness 0.15)
				)
				(justify left bottom mirror)
			)
		)
		(property "Datasheet" "https://www.bourns.com/docs/product-datasheets/cr.pdf"
			(at 0 0 270)
			(layer "F.Fab")
			(hide yes)
			(effects
				(font
					(size 1.27 1.27)
					(thickness 0.15)
				)
			)
		)
		(property "Author" "Antmicro"
			(at -79.8 282.1 0)
			(layer "B.Fab")
			(hide yes)
			(effects
				(font
					(size 1 1)
					(thickness 0.15)
				)
				(justify mirror)
			)
		)
		(property "License" "Apache-2.0"
			(at -79.8 282.1 0)
			(layer "B.Fab")
			(hide yes)
			(effects
				(font
					(size 1 1)
					(thickness 0.15)
				)
				(justify mirror)
			)
		)
		(property "MPN" "CR0402-FX-22R0GLF"
			(at -79.8 282.1 0)
			(layer "B.Fab")
			(hide yes)
			(effects
				(font
					(size 1 1)
					(thickness 0.15)
				)
				(justify mirror)
			)
		)
		(property "Manufacturer" "Bourns"
			(at -79.8 282.1 0)
			(layer "B.Fab")
			(hide yes)
			(effects
				(font
					(size 1 1)
					(thickness 0.15)
				)
				(justify mirror)
			)
		)
		(property "Tolerance" "1%"
			(at -79.8 282.1 0)
			(layer "B.Fab")
			(hide yes)
			(effects
				(font
					(size 1 1)
					(thickness 0.15)
				)
				(justify mirror)
			)
		)
		(property "Val" "22R"
			(at -79.8 282.1 0)
			(layer "B.Fab")
			(hide yes)
			(effects
				(font
					(size 1 1)
					(thickness 0.15)
				)
				(justify mirror)
			)
		)
		(sheetname "/Debug FTDI/")
		(sheetfile "debug-ftdi.kicad_sch")
		(attr exclude_from_pos_files exclude_from_bom dnp)
		(fp_rect
			(start -0.93 0.47)
			(end 0.93 -0.47)
			(stroke
				(width 0.05)
				(type solid)
			)
			(fill no)
			(layer "B.CrtYd")
		)
		(fp_rect
			(start -0.5 0.25)
			(end 0.5 -0.25)
			(stroke
				(width 0.15)
				(type solid)
			)
			(fill no)
			(layer "B.Fab")
		)
		(pad "1" smd roundrect
			(at -0.485 0 270)
			(size 0.59 0.64)
			(layers "B.Cu" "B.Mask" "B.Paste")
			(roundrect_rratio 0.25)
			(net 652 "/Debug FTDI/BDBUS3")
			(pintype "passive")
		)
		(pad "2" smd roundrect
			(at 0.485 0 270)
			(size 0.59 0.64)
			(layers "B.Cu" "B.Mask" "B.Paste")
			(roundrect_rratio 0.25)
			(net 653 "/Debug FTDI/AUX.TMS")
			(pintype "passive")
		)
	)
	(footprint "antmicro-footprints:R_0402_1005Metric"
		(layer "B.Cu")
		(at 84.75 171.4)
		(descr "Resistor SMD 0402")
		(tags "resistor SMD 0402")
		(property "Reference" "R83"
			(at -1.122484 0.772697 180)
			(layer "B.SilkS")
			(hide yes)
			(effects
				(font
					(size 0.7 0.7)
					(thickness 0.15)
				)
				(justify left bottom mirror)
			)
		)
		(property "Value" "R_20k_0402"
			(at -1.011843 -1.772047 180)
			(layer "B.Fab")
			(effects
				(font
					(size 0.7 0.7)
					(thickness 0.15)
				)
				(justify left bottom mirror)
			)
		)
		(property "Datasheet" "https://www.bourns.com/docs/product-datasheets/cr.pdf"
			(at 0 0 0)
			(layer "F.Fab")
			(hide yes)
			(effects
				(font
					(size 1.27 1.27)
					(thickness 0.15)
				)
			)
		)
		(property "Author" "Antmicro"
			(at 0 0 0)
			(layer "B.Fab")
			(hide yes)
			(effects
				(font
					(size 1 1)
					(thickness 0.15)
				)
				(justify mirror)
			)
		)
		(property "License" "Apache-2.0"
			(at 0 0 0)
			(layer "B.Fab")
			(hide yes)
			(effects
				(font
					(size 1 1)
					(thickness 0.15)
				)
				(justify mirror)
			)
		)
		(property "MPN" "CR0402-FX-2002GLF"
			(at 0 0 0)
			(layer "B.Fab")
			(hide yes)
			(effects
				(font
					(size 1 1)
					(thickness 0.15)
				)
				(justify mirror)
			)
		)
		(property "Manufacturer" "Bourns"
			(at 0 0 0)
			(layer "B.Fab")
			(hide yes)
			(effects
				(font
					(size 1 1)
					(thickness 0.15)
				)
				(justify mirror)
			)
		)
		(property "Tolerance" "1%"
			(at 0 0 0)
			(layer "B.Fab")
			(hide yes)
			(effects
				(font
					(size 1 1)
					(thickness 0.15)
				)
				(justify mirror)
			)
		)
		(property "Val" "20k"
			(at 0 0 0)
			(layer "B.Fab")
			(hide yes)
			(effects
				(font
					(size 1 1)
					(thickness 0.15)
				)
				(justify mirror)
			)
		)
		(sheetname "/HDMI + SD Card/")
		(sheetfile "hdmi-sd-card.kicad_sch")
		(attr smd)
		(fp_rect
			(start -0.93 0.47)
			(end 0.93 -0.47)
			(stroke
				(width 0.05)
				(type solid)
			)
			(fill no)
			(layer "B.CrtYd")
		)
		(fp_rect
			(start -0.5 0.25)
			(end 0.5 -0.25)
			(stroke
				(width 0.15)
				(type solid)
			)
			(fill no)
			(layer "B.Fab")
		)
		(pad "1" smd roundrect
			(at -0.485 0)
			(size 0.59 0.64)
			(layers "B.Cu" "B.Mask" "B.Paste")
			(roundrect_rratio 0.25)
			(net 200 "+3V3")
			(pintype "passive")
		)
		(pad "2" smd roundrect
			(at 0.485 0)
			(size 0.59 0.64)
			(layers "B.Cu" "B.Mask" "B.Paste")
			(roundrect_rratio 0.25)
			(net 373 "/FPGA bank 16/SD.CLK")
			(pintype "passive")
		)
	)
	(footprint "antmicro-footprints:R_0402_1005Metric"
		(layer "B.Cu")
		(at 84.75 172.4)
		(descr "Resistor SMD 0402")
		(tags "resistor SMD 0402")
		(property "Reference" "R85"
			(at -1.122484 0.772697 180)
			(layer "B.SilkS")
			(hide yes)
			(effects
				(font
					(size 0.7 0.7)
					(thickness 0.15)
				)
				(justify left bottom mirror)
			)
		)
		(property "Value" "R_20k_0402"
			(at -1.011843 -1.772047 180)
			(layer "B.Fab")
			(effects
				(font
					(size 0.7 0.7)
					(thickness 0.15)
				)
				(justify left bottom mirror)
			)
		)
		(property "Datasheet" "https://www.bourns.com/docs/product-datasheets/cr.pdf"
			(at 0 0 0)
			(layer "F.Fab")
			(hide yes)
			(effects
				(font
					(size 1.27 1.27)
					(thickness 0.15)
				)
			)
		)
		(property "Author" "Antmicro"
			(at 0 0 0)
			(layer "B.Fab")
			(hide yes)
			(effects
				(font
					(size 1 1)
					(thickness 0.15)
				)
				(justify mirror)
			)
		)
		(property "License" "Apache-2.0"
			(at 0 0 0)
			(layer "B.Fab")
			(hide yes)
			(effects
				(font
					(size 1 1)
					(thickness 0.15)
				)
				(justify mirror)
			)
		)
		(property "MPN" "CR0402-FX-2002GLF"
			(at 0 0 0)
			(layer "B.Fab")
			(hide yes)
			(effects
				(font
					(size 1 1)
					(thickness 0.15)
				)
				(justify mirror)
			)
		)
		(property "Manufacturer" "Bourns"
			(at 0 0 0)
			(layer "B.Fab")
			(hide yes)
			(effects
				(font
					(size 1 1)
					(thickness 0.15)
				)
				(justify mirror)
			)
		)
		(property "Tolerance" "1%"
			(at 0 0 0)
			(layer "B.Fab")
			(hide yes)
			(effects
				(font
					(size 1 1)
					(thickness 0.15)
				)
				(justify mirror)
			)
		)
		(property "Val" "20k"
			(at 0 0 0)
			(layer "B.Fab")
			(hide yes)
			(effects
				(font
					(size 1 1)
					(thickness 0.15)
				)
				(justify mirror)
			)
		)
		(sheetname "/HDMI + SD Card/")
		(sheetfile "hdmi-sd-card.kicad_sch")
		(attr smd)
		(fp_rect
			(start -0.93 0.47)
			(end 0.93 -0.47)
			(stroke
				(width 0.05)
				(type solid)
			)
			(fill no)
			(layer "B.CrtYd")
		)
		(fp_rect
			(start -0.5 0.25)
			(end 0.5 -0.25)
			(stroke
				(width 0.15)
				(type solid)
			)
			(fill no)
			(layer "B.Fab")
		)
		(pad "1" smd roundrect
			(at -0.485 0)
			(size 0.59 0.64)
			(layers "B.Cu" "B.Mask" "B.Paste")
			(roundrect_rratio 0.25)
			(net 200 "+3V3")
			(pintype "passive")
		)
		(pad "2" smd roundrect
			(at 0.485 0)
			(size 0.59 0.64)
			(layers "B.Cu" "B.Mask" "B.Paste")
			(roundrect_rratio 0.25)
			(net 372 "/FPGA bank 16/SD.CMD")
			(pintype "passive")
		)
	)
	(footprint "antmicro-footprints:R_0402_1005Metric"
		(layer "B.Cu")
		(at 84.75 167.9)
		(descr "Resistor SMD 0402")
		(tags "resistor SMD 0402")
		(property "Reference" "R81"
			(at -1.122484 0.772697 180)
			(layer "B.SilkS")
			(hide yes)
			(effects
				(font
					(size 0.7 0.7)
					(thickness 0.15)
				)
				(justify left bottom mirror)
			)
		)
		(property "Value" "R_20k_0402"
			(at -1.011843 -1.772047 180)
			(layer "B.Fab")
			(effects
				(font
					(size 0.7 0.7)
					(thickness 0.15)
				)
				(justify left bottom mirror)
			)
		)
		(property "Datasheet" "https://www.bourns.com/docs/product-datasheets/cr.pdf"
			(at 0 0 0)
			(layer "F.Fab")
			(hide yes)
			(effects
				(font
					(size 1.27 1.27)
					(thickness 0.15)
				)
			)
		)
		(property "Author" "Antmicro"
			(at 0 0 0)
			(layer "B.Fab")
			(hide yes)
			(effects
				(font
					(size 1 1)
					(thickness 0.15)
				)
				(justify mirror)
			)
		)
		(property "License" "Apache-2.0"
			(at 0 0 0)
			(layer "B.Fab")
			(hide yes)
			(effects
				(font
					(size 1 1)
					(thickness 0.15)
				)
				(justify mirror)
			)
		)
		(property "MPN" "CR0402-FX-2002GLF"
			(at 0 0 0)
			(layer "B.Fab")
			(hide yes)
			(effects
				(font
					(size 1 1)
					(thickness 0.15)
				)
				(justify mirror)
			)
		)
		(property "Manufacturer" "Bourns"
			(at 0 0 0)
			(layer "B.Fab")
			(hide yes)
			(effects
				(font
					(size 1 1)
					(thickness 0.15)
				)
				(justify mirror)
			)
		)
		(property "Tolerance" "1%"
			(at 0 0 0)
			(layer "B.Fab")
			(hide yes)
			(effects
				(font
					(size 1 1)
					(thickness 0.15)
				)
				(justify mirror)
			)
		)
		(property "Val" "20k"
			(at 0 0 0)
			(layer "B.Fab")
			(hide yes)
			(effects
				(font
					(size 1 1)
					(thickness 0.15)
				)
				(justify mirror)
			)
		)
		(sheetname "/HDMI + SD Card/")
		(sheetfile "hdmi-sd-card.kicad_sch")
		(attr smd)
		(fp_rect
			(start -0.93 0.47)
			(end 0.93 -0.47)
			(stroke
				(width 0.05)
				(type solid)
			)
			(fill no)
			(layer "B.CrtYd")
		)
		(fp_rect
			(start -0.5 0.25)
			(end 0.5 -0.25)
			(stroke
				(width 0.15)
				(type solid)
			)
			(fill no)
			(layer "B.Fab")
		)
		(pad "1" smd roundrect
			(at -0.485 0)
			(size 0.59 0.64)
			(layers "B.Cu" "B.Mask" "B.Paste")
			(roundrect_rratio 0.25)
			(net 200 "+3V3")
			(pintype "passive")
		)
		(pad "2" smd roundrect
			(at 0.485 0)
			(size 0.59 0.64)
			(layers "B.Cu" "B.Mask" "B.Paste")
			(roundrect_rratio 0.25)
			(net 594 "/FPGA bank 16/SD.DAT1")
			(pintype "passive")
		)
	)
	(footprint "antmicro-footprints:R_0402_1005Metric"
		(layer "B.Cu")
		(at 84.745499 166.884)
		(descr "Resistor SMD 0402")
		(tags "resistor SMD 0402")
		(property "Reference" "R80"
			(at -1.122484 0.772697 180)
			(layer "B.SilkS")
			(hide yes)
			(effects
				(font
					(size 0.7 0.7)
					(thickness 0.15)
				)
				(justify left bottom mirror)
			)
		)
		(property "Value" "R_20k_0402"
			(at -1.011843 -1.772047 180)
			(layer "B.Fab")
			(effects
				(font
					(size 0.7 0.7)
					(thickness 0.15)
				)
				(justify left bottom mirror)
			)
		)
		(property "Datasheet" "https://www.bourns.com/docs/product-datasheets/cr.pdf"
			(at 0 0 0)
			(layer "F.Fab")
			(hide yes)
			(effects
				(font
					(size 1.27 1.27)
					(thickness 0.15)
				)
			)
		)
		(property "Author" "Antmicro"
			(at 0 0 0)
			(layer "B.Fab")
			(hide yes)
			(effects
				(font
					(size 1 1)
					(thickness 0.15)
				)
				(justify mirror)
			)
		)
		(property "License" "Apache-2.0"
			(at 0 0 0)
			(layer "B.Fab")
			(hide yes)
			(effects
				(font
					(size 1 1)
					(thickness 0.15)
				)
				(justify mirror)
			)
		)
		(property "MPN" "CR0402-FX-2002GLF"
			(at 0 0 0)
			(layer "B.Fab")
			(hide yes)
			(effects
				(font
					(size 1 1)
					(thickness 0.15)
				)
				(justify mirror)
			)
		)
		(property "Manufacturer" "Bourns"
			(at 0 0 0)
			(layer "B.Fab")
			(hide yes)
			(effects
				(font
					(size 1 1)
					(thickness 0.15)
				)
				(justify mirror)
			)
		)
		(property "Tolerance" "1%"
			(at 0 0 0)
			(layer "B.Fab")
			(hide yes)
			(effects
				(font
					(size 1 1)
					(thickness 0.15)
				)
				(justify mirror)
			)
		)
		(property "Val" "20k"
			(at 0 0 0)
			(layer "B.Fab")
			(hide yes)
			(effects
				(font
					(size 1 1)
					(thickness 0.15)
				)
				(justify mirror)
			)
		)
		(sheetname "/HDMI + SD Card/")
		(sheetfile "hdmi-sd-card.kicad_sch")
		(attr smd)
		(fp_rect
			(start -0.93 0.47)
			(end 0.93 -0.47)
			(stroke
				(width 0.05)
				(type solid)
			)
			(fill no)
			(layer "B.CrtYd")
		)
		(fp_rect
			(start -0.5 0.25)
			(end 0.5 -0.25)
			(stroke
				(width 0.15)
				(type solid)
			)
			(fill no)
			(layer "B.Fab")
		)
		(pad "1" smd roundrect
			(at -0.485 0)
			(size 0.59 0.64)
			(layers "B.Cu" "B.Mask" "B.Paste")
			(roundrect_rratio 0.25)
			(net 200 "+3V3")
			(pintype "passive")
		)
		(pad "2" smd roundrect
			(at 0.485 0)
			(size 0.59 0.64)
			(layers "B.Cu" "B.Mask" "B.Paste")
			(roundrect_rratio 0.25)
			(net 669 "/FPGA bank 16/SD.CD")
			(pintype "passive")
		)
	)
	(footprint "antmicro-footprints:R_0402_1005Metric"
		(layer "B.Cu")
		(at 84.76 168.925)
		(descr "Resistor SMD 0402")
		(tags "resistor SMD 0402")
		(property "Reference" "R82"
			(at -1.122484 0.772697 180)
			(layer "B.SilkS")
			(hide yes)
			(effects
				(font
					(size 0.7 0.7)
					(thickness 0.15)
				)
				(justify left bottom mirror)
			)
		)
		(property "Value" "R_20k_0402"
			(at -1.011843 -1.772047 180)
			(layer "B.Fab")
			(effects
				(font
					(size 0.7 0.7)
					(thickness 0.15)
				)
				(justify left bottom mirror)
			)
		)
		(property "Datasheet" "https://www.bourns.com/docs/product-datasheets/cr.pdf"
			(at 0 0 0)
			(layer "F.Fab")
			(hide yes)
			(effects
				(font
					(size 1.27 1.27)
					(thickness 0.15)
				)
			)
		)
		(property "Author" "Antmicro"
			(at 0 0 0)
			(layer "B.Fab")
			(hide yes)
			(effects
				(font
					(size 1 1)
					(thickness 0.15)
				)
				(justify mirror)
			)
		)
		(property "License" "Apache-2.0"
			(at 0 0 0)
			(layer "B.Fab")
			(hide yes)
			(effects
				(font
					(size 1 1)
					(thickness 0.15)
				)
				(justify mirror)
			)
		)
		(property "MPN" "CR0402-FX-2002GLF"
			(at 0 0 0)
			(layer "B.Fab")
			(hide yes)
			(effects
				(font
					(size 1 1)
					(thickness 0.15)
				)
				(justify mirror)
			)
		)
		(property "Manufacturer" "Bourns"
			(at 0 0 0)
			(layer "B.Fab")
			(hide yes)
			(effects
				(font
					(size 1 1)
					(thickness 0.15)
				)
				(justify mirror)
			)
		)
		(property "Tolerance" "1%"
			(at 0 0 0)
			(layer "B.Fab")
			(hide yes)
			(effects
				(font
					(size 1 1)
					(thickness 0.15)
				)
				(justify mirror)
			)
		)
		(property "Val" "20k"
			(at 0 0 0)
			(layer "B.Fab")
			(hide yes)
			(effects
				(font
					(size 1 1)
					(thickness 0.15)
				)
				(justify mirror)
			)
		)
		(sheetname "/HDMI + SD Card/")
		(sheetfile "hdmi-sd-card.kicad_sch")
		(attr smd)
		(fp_rect
			(start -0.93 0.47)
			(end 0.93 -0.47)
			(stroke
				(width 0.05)
				(type solid)
			)
			(fill no)
			(layer "B.CrtYd")
		)
		(fp_rect
			(start -0.5 0.25)
			(end 0.5 -0.25)
			(stroke
				(width 0.15)
				(type solid)
			)
			(fill no)
			(layer "B.Fab")
		)
		(pad "1" smd roundrect
			(at -0.485 0)
			(size 0.59 0.64)
			(layers "B.Cu" "B.Mask" "B.Paste")
			(roundrect_rratio 0.25)
			(net 200 "+3V3")
			(pintype "passive")
		)
		(pad "2" smd roundrect
			(at 0.485 0)
			(size 0.59 0.64)
			(layers "B.Cu" "B.Mask" "B.Paste")
			(roundrect_rratio 0.25)
			(net 374 "/FPGA bank 16/SD.DAT0")
			(pintype "passive")
		)
	)
	(footprint "antmicro-footprints:R_0402_1005Metric"
		(layer "B.Cu")
		(at 84.75 173.4)
		(descr "Resistor SMD 0402")
		(tags "resistor SMD 0402")
		(property "Reference" "R86"
			(at -1.122484 0.772697 180)
			(layer "B.SilkS")
			(hide yes)
			(effects
				(font
					(size 0.7 0.7)
					(thickness 0.15)
				)
				(justify left bottom mirror)
			)
		)
		(property "Value" "R_20k_0402"
			(at -1.011843 -1.772047 180)
			(layer "B.Fab")
			(effects
				(font
					(size 0.7 0.7)
					(thickness 0.15)
				)
				(justify left bottom mirror)
			)
		)
		(property "Datasheet" "https://www.bourns.com/docs/product-datasheets/cr.pdf"
			(at 0 0 0)
			(layer "F.Fab")
			(hide yes)
			(effects
				(font
					(size 1.27 1.27)
					(thickness 0.15)
				)
			)
		)
		(property "Author" "Antmicro"
			(at 0 0 0)
			(layer "B.Fab")
			(hide yes)
			(effects
				(font
					(size 1 1)
					(thickness 0.15)
				)
				(justify mirror)
			)
		)
		(property "License" "Apache-2.0"
			(at 0 0 0)
			(layer "B.Fab")
			(hide yes)
			(effects
				(font
					(size 1 1)
					(thickness 0.15)
				)
				(justify mirror)
			)
		)
		(property "MPN" "CR0402-FX-2002GLF"
			(at 0 0 0)
			(layer "B.Fab")
			(hide yes)
			(effects
				(font
					(size 1 1)
					(thickness 0.15)
				)
				(justify mirror)
			)
		)
		(property "Manufacturer" "Bourns"
			(at 0 0 0)
			(layer "B.Fab")
			(hide yes)
			(effects
				(font
					(size 1 1)
					(thickness 0.15)
				)
				(justify mirror)
			)
		)
		(property "Tolerance" "1%"
			(at 0 0 0)
			(layer "B.Fab")
			(hide yes)
			(effects
				(font
					(size 1 1)
					(thickness 0.15)
				)
				(justify mirror)
			)
		)
		(property "Val" "20k"
			(at 0 0 0)
			(layer "B.Fab")
			(hide yes)
			(effects
				(font
					(size 1 1)
					(thickness 0.15)
				)
				(justify mirror)
			)
		)
		(sheetname "/HDMI + SD Card/")
		(sheetfile "hdmi-sd-card.kicad_sch")
		(attr smd)
		(fp_rect
			(start -0.93 0.47)
			(end 0.93 -0.47)
			(stroke
				(width 0.05)
				(type solid)
			)
			(fill no)
			(layer "B.CrtYd")
		)
		(fp_rect
			(start -0.5 0.25)
			(end 0.5 -0.25)
			(stroke
				(width 0.15)
				(type solid)
			)
			(fill no)
			(layer "B.Fab")
		)
		(pad "1" smd roundrect
			(at -0.485 0)
			(size 0.59 0.64)
			(layers "B.Cu" "B.Mask" "B.Paste")
			(roundrect_rratio 0.25)
			(net 200 "+3V3")
			(pintype "passive")
		)
		(pad "2" smd roundrect
			(at 0.485 0)
			(size 0.59 0.64)
			(layers "B.Cu" "B.Mask" "B.Paste")
			(roundrect_rratio 0.25)
			(net 371 "/FPGA bank 16/SD.DAT3")
			(pintype "passive")
		)
	)
	(footprint "antmicro-footprints:R_0402_1005Metric"
		(layer "B.Cu")
		(at 84.75 174.4)
		(descr "Resistor SMD 0402")
		(tags "resistor SMD 0402")
		(property "Reference" "R87"
			(at -1.122484 0.772697 180)
			(layer "B.SilkS")
			(hide yes)
			(effects
				(font
					(size 0.7 0.7)
					(thickness 0.15)
				)
				(justify left bottom mirror)
			)
		)
		(property "Value" "R_20k_0402"
			(at -1.011843 -1.772047 180)
			(layer "B.Fab")
			(effects
				(font
					(size 0.7 0.7)
					(thickness 0.15)
				)
				(justify left bottom mirror)
			)
		)
		(property "Datasheet" "https://www.bourns.com/docs/product-datasheets/cr.pdf"
			(at 0 0 0)
			(layer "F.Fab")
			(hide yes)
			(effects
				(font
					(size 1.27 1.27)
					(thickness 0.15)
				)
			)
		)
		(property "Author" "Antmicro"
			(at 0 0 0)
			(layer "B.Fab")
			(hide yes)
			(effects
				(font
					(size 1 1)
					(thickness 0.15)
				)
				(justify mirror)
			)
		)
		(property "License" "Apache-2.0"
			(at 0 0 0)
			(layer "B.Fab")
			(hide yes)
			(effects
				(font
					(size 1 1)
					(thickness 0.15)
				)
				(justify mirror)
			)
		)
		(property "MPN" "CR0402-FX-2002GLF"
			(at 0 0 0)
			(layer "B.Fab")
			(hide yes)
			(effects
				(font
					(size 1 1)
					(thickness 0.15)
				)
				(justify mirror)
			)
		)
		(property "Manufacturer" "Bourns"
			(at 0 0 0)
			(layer "B.Fab")
			(hide yes)
			(effects
				(font
					(size 1 1)
					(thickness 0.15)
				)
				(justify mirror)
			)
		)
		(property "Tolerance" "1%"
			(at 0 0 0)
			(layer "B.Fab")
			(hide yes)
			(effects
				(font
					(size 1 1)
					(thickness 0.15)
				)
				(justify mirror)
			)
		)
		(property "Val" "20k"
			(at 0 0 0)
			(layer "B.Fab")
			(hide yes)
			(effects
				(font
					(size 1 1)
					(thickness 0.15)
				)
				(justify mirror)
			)
		)
		(sheetname "/HDMI + SD Card/")
		(sheetfile "hdmi-sd-card.kicad_sch")
		(attr smd)
		(fp_rect
			(start -0.93 0.47)
			(end 0.93 -0.47)
			(stroke
				(width 0.05)
				(type solid)
			)
			(fill no)
			(layer "B.CrtYd")
		)
		(fp_rect
			(start -0.5 0.25)
			(end 0.5 -0.25)
			(stroke
				(width 0.15)
				(type solid)
			)
			(fill no)
			(layer "B.Fab")
		)
		(pad "1" smd roundrect
			(at -0.485 0)
			(size 0.59 0.64)
			(layers "B.Cu" "B.Mask" "B.Paste")
			(roundrect_rratio 0.25)
			(net 200 "+3V3")
			(pintype "passive")
		)
		(pad "2" smd roundrect
			(at 0.485 0)
			(size 0.59 0.64)
			(layers "B.Cu" "B.Mask" "B.Paste")
			(roundrect_rratio 0.25)
			(net 350 "/FPGA bank 16/SD.DAT2")
			(pintype "passive")
		)
	)
	(footprint "antmicro-footprints:R_0402_1005Metric"
		(layer "B.Cu")
		(at 99.500501 161.576 90)
		(descr "Resistor SMD 0402")
		(tags "resistor SMD 0402")
		(property "Reference" "R101"
			(at -1.122484 0.772697 270)
			(layer "B.SilkS")
			(hide yes)
			(effects
				(font
					(size 0.7 0.7)
					(thickness 0.15)
				)
				(justify left bottom mirror)
			)
		)
		(property "Value" "R_10k_0402"
			(at -1.011843 -1.772047 270)
			(layer "B.Fab")
			(effects
				(font
					(size 0.7 0.7)
					(thickness 0.15)
				)
				(justify left bottom mirror)
			)
		)
		(property "Datasheet" "https://www.bourns.com/docs/product-datasheets/cr.pdf"
			(at 0 0 90)
			(layer "F.Fab")
			(hide yes)
			(effects
				(font
					(size 1.27 1.27)
					(thickness 0.15)
				)
			)
		)
		(property "Author" "Antmicro"
			(at 261.076501 62.075499 0)
			(layer "B.Fab")
			(hide yes)
			(effects
				(font
					(size 1 1)
					(thickness 0.15)
				)
				(justify mirror)
			)
		)
		(property "License" "Apache-2.0"
			(at 261.076501 62.075499 0)
			(layer "B.Fab")
			(hide yes)
			(effects
				(font
					(size 1 1)
					(thickness 0.15)
				)
				(justify mirror)
			)
		)
		(property "MPN" "CR0402-FX-1002GLF"
			(at 261.076501 62.075499 0)
			(layer "B.Fab")
			(hide yes)
			(effects
				(font
					(size 1 1)
					(thickness 0.15)
				)
				(justify mirror)
			)
		)
		(property "Manufacturer" "Bourns"
			(at 261.076501 62.075499 0)
			(layer "B.Fab")
			(hide yes)
			(effects
				(font
					(size 1 1)
					(thickness 0.15)
				)
				(justify mirror)
			)
		)
		(property "Tolerance" "1%"
			(at 261.076501 62.075499 0)
			(layer "B.Fab")
			(hide yes)
			(effects
				(font
					(size 1 1)
					(thickness 0.15)
				)
				(justify mirror)
			)
		)
		(property "Val" "10k"
			(at 261.076501 62.075499 0)
			(layer "B.Fab")
			(hide yes)
			(effects
				(font
					(size 1 1)
					(thickness 0.15)
				)
				(justify mirror)
			)
		)
		(sheetname "/Ethernet/")
		(sheetfile "ethernet.kicad_sch")
		(attr exclude_from_pos_files exclude_from_bom dnp)
		(fp_rect
			(start -0.93 0.47)
			(end 0.93 -0.47)
			(stroke
				(width 0.05)
				(type solid)
			)
			(fill no)
			(layer "B.CrtYd")
		)
		(fp_rect
			(start -0.5 0.25)
			(end 0.5 -0.25)
			(stroke
				(width 0.15)
				(type solid)
			)
			(fill no)
			(layer "B.Fab")
		)
		(pad "1" smd roundrect
			(at -0.485 0 90)
			(size 0.59 0.64)
			(layers "B.Cu" "B.Mask" "B.Paste")
			(roundrect_rratio 0.25)
			(net 673 "/Ethernet/ETH.RXD0")
			(pintype "passive")
		)
		(pad "2" smd roundrect
			(at 0.485 0 90)
			(size 0.59 0.64)
			(layers "B.Cu" "B.Mask" "B.Paste")
			(roundrect_rratio 0.25)
			(net 200 "+3V3")
			(pintype "passive")
		)
	)
	(footprint "antmicro-footprints:R_0402_1005Metric"
		(layer "B.Cu")
		(at 98.450501 161.576 90)
		(descr "Resistor SMD 0402")
		(tags "resistor SMD 0402")
		(property "Reference" "R102"
			(at -1.122484 0.772697 270)
			(layer "B.SilkS")
			(hide yes)
			(effects
				(font
					(size 0.7 0.7)
					(thickness 0.15)
				)
				(justify left bottom mirror)
			)
		)
		(property "Value" "R_10k_0402"
			(at -1.011843 -1.772047 270)
			(layer "B.Fab")
			(effects
				(font
					(size 0.7 0.7)
					(thickness 0.15)
				)
				(justify left bottom mirror)
			)
		)
		(property "Datasheet" "https://www.bourns.com/docs/product-datasheets/cr.pdf"
			(at 0 0 90)
			(layer "F.Fab")
			(hide yes)
			(effects
				(font
					(size 1.27 1.27)
					(thickness 0.15)
				)
			)
		)
		(property "Author" "Antmicro"
			(at 260.026501 63.125499 0)
			(layer "B.Fab")
			(hide yes)
			(effects
				(font
					(size 1 1)
					(thickness 0.15)
				)
				(justify mirror)
			)
		)
		(property "License" "Apache-2.0"
			(at 260.026501 63.125499 0)
			(layer "B.Fab")
			(hide yes)
			(effects
				(font
					(size 1 1)
					(thickness 0.15)
				)
				(justify mirror)
			)
		)
		(property "MPN" "CR0402-FX-1002GLF"
			(at 260.026501 63.125499 0)
			(layer "B.Fab")
			(hide yes)
			(effects
				(font
					(size 1 1)
					(thickness 0.15)
				)
				(justify mirror)
			)
		)
		(property "Manufacturer" "Bourns"
			(at 260.026501 63.125499 0)
			(layer "B.Fab")
			(hide yes)
			(effects
				(font
					(size 1 1)
					(thickness 0.15)
				)
				(justify mirror)
			)
		)
		(property "Tolerance" "1%"
			(at 260.026501 63.125499 0)
			(layer "B.Fab")
			(hide yes)
			(effects
				(font
					(size 1 1)
					(thickness 0.15)
				)
				(justify mirror)
			)
		)
		(property "Val" "10k"
			(at 260.026501 63.125499 0)
			(layer "B.Fab")
			(hide yes)
			(effects
				(font
					(size 1 1)
					(thickness 0.15)
				)
				(justify mirror)
			)
		)
		(sheetname "/Ethernet/")
		(sheetfile "ethernet.kicad_sch")
		(attr exclude_from_pos_files exclude_from_bom dnp)
		(fp_rect
			(start -0.93 0.47)
			(end 0.93 -0.47)
			(stroke
				(width 0.05)
				(type solid)
			)
			(fill no)
			(layer "B.CrtYd")
		)
		(fp_rect
			(start -0.5 0.25)
			(end 0.5 -0.25)
			(stroke
				(width 0.15)
				(type solid)
			)
			(fill no)
			(layer "B.Fab")
		)
		(pad "1" smd roundrect
			(at -0.485 0 90)
			(size 0.59 0.64)
			(layers "B.Cu" "B.Mask" "B.Paste")
			(roundrect_rratio 0.25)
			(net 674 "/Ethernet/ETH.RXD1")
			(pintype "passive")
		)
		(pad "2" smd roundrect
			(at 0.485 0 90)
			(size 0.59 0.64)
			(layers "B.Cu" "B.Mask" "B.Paste")
			(roundrect_rratio 0.25)
			(net 200 "+3V3")
			(pintype "passive")
		)
	)
	(footprint "antmicro-footprints:R_0402_1005Metric"
		(layer "B.Cu")
		(at 101.625501 161.601 90)
		(descr "Resistor SMD 0402")
		(tags "resistor SMD 0402")
		(property "Reference" "R105"
			(at -1.122484 0.772697 270)
			(layer "B.SilkS")
			(hide yes)
			(effects
				(font
					(size 0.7 0.7)
					(thickness 0.15)
				)
				(justify left bottom mirror)
			)
		)
		(property "Value" "R_10k_0402"
			(at -1.011843 -1.772047 270)
			(layer "B.Fab")
			(effects
				(font
					(size 0.7 0.7)
					(thickness 0.15)
				)
				(justify left bottom mirror)
			)
		)
		(property "Datasheet" "https://www.bourns.com/docs/product-datasheets/cr.pdf"
			(at 0 0 90)
			(layer "F.Fab")
			(hide yes)
			(effects
				(font
					(size 1.27 1.27)
					(thickness 0.15)
				)
			)
		)
		(property "Author" "Antmicro"
			(at 263.226501 59.975499 0)
			(layer "B.Fab")
			(hide yes)
			(effects
				(font
					(size 1 1)
					(thickness 0.15)
				)
				(justify mirror)
			)
		)
		(property "License" "Apache-2.0"
			(at 263.226501 59.975499 0)
			(layer "B.Fab")
			(hide yes)
			(effects
				(font
					(size 1 1)
					(thickness 0.15)
				)
				(justify mirror)
			)
		)
		(property "MPN" "CR0402-FX-1002GLF"
			(at 263.226501 59.975499 0)
			(layer "B.Fab")
			(hide yes)
			(effects
				(font
					(size 1 1)
					(thickness 0.15)
				)
				(justify mirror)
			)
		)
		(property "Manufacturer" "Bourns"
			(at 263.226501 59.975499 0)
			(layer "B.Fab")
			(hide yes)
			(effects
				(font
					(size 1 1)
					(thickness 0.15)
				)
				(justify mirror)
			)
		)
		(property "Tolerance" "1%"
			(at 263.226501 59.975499 0)
			(layer "B.Fab")
			(hide yes)
			(effects
				(font
					(size 1 1)
					(thickness 0.15)
				)
				(justify mirror)
			)
		)
		(property "Val" "10k"
			(at 263.226501 59.975499 0)
			(layer "B.Fab")
			(hide yes)
			(effects
				(font
					(size 1 1)
					(thickness 0.15)
				)
				(justify mirror)
			)
		)
		(sheetname "/Ethernet/")
		(sheetfile "ethernet.kicad_sch")
		(attr exclude_from_pos_files exclude_from_bom dnp)
		(fp_rect
			(start -0.93 0.47)
			(end 0.93 -0.47)
			(stroke
				(width 0.05)
				(type solid)
			)
			(fill no)
			(layer "B.CrtYd")
		)
		(fp_rect
			(start -0.5 0.25)
			(end 0.5 -0.25)
			(stroke
				(width 0.15)
				(type solid)
			)
			(fill no)
			(layer "B.Fab")
		)
		(pad "1" smd roundrect
			(at -0.485 0 90)
			(size 0.59 0.64)
			(layers "B.Cu" "B.Mask" "B.Paste")
			(roundrect_rratio 0.25)
			(net 677 "/Ethernet/ETH.RX_CTL")
			(pintype "passive")
		)
		(pad "2" smd roundrect
			(at 0.485 0 90)
			(size 0.59 0.64)
			(layers "B.Cu" "B.Mask" "B.Paste")
			(roundrect_rratio 0.25)
			(net 200 "+3V3")
			(pintype "passive")
		)
	)
	(footprint "antmicro-footprints:R_0402_1005Metric"
		(layer "B.Cu")
		(at 100.525501 161.576 90)
		(descr "Resistor SMD 0402")
		(tags "resistor SMD 0402")
		(property "Reference" "R106"
			(at -1.122484 0.772697 270)
			(layer "B.SilkS")
			(hide yes)
			(effects
				(font
					(size 0.7 0.7)
					(thickness 0.15)
				)
				(justify left bottom mirror)
			)
		)
		(property "Value" "R_10k_0402"
			(at -1.011843 -1.772047 270)
			(layer "B.Fab")
			(effects
				(font
					(size 0.7 0.7)
					(thickness 0.15)
				)
				(justify left bottom mirror)
			)
		)
		(property "Datasheet" "https://www.bourns.com/docs/product-datasheets/cr.pdf"
			(at 0 0 90)
			(layer "F.Fab")
			(hide yes)
			(effects
				(font
					(size 1.27 1.27)
					(thickness 0.15)
				)
			)
		)
		(property "Author" "Antmicro"
			(at 262.101501 61.050499 0)
			(layer "B.Fab")
			(hide yes)
			(effects
				(font
					(size 1 1)
					(thickness 0.15)
				)
				(justify mirror)
			)
		)
		(property "License" "Apache-2.0"
			(at 262.101501 61.050499 0)
			(layer "B.Fab")
			(hide yes)
			(effects
				(font
					(size 1 1)
					(thickness 0.15)
				)
				(justify mirror)
			)
		)
		(property "MPN" "CR0402-FX-1002GLF"
			(at 262.101501 61.050499 0)
			(layer "B.Fab")
			(hide yes)
			(effects
				(font
					(size 1 1)
					(thickness 0.15)
				)
				(justify mirror)
			)
		)
		(property "Manufacturer" "Bourns"
			(at 262.101501 61.050499 0)
			(layer "B.Fab")
			(hide yes)
			(effects
				(font
					(size 1 1)
					(thickness 0.15)
				)
				(justify mirror)
			)
		)
		(property "Tolerance" "1%"
			(at 262.101501 61.050499 0)
			(layer "B.Fab")
			(hide yes)
			(effects
				(font
					(size 1 1)
					(thickness 0.15)
				)
				(justify mirror)
			)
		)
		(property "Val" "10k"
			(at 262.101501 61.050499 0)
			(layer "B.Fab")
			(hide yes)
			(effects
				(font
					(size 1 1)
					(thickness 0.15)
				)
				(justify mirror)
			)
		)
		(sheetname "/Ethernet/")
		(sheetfile "ethernet.kicad_sch")
		(attr exclude_from_pos_files exclude_from_bom dnp)
		(fp_rect
			(start -0.93 0.47)
			(end 0.93 -0.47)
			(stroke
				(width 0.05)
				(type solid)
			)
			(fill no)
			(layer "B.CrtYd")
		)
		(fp_rect
			(start -0.5 0.25)
			(end 0.5 -0.25)
			(stroke
				(width 0.15)
				(type solid)
			)
			(fill no)
			(layer "B.Fab")
		)
		(pad "1" smd roundrect
			(at -0.485 0 90)
			(size 0.59 0.64)
			(layers "B.Cu" "B.Mask" "B.Paste")
			(roundrect_rratio 0.25)
			(net 678 "/Ethernet/ETH.RXC")
			(pintype "passive")
		)
		(pad "2" smd roundrect
			(at 0.485 0 90)
			(size 0.59 0.64)
			(layers "B.Cu" "B.Mask" "B.Paste")
			(roundrect_rratio 0.25)
			(net 200 "+3V3")
			(pintype "passive")
		)
	)
	(footprint "antmicro-footprints:R_0402_1005Metric"
		(layer "B.Cu")
		(at 95.308672 154.95 90)
		(descr "Resistor SMD 0402")
		(tags "resistor SMD 0402")
		(property "Reference" "R107"
			(at -1.122484 0.772697 270)
			(layer "B.SilkS")
			(hide yes)
			(effects
				(font
					(size 0.7 0.7)
					(thickness 0.15)
				)
				(justify left bottom mirror)
			)
		)
		(property "Value" "R_10k_0402"
			(at -1.011843 -1.772047 270)
			(layer "B.Fab")
			(effects
				(font
					(size 0.7 0.7)
					(thickness 0.15)
				)
				(justify left bottom mirror)
			)
		)
		(property "Datasheet" "https://www.bourns.com/docs/product-datasheets/cr.pdf"
			(at 0 0 90)
			(layer "F.Fab")
			(hide yes)
			(effects
				(font
					(size 1.27 1.27)
					(thickness 0.15)
				)
			)
		)
		(property "Author" "Antmicro"
			(at 250.258672 59.641328 0)
			(layer "B.Fab")
			(hide yes)
			(effects
				(font
					(size 1 1)
					(thickness 0.15)
				)
				(justify mirror)
			)
		)
		(property "License" "Apache-2.0"
			(at 250.258672 59.641328 0)
			(layer "B.Fab")
			(hide yes)
			(effects
				(font
					(size 1 1)
					(thickness 0.15)
				)
				(justify mirror)
			)
		)
		(property "MPN" "CR0402-FX-1002GLF"
			(at 250.258672 59.641328 0)
			(layer "B.Fab")
			(hide yes)
			(effects
				(font
					(size 1 1)
					(thickness 0.15)
				)
				(justify mirror)
			)
		)
		(property "Manufacturer" "Bourns"
			(at 250.258672 59.641328 0)
			(layer "B.Fab")
			(hide yes)
			(effects
				(font
					(size 1 1)
					(thickness 0.15)
				)
				(justify mirror)
			)
		)
		(property "Tolerance" "1%"
			(at 250.258672 59.641328 0)
			(layer "B.Fab")
			(hide yes)
			(effects
				(font
					(size 1 1)
					(thickness 0.15)
				)
				(justify mirror)
			)
		)
		(property "Val" "10k"
			(at 250.258672 59.641328 0)
			(layer "B.Fab")
			(hide yes)
			(effects
				(font
					(size 1 1)
					(thickness 0.15)
				)
				(justify mirror)
			)
		)
		(sheetname "/Ethernet/")
		(sheetfile "ethernet.kicad_sch")
		(attr smd)
		(fp_rect
			(start -0.93 0.47)
			(end 0.93 -0.47)
			(stroke
				(width 0.05)
				(type solid)
			)
			(fill no)
			(layer "B.CrtYd")
		)
		(fp_rect
			(start -0.5 0.25)
			(end 0.5 -0.25)
			(stroke
				(width 0.15)
				(type solid)
			)
			(fill no)
			(layer "B.Fab")
		)
		(pad "1" smd roundrect
			(at -0.485 0 90)
			(size 0.59 0.64)
			(layers "B.Cu" "B.Mask" "B.Paste")
			(roundrect_rratio 0.25)
			(net 679 "/Ethernet/ETH.REF_CLK")
			(pintype "passive")
		)
		(pad "2" smd roundrect
			(at 0.485 0 90)
			(size 0.59 0.64)
			(layers "B.Cu" "B.Mask" "B.Paste")
			(roundrect_rratio 0.25)
			(net 200 "+3V3")
			(pintype "passive")
		)
	)
	(footprint "antmicro-footprints:R_0402_1005Metric"
		(layer "B.Cu")
		(at 98.1 153.8)
		(descr "Resistor SMD 0402")
		(tags "resistor SMD 0402")
		(property "Reference" "R111"
			(at -1.122484 0.772697 180)
			(layer "B.SilkS")
			(hide yes)
			(effects
				(font
					(size 0.7 0.7)
					(thickness 0.15)
				)
				(justify left bottom mirror)
			)
		)
		(property "Value" "R_10k_0402"
			(at -1.011843 -1.772047 180)
			(layer "B.Fab")
			(effects
				(font
					(size 0.7 0.7)
					(thickness 0.15)
				)
				(justify left bottom mirror)
			)
		)
		(property "Datasheet" "https://www.bourns.com/docs/product-datasheets/cr.pdf"
			(at 0 0 0)
			(layer "F.Fab")
			(hide yes)
			(effects
				(font
					(size 1.27 1.27)
					(thickness 0.15)
				)
			)
		)
		(property "Author" "Antmicro"
			(at 0 0 0)
			(layer "B.Fab")
			(hide yes)
			(effects
				(font
					(size 1 1)
					(thickness 0.15)
				)
				(justify mirror)
			)
		)
		(property "License" "Apache-2.0"
			(at 0 0 0)
			(layer "B.Fab")
			(hide yes)
			(effects
				(font
					(size 1 1)
					(thickness 0.15)
				)
				(justify mirror)
			)
		)
		(property "MPN" "CR0402-FX-1002GLF"
			(at 0 0 0)
			(layer "B.Fab")
			(hide yes)
			(effects
				(font
					(size 1 1)
					(thickness 0.15)
				)
				(justify mirror)
			)
		)
		(property "Manufacturer" "Bourns"
			(at 0 0 0)
			(layer "B.Fab")
			(hide yes)
			(effects
				(font
					(size 1 1)
					(thickness 0.15)
				)
				(justify mirror)
			)
		)
		(property "Tolerance" "1%"
			(at 0 0 0)
			(layer "B.Fab")
			(hide yes)
			(effects
				(font
					(size 1 1)
					(thickness 0.15)
				)
				(justify mirror)
			)
		)
		(property "Val" "10k"
			(at 0 0 0)
			(layer "B.Fab")
			(hide yes)
			(effects
				(font
					(size 1 1)
					(thickness 0.15)
				)
				(justify mirror)
			)
		)
		(sheetname "/Ethernet/")
		(sheetfile "ethernet.kicad_sch")
		(attr smd)
		(fp_rect
			(start -0.93 0.47)
			(end 0.93 -0.47)
			(stroke
				(width 0.05)
				(type solid)
			)
			(fill no)
			(layer "B.CrtYd")
		)
		(fp_rect
			(start -0.5 0.25)
			(end 0.5 -0.25)
			(stroke
				(width 0.15)
				(type solid)
			)
			(fill no)
			(layer "B.Fab")
		)
		(pad "1" smd roundrect
			(at -0.485 0)
			(size 0.59 0.64)
			(layers "B.Cu" "B.Mask" "B.Paste")
			(roundrect_rratio 0.25)
			(net 681 "/Ethernet/ETH.~{RESET}")
			(pintype "passive")
		)
		(pad "2" smd roundrect
			(at 0.485 0)
			(size 0.59 0.64)
			(layers "B.Cu" "B.Mask" "B.Paste")
			(roundrect_rratio 0.25)
			(net 200 "+3V3")
			(pintype "passive")
		)
	)
	(footprint "antmicro-footprints:R_0402_1005Metric"
		(layer "B.Cu")
		(at 85.200501 152.813149 180)
		(descr "Resistor SMD 0402")
		(tags "resistor SMD 0402")
		(property "Reference" "R108"
			(at -1.122484 0.772697 0)
			(layer "B.SilkS")
			(hide yes)
			(effects
				(font
					(size 0.7 0.7)
					(thickness 0.15)
				)
				(justify left bottom mirror)
			)
		)
		(property "Value" "R_10k_0402"
			(at -1.011843 -1.772047 0)
			(layer "B.Fab")
			(effects
				(font
					(size 0.7 0.7)
					(thickness 0.15)
				)
				(justify left bottom mirror)
			)
		)
		(property "Datasheet" "https://www.bourns.com/docs/product-datasheets/cr.pdf"
			(at 0 0 180)
			(layer "F.Fab")
			(hide yes)
			(effects
				(font
					(size 1.27 1.27)
					(thickness 0.15)
				)
			)
		)
		(property "Author" "Antmicro"
			(at 170.401002 305.626298 0)
			(layer "B.Fab")
			(hide yes)
			(effects
				(font
					(size 1 1)
					(thickness 0.15)
				)
				(justify mirror)
			)
		)
		(property "License" "Apache-2.0"
			(at 170.401002 305.626298 0)
			(layer "B.Fab")
			(hide yes)
			(effects
				(font
					(size 1 1)
					(thickness 0.15)
				)
				(justify mirror)
			)
		)
		(property "MPN" "CR0402-FX-1002GLF"
			(at 170.401002 305.626298 0)
			(layer "B.Fab")
			(hide yes)
			(effects
				(font
					(size 1 1)
					(thickness 0.15)
				)
				(justify mirror)
			)
		)
		(property "Manufacturer" "Bourns"
			(at 170.401002 305.626298 0)
			(layer "B.Fab")
			(hide yes)
			(effects
				(font
					(size 1 1)
					(thickness 0.15)
				)
				(justify mirror)
			)
		)
		(property "Tolerance" "1%"
			(at 170.401002 305.626298 0)
			(layer "B.Fab")
			(hide yes)
			(effects
				(font
					(size 1 1)
					(thickness 0.15)
				)
				(justify mirror)
			)
		)
		(property "Val" "10k"
			(at 170.401002 305.626298 0)
			(layer "B.Fab")
			(hide yes)
			(effects
				(font
					(size 1 1)
					(thickness 0.15)
				)
				(justify mirror)
			)
		)
		(sheetname "/Ethernet/")
		(sheetfile "ethernet.kicad_sch")
		(attr smd)
		(fp_rect
			(start -0.93 0.47)
			(end 0.93 -0.47)
			(stroke
				(width 0.05)
				(type solid)
			)
			(fill no)
			(layer "B.CrtYd")
		)
		(fp_rect
			(start -0.5 0.25)
			(end 0.5 -0.25)
			(stroke
				(width 0.15)
				(type solid)
			)
			(fill no)
			(layer "B.Fab")
		)
		(pad "1" smd roundrect
			(at -0.485 0 180)
			(size 0.59 0.64)
			(layers "B.Cu" "B.Mask" "B.Paste")
			(roundrect_rratio 0.25)
			(net 602 "/Ethernet/LED_SPD")
			(pintype "passive")
		)
		(pad "2" smd roundrect
			(at 0.485 0 180)
			(size 0.59 0.64)
			(layers "B.Cu" "B.Mask" "B.Paste")
			(roundrect_rratio 0.25)
			(net 200 "+3V3")
			(pintype "passive")
		)
	)
	(footprint "antmicro-footprints:R_0402_1005Metric"
		(layer "B.Cu")
		(at 85.200501 154.313149 180)
		(descr "Resistor SMD 0402")
		(tags "resistor SMD 0402")
		(property "Reference" "R109"
			(at -1.122484 0.772697 0)
			(layer "B.SilkS")
			(hide yes)
			(effects
				(font
					(size 0.7 0.7)
					(thickness 0.15)
				)
				(justify left bottom mirror)
			)
		)
		(property "Value" "R_10k_0402"
			(at -1.011843 -1.772047 0)
			(layer "B.Fab")
			(effects
				(font
					(size 0.7 0.7)
					(thickness 0.15)
				)
				(justify left bottom mirror)
			)
		)
		(property "Datasheet" "https://www.bourns.com/docs/product-datasheets/cr.pdf"
			(at 0 0 180)
			(layer "F.Fab")
			(hide yes)
			(effects
				(font
					(size 1.27 1.27)
					(thickness 0.15)
				)
			)
		)
		(property "Author" "Antmicro"
			(at 170.401002 308.626298 0)
			(layer "B.Fab")
			(hide yes)
			(effects
				(font
					(size 1 1)
					(thickness 0.15)
				)
				(justify mirror)
			)
		)
		(property "License" "Apache-2.0"
			(at 170.401002 308.626298 0)
			(layer "B.Fab")
			(hide yes)
			(effects
				(font
					(size 1 1)
					(thickness 0.15)
				)
				(justify mirror)
			)
		)
		(property "MPN" "CR0402-FX-1002GLF"
			(at 170.401002 308.626298 0)
			(layer "B.Fab")
			(hide yes)
			(effects
				(font
					(size 1 1)
					(thickness 0.15)
				)
				(justify mirror)
			)
		)
		(property "Manufacturer" "Bourns"
			(at 170.401002 308.626298 0)
			(layer "B.Fab")
			(hide yes)
			(effects
				(font
					(size 1 1)
					(thickness 0.15)
				)
				(justify mirror)
			)
		)
		(property "Tolerance" "1%"
			(at 170.401002 308.626298 0)
			(layer "B.Fab")
			(hide yes)
			(effects
				(font
					(size 1 1)
					(thickness 0.15)
				)
				(justify mirror)
			)
		)
		(property "Val" "10k"
			(at 170.401002 308.626298 0)
			(layer "B.Fab")
			(hide yes)
			(effects
				(font
					(size 1 1)
					(thickness 0.15)
				)
				(justify mirror)
			)
		)
		(sheetname "/Ethernet/")
		(sheetfile "ethernet.kicad_sch")
		(attr smd)
		(fp_rect
			(start -0.93 0.47)
			(end 0.93 -0.47)
			(stroke
				(width 0.05)
				(type solid)
			)
			(fill no)
			(layer "B.CrtYd")
		)
		(fp_rect
			(start -0.5 0.25)
			(end 0.5 -0.25)
			(stroke
				(width 0.15)
				(type solid)
			)
			(fill no)
			(layer "B.Fab")
		)
		(pad "1" smd roundrect
			(at -0.485 0 180)
			(size 0.59 0.64)
			(layers "B.Cu" "B.Mask" "B.Paste")
			(roundrect_rratio 0.25)
			(net 603 "/Ethernet/LED_LINK")
			(pintype "passive")
		)
		(pad "2" smd roundrect
			(at 0.485 0 180)
			(size 0.59 0.64)
			(layers "B.Cu" "B.Mask" "B.Paste")
			(roundrect_rratio 0.25)
			(net 200 "+3V3")
			(pintype "passive")
		)
	)
	(footprint "antmicro-footprints:C_0402_1005Metric"
		(layer "B.Cu")
		(at 95.6 150.3 90)
		(descr "Capacitor SMD 0402")
		(tags "capacitor SMD 0402")
		(property "Reference" "C146"
			(at 0 0.699 270)
			(layer "B.SilkS")
			(hide yes)
			(effects
				(font
					(size 0.7 0.7)
					(thickness 0.15)
				)
				(justify left bottom mirror)
			)
		)
		(property "Value" "C_4u7_0402"
			(at -1.022927 -2.155213 270)
			(layer "B.Fab")
			(effects
				(font
					(size 0.7 0.7)
					(thickness 0.15)
				)
				(justify left bottom mirror)
			)
		)
		(property "Datasheet" "https://www.murata.com/products/productdetail?partno=GRM155R61A475MEAA%23"
			(at 0 0 90)
			(layer "F.Fab")
			(hide yes)
			(effects
				(font
					(size 1.27 1.27)
					(thickness 0.15)
				)
			)
		)
		(property "Author" "Antmicro"
			(at 245.9 54.7 0)
			(layer "B.Fab")
			(hide yes)
			(effects
				(font
					(size 1 1)
					(thickness 0.15)
				)
				(justify mirror)
			)
		)
		(property "Dielectric" ""
			(at 245.9 54.7 0)
			(layer "B.Fab")
			(hide yes)
			(effects
				(font
					(size 1 1)
					(thickness 0.15)
				)
				(justify mirror)
			)
		)
		(property "License" "Apache-2.0"
			(at 245.9 54.7 0)
			(layer "B.Fab")
			(hide yes)
			(effects
				(font
					(size 1 1)
					(thickness 0.15)
				)
				(justify mirror)
			)
		)
		(property "MPN" "GRM155R61A475MEAAD"
			(at 245.9 54.7 0)
			(layer "B.Fab")
			(hide yes)
			(effects
				(font
					(size 1 1)
					(thickness 0.15)
				)
				(justify mirror)
			)
		)
		(property "Manufacturer" "Murata"
			(at 245.9 54.7 0)
			(layer "B.Fab")
			(hide yes)
			(effects
				(font
					(size 1 1)
					(thickness 0.15)
				)
				(justify mirror)
			)
		)
		(property "Val" "4u7"
			(at 245.9 54.7 0)
			(layer "B.Fab")
			(hide yes)
			(effects
				(font
					(size 1 1)
					(thickness 0.15)
				)
				(justify mirror)
			)
		)
		(property "Voltage" ""
			(at 245.9 54.7 0)
			(layer "B.Fab")
			(hide yes)
			(effects
				(font
					(size 1 1)
					(thickness 0.15)
				)
				(justify mirror)
			)
		)
		(sheetname "/Ethernet/")
		(sheetfile "ethernet.kicad_sch")
		(attr smd)
		(fp_rect
			(start -0.9659 0.481258)
			(end 0.9649 -0.458742)
			(stroke
				(width 0.05)
				(type solid)
			)
			(fill no)
			(layer "B.CrtYd")
		)
		(fp_line
			(start 0.499 -0.248)
			(end -0.499 -0.248)
			(stroke
				(width 0.15)
				(type solid)
			)
			(layer "B.Fab")
		)
		(fp_line
			(start -0.499 -0.248)
			(end -0.499 0.25)
			(stroke
				(width 0.15)
				(type solid)
			)
			(layer "B.Fab")
		)
		(fp_line
			(start 0.499 0.25)
			(end 0.499 -0.248)
			(stroke
				(width 0.15)
				(type solid)
			)
			(layer "B.Fab")
		)
		(fp_line
			(start -0.499 0.25)
			(end 0.499 0.25)
			(stroke
				(width 0.15)
				(type solid)
			)
			(layer "B.Fab")
		)
		(pad "1" smd roundrect
			(at -0.484 0 90)
			(size 0.59 0.64)
			(layers "B.Cu" "B.Mask" "B.Paste")
			(roundrect_rratio 0.25)
			(net 132 "/Ethernet/AVDDL")
			(pintype "passive")
		)
		(pad "2" smd roundrect
			(at 0.484 0 90)
			(size 0.59 0.64)
			(layers "B.Cu" "B.Mask" "B.Paste")
			(roundrect_rratio 0.25)
			(net 1 "GND")
			(pintype "passive")
		)
	)
	(footprint "antmicro-footprints:C_0402_1005Metric"
		(layer "B.Cu")
		(at 93.308672 158.004992 90)
		(descr "Capacitor SMD 0402")
		(tags "capacitor SMD 0402")
		(property "Reference" "C145"
			(at 0 0.699 270)
			(layer "B.SilkS")
			(hide yes)
			(effects
				(font
					(size 0.7 0.7)
					(thickness 0.15)
				)
				(justify left bottom mirror)
			)
		)
		(property "Value" "C_470n_0402"
			(at -1.022927 -2.155213 270)
			(layer "B.Fab")
			(effects
				(font
					(size 0.7 0.7)
					(thickness 0.15)
				)
				(justify left bottom mirror)
			)
		)
		(property "Datasheet" "https://product.tdk.com/en/search/capacitor/ceramic/mlcc/info?part_no=C1005X5R1E474M050BB"
			(at 0 0 90)
			(layer "F.Fab")
			(hide yes)
			(effects
				(font
					(size 1.27 1.27)
					(thickness 0.15)
				)
			)
		)
		(property "Author" "Antmicro"
			(at 251.313664 64.69632 0)
			(layer "B.Fab")
			(hide yes)
			(effects
				(font
					(size 1 1)
					(thickness 0.15)
				)
				(justify mirror)
			)
		)
		(property "Dielectric" ""
			(at 251.313664 64.69632 0)
			(layer "B.Fab")
			(hide yes)
			(effects
				(font
					(size 1 1)
					(thickness 0.15)
				)
				(justify mirror)
			)
		)
		(property "License" "Apache-2.0"
			(at 251.313664 64.69632 0)
			(layer "B.Fab")
			(hide yes)
			(effects
				(font
					(size 1 1)
					(thickness 0.15)
				)
				(justify mirror)
			)
		)
		(property "MPN" "C1005X5R1E474M050BB"
			(at 251.313664 64.69632 0)
			(layer "B.Fab")
			(hide yes)
			(effects
				(font
					(size 1 1)
					(thickness 0.15)
				)
				(justify mirror)
			)
		)
		(property "Manufacturer" "TDK"
			(at 251.313664 64.69632 0)
			(layer "B.Fab")
			(hide yes)
			(effects
				(font
					(size 1 1)
					(thickness 0.15)
				)
				(justify mirror)
			)
		)
		(property "Val" "470n"
			(at 251.313664 64.69632 0)
			(layer "B.Fab")
			(hide yes)
			(effects
				(font
					(size 1 1)
					(thickness 0.15)
				)
				(justify mirror)
			)
		)
		(property "Voltage" ""
			(at 251.313664 64.69632 0)
			(layer "B.Fab")
			(hide yes)
			(effects
				(font
					(size 1 1)
					(thickness 0.15)
				)
				(justify mirror)
			)
		)
		(sheetname "/Ethernet/")
		(sheetfile "ethernet.kicad_sch")
		(attr smd)
		(fp_rect
			(start -0.9659 0.481258)
			(end 0.9649 -0.458742)
			(stroke
				(width 0.05)
				(type solid)
			)
			(fill no)
			(layer "B.CrtYd")
		)
		(fp_line
			(start 0.499 -0.248)
			(end -0.499 -0.248)
			(stroke
				(width 0.15)
				(type solid)
			)
			(layer "B.Fab")
		)
		(fp_line
			(start -0.499 -0.248)
			(end -0.499 0.25)
			(stroke
				(width 0.15)
				(type solid)
			)
			(layer "B.Fab")
		)
		(fp_line
			(start 0.499 0.25)
			(end 0.499 -0.248)
			(stroke
				(width 0.15)
				(type solid)
			)
			(layer "B.Fab")
		)
		(fp_line
			(start -0.499 0.25)
			(end 0.499 0.25)
			(stroke
				(width 0.15)
				(type solid)
			)
			(layer "B.Fab")
		)
		(pad "1" smd roundrect
			(at -0.484 0 90)
			(size 0.59 0.64)
			(layers "B.Cu" "B.Mask" "B.Paste")
			(roundrect_rratio 0.25)
			(net 199 "+1V2")
			(pintype "passive")
		)
		(pad "2" smd roundrect
			(at 0.484 0 90)
			(size 0.59 0.64)
			(layers "B.Cu" "B.Mask" "B.Paste")
			(roundrect_rratio 0.25)
			(net 1 "GND")
			(pintype "passive")
		)
	)
	(footprint "antmicro-footprints:C_0402_1005Metric"
		(layer "B.Cu")
		(at 95.308672 158.004992 90)
		(descr "Capacitor SMD 0402")
		(tags "capacitor SMD 0402")
		(property "Reference" "C134"
			(at 0 0.699 270)
			(layer "B.SilkS")
			(hide yes)
			(effects
				(font
					(size 0.7 0.7)
					(thickness 0.15)
				)
				(justify left bottom mirror)
			)
		)
		(property "Value" "C_4u7_0402"
			(at -1.022927 -2.155213 270)
			(layer "B.Fab")
			(effects
				(font
					(size 0.7 0.7)
					(thickness 0.15)
				)
				(justify left bottom mirror)
			)
		)
		(property "Datasheet" "https://www.murata.com/products/productdetail?partno=GRM155R61A475MEAA%23"
			(at 0 0 90)
			(layer "F.Fab")
			(hide yes)
			(effects
				(font
					(size 1.27 1.27)
					(thickness 0.15)
				)
			)
		)
		(property "Author" "Antmicro"
			(at 253.313664 62.69632 0)
			(layer "B.Fab")
			(hide yes)
			(effects
				(font
					(size 1 1)
					(thickness 0.15)
				)
				(justify mirror)
			)
		)
		(property "Dielectric" ""
			(at 253.313664 62.69632 0)
			(layer "B.Fab")
			(hide yes)
			(effects
				(font
					(size 1 1)
					(thickness 0.15)
				)
				(justify mirror)
			)
		)
		(property "License" "Apache-2.0"
			(at 253.313664 62.69632 0)
			(layer "B.Fab")
			(hide yes)
			(effects
				(font
					(size 1 1)
					(thickness 0.15)
				)
				(justify mirror)
			)
		)
		(property "MPN" "GRM155R61A475MEAAD"
			(at 253.313664 62.69632 0)
			(layer "B.Fab")
			(hide yes)
			(effects
				(font
					(size 1 1)
					(thickness 0.15)
				)
				(justify mirror)
			)
		)
		(property "Manufacturer" "Murata"
			(at 253.313664 62.69632 0)
			(layer "B.Fab")
			(hide yes)
			(effects
				(font
					(size 1 1)
					(thickness 0.15)
				)
				(justify mirror)
			)
		)
		(property "Val" "4u7"
			(at 253.313664 62.69632 0)
			(layer "B.Fab")
			(hide yes)
			(effects
				(font
					(size 1 1)
					(thickness 0.15)
				)
				(justify mirror)
			)
		)
		(property "Voltage" ""
			(at 253.313664 62.69632 0)
			(layer "B.Fab")
			(hide yes)
			(effects
				(font
					(size 1 1)
					(thickness 0.15)
				)
				(justify mirror)
			)
		)
		(sheetname "/Ethernet/")
		(sheetfile "ethernet.kicad_sch")
		(attr smd)
		(fp_rect
			(start -0.9659 0.481258)
			(end 0.9649 -0.458742)
			(stroke
				(width 0.05)
				(type solid)
			)
			(fill no)
			(layer "B.CrtYd")
		)
		(fp_line
			(start 0.499 -0.248)
			(end -0.499 -0.248)
			(stroke
				(width 0.15)
				(type solid)
			)
			(layer "B.Fab")
		)
		(fp_line
			(start -0.499 -0.248)
			(end -0.499 0.25)
			(stroke
				(width 0.15)
				(type solid)
			)
			(layer "B.Fab")
		)
		(fp_line
			(start 0.499 0.25)
			(end 0.499 -0.248)
			(stroke
				(width 0.15)
				(type solid)
			)
			(layer "B.Fab")
		)
		(fp_line
			(start -0.499 0.25)
			(end 0.499 0.25)
			(stroke
				(width 0.15)
				(type solid)
			)
			(layer "B.Fab")
		)
		(pad "1" smd roundrect
			(at -0.484 0 90)
			(size 0.59 0.64)
			(layers "B.Cu" "B.Mask" "B.Paste")
			(roundrect_rratio 0.25)
			(net 200 "+3V3")
			(pintype "passive")
		)
		(pad "2" smd roundrect
			(at 0.484 0 90)
			(size 0.59 0.64)
			(layers "B.Cu" "B.Mask" "B.Paste")
			(roundrect_rratio 0.25)
			(net 1 "GND")
			(pintype "passive")
		)
	)
	(footprint "antmicro-footprints:C_0402_1005Metric"
		(layer "B.Cu")
		(at 93.036829 150.283157 90)
		(descr "Capacitor SMD 0402")
		(tags "capacitor SMD 0402")
		(property "Reference" "C143"
			(at 0 0.699 270)
			(layer "B.SilkS")
			(hide yes)
			(effects
				(font
					(size 0.7 0.7)
					(thickness 0.15)
				)
				(justify left bottom mirror)
			)
		)
		(property "Value" "C_470n_0402"
			(at -1.022927 -2.155213 270)
			(layer "B.Fab")
			(effects
				(font
					(size 0.7 0.7)
					(thickness 0.15)
				)
				(justify left bottom mirror)
			)
		)
		(property "Datasheet" "https://product.tdk.com/en/search/capacitor/ceramic/mlcc/info?part_no=C1005X5R1E474M050BB"
			(at 0 0 90)
			(layer "F.Fab")
			(hide yes)
			(effects
				(font
					(size 1.27 1.27)
					(thickness 0.15)
				)
			)
		)
		(property "Author" "Antmicro"
			(at 243.319986 57.246328 0)
			(layer "B.Fab")
			(hide yes)
			(effects
				(font
					(size 1 1)
					(thickness 0.15)
				)
				(justify mirror)
			)
		)
		(property "Dielectric" ""
			(at 243.319986 57.246328 0)
			(layer "B.Fab")
			(hide yes)
			(effects
				(font
					(size 1 1)
					(thickness 0.15)
				)
				(justify mirror)
			)
		)
		(property "License" "Apache-2.0"
			(at 243.319986 57.246328 0)
			(layer "B.Fab")
			(hide yes)
			(effects
				(font
					(size 1 1)
					(thickness 0.15)
				)
				(justify mirror)
			)
		)
		(property "MPN" "C1005X5R1E474M050BB"
			(at 243.319986 57.246328 0)
			(layer "B.Fab")
			(hide yes)
			(effects
				(font
					(size 1 1)
					(thickness 0.15)
				)
				(justify mirror)
			)
		)
		(property "Manufacturer" "TDK"
			(at 243.319986 57.246328 0)
			(layer "B.Fab")
			(hide yes)
			(effects
				(font
					(size 1 1)
					(thickness 0.15)
				)
				(justify mirror)
			)
		)
		(property "Val" "470n"
			(at 243.319986 57.246328 0)
			(layer "B.Fab")
			(hide yes)
			(effects
				(font
					(size 1 1)
					(thickness 0.15)
				)
				(justify mirror)
			)
		)
		(property "Voltage" ""
			(at 243.319986 57.246328 0)
			(layer "B.Fab")
			(hide yes)
			(effects
				(font
					(size 1 1)
					(thickness 0.15)
				)
				(justify mirror)
			)
		)
		(sheetname "/Ethernet/")
		(sheetfile "ethernet.kicad_sch")
		(attr smd)
		(fp_rect
			(start -0.9659 0.481258)
			(end 0.9649 -0.458742)
			(stroke
				(width 0.05)
				(type solid)
			)
			(fill no)
			(layer "B.CrtYd")
		)
		(fp_line
			(start 0.499 -0.248)
			(end -0.499 -0.248)
			(stroke
				(width 0.15)
				(type solid)
			)
			(layer "B.Fab")
		)
		(fp_line
			(start -0.499 -0.248)
			(end -0.499 0.25)
			(stroke
				(width 0.15)
				(type solid)
			)
			(layer "B.Fab")
		)
		(fp_line
			(start 0.499 0.25)
			(end 0.499 -0.248)
			(stroke
				(width 0.15)
				(type solid)
			)
			(layer "B.Fab")
		)
		(fp_line
			(start -0.499 0.25)
			(end 0.499 0.25)
			(stroke
				(width 0.15)
				(type solid)
			)
			(layer "B.Fab")
		)
		(pad "1" smd roundrect
			(at -0.484 0 90)
			(size 0.59 0.64)
			(layers "B.Cu" "B.Mask" "B.Paste")
			(roundrect_rratio 0.25)
			(net 132 "/Ethernet/AVDDL")
			(pintype "passive")
		)
		(pad "2" smd roundrect
			(at 0.484 0 90)
			(size 0.59 0.64)
			(layers "B.Cu" "B.Mask" "B.Paste")
			(roundrect_rratio 0.25)
			(net 1 "GND")
			(pintype "passive")
		)
	)
	(footprint "antmicro-footprints:C_0402_1005Metric"
		(layer "B.Cu")
		(at 91.15 158.004992 90)
		(descr "Capacitor SMD 0402")
		(tags "capacitor SMD 0402")
		(property "Reference" "C148"
			(at 0 0.699 270)
			(layer "B.SilkS")
			(hide yes)
			(effects
				(font
					(size 0.7 0.7)
					(thickness 0.15)
				)
				(justify left bottom mirror)
			)
		)
		(property "Value" "C_470n_0402"
			(at -1.022927 -2.155213 270)
			(layer "B.Fab")
			(effects
				(font
					(size 0.7 0.7)
					(thickness 0.15)
				)
				(justify left bottom mirror)
			)
		)
		(property "Datasheet" "https://product.tdk.com/en/search/capacitor/ceramic/mlcc/info?part_no=C1005X5R1E474M050BB"
			(at 0 0 90)
			(layer "F.Fab")
			(hide yes)
			(effects
				(font
					(size 1.27 1.27)
					(thickness 0.15)
				)
			)
		)
		(property "Author" "Antmicro"
			(at 249.154992 66.854992 0)
			(layer "B.Fab")
			(hide yes)
			(effects
				(font
					(size 1 1)
					(thickness 0.15)
				)
				(justify mirror)
			)
		)
		(property "Dielectric" ""
			(at 249.154992 66.854992 0)
			(layer "B.Fab")
			(hide yes)
			(effects
				(font
					(size 1 1)
					(thickness 0.15)
				)
				(justify mirror)
			)
		)
		(property "License" "Apache-2.0"
			(at 249.154992 66.854992 0)
			(layer "B.Fab")
			(hide yes)
			(effects
				(font
					(size 1 1)
					(thickness 0.15)
				)
				(justify mirror)
			)
		)
		(property "MPN" "C1005X5R1E474M050BB"
			(at 249.154992 66.854992 0)
			(layer "B.Fab")
			(hide yes)
			(effects
				(font
					(size 1 1)
					(thickness 0.15)
				)
				(justify mirror)
			)
		)
		(property "Manufacturer" "TDK"
			(at 249.154992 66.854992 0)
			(layer "B.Fab")
			(hide yes)
			(effects
				(font
					(size 1 1)
					(thickness 0.15)
				)
				(justify mirror)
			)
		)
		(property "Val" "470n"
			(at 249.154992 66.854992 0)
			(layer "B.Fab")
			(hide yes)
			(effects
				(font
					(size 1 1)
					(thickness 0.15)
				)
				(justify mirror)
			)
		)
		(property "Voltage" ""
			(at 249.154992 66.854992 0)
			(layer "B.Fab")
			(hide yes)
			(effects
				(font
					(size 1 1)
					(thickness 0.15)
				)
				(justify mirror)
			)
		)
		(sheetname "/Ethernet/")
		(sheetfile "ethernet.kicad_sch")
		(attr smd)
		(fp_rect
			(start -0.9659 0.481258)
			(end 0.9649 -0.458742)
			(stroke
				(width 0.05)
				(type solid)
			)
			(fill no)
			(layer "B.CrtYd")
		)
		(fp_line
			(start 0.499 -0.248)
			(end -0.499 -0.248)
			(stroke
				(width 0.15)
				(type solid)
			)
			(layer "B.Fab")
		)
		(fp_line
			(start -0.499 -0.248)
			(end -0.499 0.25)
			(stroke
				(width 0.15)
				(type solid)
			)
			(layer "B.Fab")
		)
		(fp_line
			(start 0.499 0.25)
			(end 0.499 -0.248)
			(stroke
				(width 0.15)
				(type solid)
			)
			(layer "B.Fab")
		)
		(fp_line
			(start -0.499 0.25)
			(end 0.499 0.25)
			(stroke
				(width 0.15)
				(type solid)
			)
			(layer "B.Fab")
		)
		(pad "1" smd roundrect
			(at -0.484 0 90)
			(size 0.59 0.64)
			(layers "B.Cu" "B.Mask" "B.Paste")
			(roundrect_rratio 0.25)
			(net 199 "+1V2")
			(pintype "passive")
		)
		(pad "2" smd roundrect
			(at 0.484 0 90)
			(size 0.59 0.64)
			(layers "B.Cu" "B.Mask" "B.Paste")
			(roundrect_rratio 0.25)
			(net 1 "GND")
			(pintype "passive")
		)
	)
	(footprint "antmicro-footprints:C_0402_1005Metric"
		(layer "B.Cu")
		(at 94.061829 150.283157 90)
		(descr "Capacitor SMD 0402")
		(tags "capacitor SMD 0402")
		(property "Reference" "C140"
			(at 0 0.699 270)
			(layer "B.SilkS")
			(hide yes)
			(effects
				(font
					(size 0.7 0.7)
					(thickness 0.15)
				)
				(justify left bottom mirror)
			)
		)
		(property "Value" "C_10n_0402"
			(at -1.022927 -2.155213 270)
			(layer "B.Fab")
			(effects
				(font
					(size 0.7 0.7)
					(thickness 0.15)
				)
				(justify left bottom mirror)
			)
		)
		(property "Datasheet" "https://www.murata.com/products/productdetail?partno=GRM155R71H103KA88%23"
			(at 0 0 90)
			(layer "F.Fab")
			(hide yes)
			(effects
				(font
					(size 1.27 1.27)
					(thickness 0.15)
				)
			)
		)
		(property "Author" "Antmicro"
			(at 244.344986 56.221328 0)
			(layer "B.Fab")
			(hide yes)
			(effects
				(font
					(size 1 1)
					(thickness 0.15)
				)
				(justify mirror)
			)
		)
		(property "Dielectric" "X7R"
			(at 244.344986 56.221328 0)
			(layer "B.Fab")
			(hide yes)
			(effects
				(font
					(size 1 1)
					(thickness 0.15)
				)
				(justify mirror)
			)
		)
		(property "License" "Apache-2.0"
			(at 244.344986 56.221328 0)
			(layer "B.Fab")
			(hide yes)
			(effects
				(font
					(size 1 1)
					(thickness 0.15)
				)
				(justify mirror)
			)
		)
		(property "MPN" "GRM155R71H103KA88D"
			(at 244.344986 56.221328 0)
			(layer "B.Fab")
			(hide yes)
			(effects
				(font
					(size 1 1)
					(thickness 0.15)
				)
				(justify mirror)
			)
		)
		(property "Manufacturer" "Murata"
			(at 244.344986 56.221328 0)
			(layer "B.Fab")
			(hide yes)
			(effects
				(font
					(size 1 1)
					(thickness 0.15)
				)
				(justify mirror)
			)
		)
		(property "Val" "10n"
			(at 244.344986 56.221328 0)
			(layer "B.Fab")
			(hide yes)
			(effects
				(font
					(size 1 1)
					(thickness 0.15)
				)
				(justify mirror)
			)
		)
		(property "Voltage" "50V"
			(at 244.344986 56.221328 0)
			(layer "B.Fab")
			(hide yes)
			(effects
				(font
					(size 1 1)
					(thickness 0.15)
				)
				(justify mirror)
			)
		)
		(sheetname "/Ethernet/")
		(sheetfile "ethernet.kicad_sch")
		(attr smd)
		(fp_rect
			(start -0.9659 0.481258)
			(end 0.9649 -0.458742)
			(stroke
				(width 0.05)
				(type solid)
			)
			(fill no)
			(layer "B.CrtYd")
		)
		(fp_line
			(start 0.499 -0.248)
			(end -0.499 -0.248)
			(stroke
				(width 0.15)
				(type solid)
			)
			(layer "B.Fab")
		)
		(fp_line
			(start -0.499 -0.248)
			(end -0.499 0.25)
			(stroke
				(width 0.15)
				(type solid)
			)
			(layer "B.Fab")
		)
		(fp_line
			(start 0.499 0.25)
			(end 0.499 -0.248)
			(stroke
				(width 0.15)
				(type solid)
			)
			(layer "B.Fab")
		)
		(fp_line
			(start -0.499 0.25)
			(end 0.499 0.25)
			(stroke
				(width 0.15)
				(type solid)
			)
			(layer "B.Fab")
		)
		(pad "1" smd roundrect
			(at -0.484 0 90)
			(size 0.59 0.64)
			(layers "B.Cu" "B.Mask" "B.Paste")
			(roundrect_rratio 0.25)
			(net 132 "/Ethernet/AVDDL")
			(pintype "passive")
		)
		(pad "2" smd roundrect
			(at 0.484 0 90)
			(size 0.59 0.64)
			(layers "B.Cu" "B.Mask" "B.Paste")
			(roundrect_rratio 0.25)
			(net 1 "GND")
			(pintype "passive")
		)
	)
	(footprint "antmicro-footprints:C_0402_1005Metric"
		(layer "B.Cu")
		(at 94.308672 158.004992 90)
		(descr "Capacitor SMD 0402")
		(tags "capacitor SMD 0402")
		(property "Reference" "C141"
			(at 0 0.699 270)
			(layer "B.SilkS")
			(hide yes)
			(effects
				(font
					(size 0.7 0.7)
					(thickness 0.15)
				)
				(justify left bottom mirror)
			)
		)
		(property "Value" "C_10n_0402"
			(at -1.022927 -2.155213 270)
			(layer "B.Fab")
			(effects
				(font
					(size 0.7 0.7)
					(thickness 0.15)
				)
				(justify left bottom mirror)
			)
		)
		(property "Datasheet" "https://www.murata.com/products/productdetail?partno=GRM155R71H103KA88%23"
			(at 0 0 90)
			(layer "F.Fab")
			(hide yes)
			(effects
				(font
					(size 1.27 1.27)
					(thickness 0.15)
				)
			)
		)
		(property "Author" "Antmicro"
			(at 252.313664 63.69632 0)
			(layer "B.Fab")
			(hide yes)
			(effects
				(font
					(size 1 1)
					(thickness 0.15)
				)
				(justify mirror)
			)
		)
		(property "Dielectric" "X7R"
			(at 252.313664 63.69632 0)
			(layer "B.Fab")
			(hide yes)
			(effects
				(font
					(size 1 1)
					(thickness 0.15)
				)
				(justify mirror)
			)
		)
		(property "License" "Apache-2.0"
			(at 252.313664 63.69632 0)
			(layer "B.Fab")
			(hide yes)
			(effects
				(font
					(size 1 1)
					(thickness 0.15)
				)
				(justify mirror)
			)
		)
		(property "MPN" "GRM155R71H103KA88D"
			(at 252.313664 63.69632 0)
			(layer "B.Fab")
			(hide yes)
			(effects
				(font
					(size 1 1)
					(thickness 0.15)
				)
				(justify mirror)
			)
		)
		(property "Manufacturer" "Murata"
			(at 252.313664 63.69632 0)
			(layer "B.Fab")
			(hide yes)
			(effects
				(font
					(size 1 1)
					(thickness 0.15)
				)
				(justify mirror)
			)
		)
		(property "Val" "10n"
			(at 252.313664 63.69632 0)
			(layer "B.Fab")
			(hide yes)
			(effects
				(font
					(size 1 1)
					(thickness 0.15)
				)
				(justify mirror)
			)
		)
		(property "Voltage" "50V"
			(at 252.313664 63.69632 0)
			(layer "B.Fab")
			(hide yes)
			(effects
				(font
					(size 1 1)
					(thickness 0.15)
				)
				(justify mirror)
			)
		)
		(sheetname "/Ethernet/")
		(sheetfile "ethernet.kicad_sch")
		(attr smd)
		(fp_rect
			(start -0.9659 0.481258)
			(end 0.9649 -0.458742)
			(stroke
				(width 0.05)
				(type solid)
			)
			(fill no)
			(layer "B.CrtYd")
		)
		(fp_line
			(start 0.499 -0.248)
			(end -0.499 -0.248)
			(stroke
				(width 0.15)
				(type solid)
			)
			(layer "B.Fab")
		)
		(fp_line
			(start -0.499 -0.248)
			(end -0.499 0.25)
			(stroke
				(width 0.15)
				(type solid)
			)
			(layer "B.Fab")
		)
		(fp_line
			(start 0.499 0.25)
			(end 0.499 -0.248)
			(stroke
				(width 0.15)
				(type solid)
			)
			(layer "B.Fab")
		)
		(fp_line
			(start -0.499 0.25)
			(end 0.499 0.25)
			(stroke
				(width 0.15)
				(type solid)
			)
			(layer "B.Fab")
		)
		(pad "1" smd roundrect
			(at -0.484 0 90)
			(size 0.59 0.64)
			(layers "B.Cu" "B.Mask" "B.Paste")
			(roundrect_rratio 0.25)
			(net 200 "+3V3")
			(pintype "passive")
		)
		(pad "2" smd roundrect
			(at 0.484 0 90)
			(size 0.59 0.64)
			(layers "B.Cu" "B.Mask" "B.Paste")
			(roundrect_rratio 0.25)
			(net 1 "GND")
			(pintype "passive")
		)
	)
	(footprint "antmicro-footprints:C_0402_1005Metric"
		(layer "B.Cu")
		(at 97.886829 150.808157)
		(descr "Capacitor SMD 0402")
		(tags "capacitor SMD 0402")
		(property "Reference" "C152"
			(at 0 0.699 180)
			(layer "B.SilkS")
			(hide yes)
			(effects
				(font
					(size 0.7 0.7)
					(thickness 0.15)
				)
				(justify left bottom mirror)
			)
		)
		(property "Value" "C_4u7_0402"
			(at -1.022927 -2.155213 180)
			(layer "B.Fab")
			(effects
				(font
					(size 0.7 0.7)
					(thickness 0.15)
				)
				(justify left bottom mirror)
			)
		)
		(property "Datasheet" "https://www.murata.com/products/productdetail?partno=GRM155R61A475MEAA%23"
			(at 0 0 0)
			(layer "F.Fab")
			(hide yes)
			(effects
				(font
					(size 1.27 1.27)
					(thickness 0.15)
				)
			)
		)
		(property "Author" "Antmicro"
			(at 0 0 0)
			(layer "B.Fab")
			(hide yes)
			(effects
				(font
					(size 1 1)
					(thickness 0.15)
				)
				(justify mirror)
			)
		)
		(property "Dielectric" ""
			(at 0 0 0)
			(layer "B.Fab")
			(hide yes)
			(effects
				(font
					(size 1 1)
					(thickness 0.15)
				)
				(justify mirror)
			)
		)
		(property "License" "Apache-2.0"
			(at 0 0 0)
			(layer "B.Fab")
			(hide yes)
			(effects
				(font
					(size 1 1)
					(thickness 0.15)
				)
				(justify mirror)
			)
		)
		(property "MPN" "GRM155R61A475MEAAD"
			(at 0 0 0)
			(layer "B.Fab")
			(hide yes)
			(effects
				(font
					(size 1 1)
					(thickness 0.15)
				)
				(justify mirror)
			)
		)
		(property "Manufacturer" "Murata"
			(at 0 0 0)
			(layer "B.Fab")
			(hide yes)
			(effects
				(font
					(size 1 1)
					(thickness 0.15)
				)
				(justify mirror)
			)
		)
		(property "Val" "4u7"
			(at 0 0 0)
			(layer "B.Fab")
			(hide yes)
			(effects
				(font
					(size 1 1)
					(thickness 0.15)
				)
				(justify mirror)
			)
		)
		(property "Voltage" ""
			(at 0 0 0)
			(layer "B.Fab")
			(hide yes)
			(effects
				(font
					(size 1 1)
					(thickness 0.15)
				)
				(justify mirror)
			)
		)
		(sheetname "/Ethernet/")
		(sheetfile "ethernet.kicad_sch")
		(attr smd)
		(fp_rect
			(start -0.9659 0.481258)
			(end 0.9649 -0.458742)
			(stroke
				(width 0.05)
				(type solid)
			)
			(fill no)
			(layer "B.CrtYd")
		)
		(fp_line
			(start -0.499 -0.248)
			(end -0.499 0.25)
			(stroke
				(width 0.15)
				(type solid)
			)
			(layer "B.Fab")
		)
		(fp_line
			(start -0.499 0.25)
			(end 0.499 0.25)
			(stroke
				(width 0.15)
				(type solid)
			)
			(layer "B.Fab")
		)
		(fp_line
			(start 0.499 -0.248)
			(end -0.499 -0.248)
			(stroke
				(width 0.15)
				(type solid)
			)
			(layer "B.Fab")
		)
		(fp_line
			(start 0.499 0.25)
			(end 0.499 -0.248)
			(stroke
				(width 0.15)
				(type solid)
			)
			(layer "B.Fab")
		)
		(pad "1" smd roundrect
			(at -0.484 0)
			(size 0.59 0.64)
			(layers "B.Cu" "B.Mask" "B.Paste")
			(roundrect_rratio 0.25)
			(net 134 "/Ethernet/AVDDH")
			(pintype "passive")
		)
		(pad "2" smd roundrect
			(at 0.484 0)
			(size 0.59 0.64)
			(layers "B.Cu" "B.Mask" "B.Paste")
			(roundrect_rratio 0.25)
			(net 1 "GND")
			(pintype "passive")
		)
	)
	(footprint "antmicro-footprints:C_0402_1005Metric"
		(layer "B.Cu")
		(at 91.5 150.283157 90)
		(descr "Capacitor SMD 0402")
		(tags "capacitor SMD 0402")
		(property "Reference" "C136"
			(at 0 0.699 270)
			(layer "B.SilkS")
			(hide yes)
			(effects
				(font
					(size 0.7 0.7)
					(thickness 0.15)
				)
				(justify left bottom mirror)
			)
		)
		(property "Value" "C_10n_0402"
			(at -1.022927 -2.155213 270)
			(layer "B.Fab")
			(effects
				(font
					(size 0.7 0.7)
					(thickness 0.15)
				)
				(justify left bottom mirror)
			)
		)
		(property "Datasheet" "https://www.murata.com/products/productdetail?partno=GRM155R71H103KA88%23"
			(at 0 0 90)
			(layer "F.Fab")
			(hide yes)
			(effects
				(font
					(size 1.27 1.27)
					(thickness 0.15)
				)
			)
		)
		(property "Author" "Antmicro"
			(at 241.783157 58.783157 0)
			(layer "B.Fab")
			(hide yes)
			(effects
				(font
					(size 1 1)
					(thickness 0.15)
				)
				(justify mirror)
			)
		)
		(property "Dielectric" "X7R"
			(at 241.783157 58.783157 0)
			(layer "B.Fab")
			(hide yes)
			(effects
				(font
					(size 1 1)
					(thickness 0.15)
				)
				(justify mirror)
			)
		)
		(property "License" "Apache-2.0"
			(at 241.783157 58.783157 0)
			(layer "B.Fab")
			(hide yes)
			(effects
				(font
					(size 1 1)
					(thickness 0.15)
				)
				(justify mirror)
			)
		)
		(property "MPN" "GRM155R71H103KA88D"
			(at 241.783157 58.783157 0)
			(layer "B.Fab")
			(hide yes)
			(effects
				(font
					(size 1 1)
					(thickness 0.15)
				)
				(justify mirror)
			)
		)
		(property "Manufacturer" "Murata"
			(at 241.783157 58.783157 0)
			(layer "B.Fab")
			(hide yes)
			(effects
				(font
					(size 1 1)
					(thickness 0.15)
				)
				(justify mirror)
			)
		)
		(property "Val" "10n"
			(at 241.783157 58.783157 0)
			(layer "B.Fab")
			(hide yes)
			(effects
				(font
					(size 1 1)
					(thickness 0.15)
				)
				(justify mirror)
			)
		)
		(property "Voltage" "50V"
			(at 241.783157 58.783157 0)
			(layer "B.Fab")
			(hide yes)
			(effects
				(font
					(size 1 1)
					(thickness 0.15)
				)
				(justify mirror)
			)
		)
		(sheetname "/Ethernet/")
		(sheetfile "ethernet.kicad_sch")
		(attr smd)
		(fp_rect
			(start -0.9659 0.481258)
			(end 0.9649 -0.458742)
			(stroke
				(width 0.05)
				(type solid)
			)
			(fill no)
			(layer "B.CrtYd")
		)
		(fp_line
			(start 0.499 -0.248)
			(end -0.499 -0.248)
			(stroke
				(width 0.15)
				(type solid)
			)
			(layer "B.Fab")
		)
		(fp_line
			(start -0.499 -0.248)
			(end -0.499 0.25)
			(stroke
				(width 0.15)
				(type solid)
			)
			(layer "B.Fab")
		)
		(fp_line
			(start 0.499 0.25)
			(end 0.499 -0.248)
			(stroke
				(width 0.15)
				(type solid)
			)
			(layer "B.Fab")
		)
		(fp_line
			(start -0.499 0.25)
			(end 0.499 0.25)
			(stroke
				(width 0.15)
				(type solid)
			)
			(layer "B.Fab")
		)
		(pad "1" smd roundrect
			(at -0.484 0 90)
			(size 0.59 0.64)
			(layers "B.Cu" "B.Mask" "B.Paste")
			(roundrect_rratio 0.25)
			(net 132 "/Ethernet/AVDDL")
			(pintype "passive")
		)
		(pad "2" smd roundrect
			(at 0.484 0 90)
			(size 0.59 0.64)
			(layers "B.Cu" "B.Mask" "B.Paste")
			(roundrect_rratio 0.25)
			(net 1 "GND")
			(pintype "passive")
		)
	)
	(footprint "antmicro-footprints:C_0402_1005Metric"
		(layer "B.Cu")
		(at 98.1 155.2)
		(descr "Capacitor SMD 0402")
		(tags "capacitor SMD 0402")
		(property "Reference" "C144"
			(at 0 0.699 180)
			(layer "B.SilkS")
			(hide yes)
			(effects
				(font
					(size 0.7 0.7)
					(thickness 0.15)
				)
				(justify left bottom mirror)
			)
		)
		(property "Value" "C_10n_0402"
			(at -1.022927 -2.155213 180)
			(layer "B.Fab")
			(effects
				(font
					(size 0.7 0.7)
					(thickness 0.15)
				)
				(justify left bottom mirror)
			)
		)
		(property "Datasheet" "https://www.murata.com/products/productdetail?partno=GRM155R71H103KA88%23"
			(at 0 0 0)
			(layer "F.Fab")
			(hide yes)
			(effects
				(font
					(size 1.27 1.27)
					(thickness 0.15)
				)
			)
		)
		(property "Author" "Antmicro"
			(at 0 0 0)
			(layer "B.Fab")
			(hide yes)
			(effects
				(font
					(size 1 1)
					(thickness 0.15)
				)
				(justify mirror)
			)
		)
		(property "Dielectric" "X7R"
			(at 0 0 0)
			(layer "B.Fab")
			(hide yes)
			(effects
				(font
					(size 1 1)
					(thickness 0.15)
				)
				(justify mirror)
			)
		)
		(property "License" "Apache-2.0"
			(at 0 0 0)
			(layer "B.Fab")
			(hide yes)
			(effects
				(font
					(size 1 1)
					(thickness 0.15)
				)
				(justify mirror)
			)
		)
		(property "MPN" "GRM155R71H103KA88D"
			(at 0 0 0)
			(layer "B.Fab")
			(hide yes)
			(effects
				(font
					(size 1 1)
					(thickness 0.15)
				)
				(justify mirror)
			)
		)
		(property "Manufacturer" "Murata"
			(at 0 0 0)
			(layer "B.Fab")
			(hide yes)
			(effects
				(font
					(size 1 1)
					(thickness 0.15)
				)
				(justify mirror)
			)
		)
		(property "Val" "10n"
			(at 0 0 0)
			(layer "B.Fab")
			(hide yes)
			(effects
				(font
					(size 1 1)
					(thickness 0.15)
				)
				(justify mirror)
			)
		)
		(property "Voltage" "50V"
			(at 0 0 0)
			(layer "B.Fab")
			(hide yes)
			(effects
				(font
					(size 1 1)
					(thickness 0.15)
				)
				(justify mirror)
			)
		)
		(sheetname "/Ethernet/")
		(sheetfile "ethernet.kicad_sch")
		(attr smd)
		(fp_rect
			(start -0.9659 0.481258)
			(end 0.9649 -0.458742)
			(stroke
				(width 0.05)
				(type solid)
			)
			(fill no)
			(layer "B.CrtYd")
		)
		(fp_line
			(start -0.499 -0.248)
			(end -0.499 0.25)
			(stroke
				(width 0.15)
				(type solid)
			)
			(layer "B.Fab")
		)
		(fp_line
			(start -0.499 0.25)
			(end 0.499 0.25)
			(stroke
				(width 0.15)
				(type solid)
			)
			(layer "B.Fab")
		)
		(fp_line
			(start 0.499 -0.248)
			(end -0.499 -0.248)
			(stroke
				(width 0.15)
				(type solid)
			)
			(layer "B.Fab")
		)
		(fp_line
			(start 0.499 0.25)
			(end 0.499 -0.248)
			(stroke
				(width 0.15)
				(type solid)
			)
			(layer "B.Fab")
		)
		(pad "1" smd roundrect
			(at -0.484 0)
			(size 0.59 0.64)
			(layers "B.Cu" "B.Mask" "B.Paste")
			(roundrect_rratio 0.25)
			(net 200 "+3V3")
			(pintype "passive")
		)
		(pad "2" smd roundrect
			(at 0.484 0)
			(size 0.59 0.64)
			(layers "B.Cu" "B.Mask" "B.Paste")
			(roundrect_rratio 0.25)
			(net 1 "GND")
			(pintype "passive")
		)
	)
	(footprint "antmicro-footprints:C_0402_1005Metric"
		(layer "B.Cu")
		(at 90.086829 149.633157 90)
		(descr "Capacitor SMD 0402")
		(tags "capacitor SMD 0402")
		(property "Reference" "C155"
			(at 0 0.699 270)
			(layer "B.SilkS")
			(hide yes)
			(effects
				(font
					(size 0.7 0.7)
					(thickness 0.15)
				)
				(justify left bottom mirror)
			)
		)
		(property "Value" "C_4u7_0402"
			(at -1.022927 -2.155213 270)
			(layer "B.Fab")
			(effects
				(font
					(size 0.7 0.7)
					(thickness 0.15)
				)
				(justify left bottom mirror)
			)
		)
		(property "Datasheet" "https://www.murata.com/products/productdetail?partno=GRM155R61A475MEAA%23"
			(at 0 0 90)
			(layer "F.Fab")
			(hide yes)
			(effects
				(font
					(size 1.27 1.27)
					(thickness 0.15)
				)
			)
		)
		(property "Author" "Antmicro"
			(at 239.719986 59.546328 0)
			(layer "B.Fab")
			(hide yes)
			(effects
				(font
					(size 1 1)
					(thickness 0.15)
				)
				(justify mirror)
			)
		)
		(property "Dielectric" ""
			(at 239.719986 59.546328 0)
			(layer "B.Fab")
			(hide yes)
			(effects
				(font
					(size 1 1)
					(thickness 0.15)
				)
				(justify mirror)
			)
		)
		(property "License" "Apache-2.0"
			(at 239.719986 59.546328 0)
			(layer "B.Fab")
			(hide yes)
			(effects
				(font
					(size 1 1)
					(thickness 0.15)
				)
				(justify mirror)
			)
		)
		(property "MPN" "GRM155R61A475MEAAD"
			(at 239.719986 59.546328 0)
			(layer "B.Fab")
			(hide yes)
			(effects
				(font
					(size 1 1)
					(thickness 0.15)
				)
				(justify mirror)
			)
		)
		(property "Manufacturer" "Murata"
			(at 239.719986 59.546328 0)
			(layer "B.Fab")
			(hide yes)
			(effects
				(font
					(size 1 1)
					(thickness 0.15)
				)
				(justify mirror)
			)
		)
		(property "Val" "4u7"
			(at 239.719986 59.546328 0)
			(layer "B.Fab")
			(hide yes)
			(effects
				(font
					(size 1 1)
					(thickness 0.15)
				)
				(justify mirror)
			)
		)
		(property "Voltage" ""
			(at 239.719986 59.546328 0)
			(layer "B.Fab")
			(hide yes)
			(effects
				(font
					(size 1 1)
					(thickness 0.15)
				)
				(justify mirror)
			)
		)
		(sheetname "/Ethernet/")
		(sheetfile "ethernet.kicad_sch")
		(attr smd)
		(fp_rect
			(start -0.9659 0.481258)
			(end 0.9649 -0.458742)
			(stroke
				(width 0.05)
				(type solid)
			)
			(fill no)
			(layer "B.CrtYd")
		)
		(fp_line
			(start 0.499 -0.248)
			(end -0.499 -0.248)
			(stroke
				(width 0.15)
				(type solid)
			)
			(layer "B.Fab")
		)
		(fp_line
			(start -0.499 -0.248)
			(end -0.499 0.25)
			(stroke
				(width 0.15)
				(type solid)
			)
			(layer "B.Fab")
		)
		(fp_line
			(start 0.499 0.25)
			(end 0.499 -0.248)
			(stroke
				(width 0.15)
				(type solid)
			)
			(layer "B.Fab")
		)
		(fp_line
			(start -0.499 0.25)
			(end 0.499 0.25)
			(stroke
				(width 0.15)
				(type solid)
			)
			(layer "B.Fab")
		)
		(pad "1" smd roundrect
			(at -0.484 0 90)
			(size 0.59 0.64)
			(layers "B.Cu" "B.Mask" "B.Paste")
			(roundrect_rratio 0.25)
			(net 134 "/Ethernet/AVDDH")
			(pintype "passive")
		)
		(pad "2" smd roundrect
			(at 0.484 0 90)
			(size 0.59 0.64)
			(layers "B.Cu" "B.Mask" "B.Paste")
			(roundrect_rratio 0.25)
			(net 1 "GND")
			(pintype "passive")
		)
	)
	(footprint "antmicro-footprints:C_0402_1005Metric"
		(layer "B.Cu")
		(at 92.308672 158.004992 90)
		(descr "Capacitor SMD 0402")
		(tags "capacitor SMD 0402")
		(property "Reference" "C151"
			(at 0 0.699 270)
			(layer "B.SilkS")
			(hide yes)
			(effects
				(font
					(size 0.7 0.7)
					(thickness 0.15)
				)
				(justify left bottom mirror)
			)
		)
		(property "Value" "C_10n_0402"
			(at -1.022927 -2.155213 270)
			(layer "B.Fab")
			(effects
				(font
					(size 0.7 0.7)
					(thickness 0.15)
				)
				(justify left bottom mirror)
			)
		)
		(property "Datasheet" "https://www.murata.com/products/productdetail?partno=GRM155R71H103KA88%23"
			(at 0 0 90)
			(layer "F.Fab")
			(hide yes)
			(effects
				(font
					(size 1.27 1.27)
					(thickness 0.15)
				)
			)
		)
		(property "Author" "Antmicro"
			(at 250.313664 65.69632 0)
			(layer "B.Fab")
			(hide yes)
			(effects
				(font
					(size 1 1)
					(thickness 0.15)
				)
				(justify mirror)
			)
		)
		(property "Dielectric" "X7R"
			(at 250.313664 65.69632 0)
			(layer "B.Fab")
			(hide yes)
			(effects
				(font
					(size 1 1)
					(thickness 0.15)
				)
				(justify mirror)
			)
		)
		(property "License" "Apache-2.0"
			(at 250.313664 65.69632 0)
			(layer "B.Fab")
			(hide yes)
			(effects
				(font
					(size 1 1)
					(thickness 0.15)
				)
				(justify mirror)
			)
		)
		(property "MPN" "GRM155R71H103KA88D"
			(at 250.313664 65.69632 0)
			(layer "B.Fab")
			(hide yes)
			(effects
				(font
					(size 1 1)
					(thickness 0.15)
				)
				(justify mirror)
			)
		)
		(property "Manufacturer" "Murata"
			(at 250.313664 65.69632 0)
			(layer "B.Fab")
			(hide yes)
			(effects
				(font
					(size 1 1)
					(thickness 0.15)
				)
				(justify mirror)
			)
		)
		(property "Val" "10n"
			(at 250.313664 65.69632 0)
			(layer "B.Fab")
			(hide yes)
			(effects
				(font
					(size 1 1)
					(thickness 0.15)
				)
				(justify mirror)
			)
		)
		(property "Voltage" "50V"
			(at 250.313664 65.69632 0)
			(layer "B.Fab")
			(hide yes)
			(effects
				(font
					(size 1 1)
					(thickness 0.15)
				)
				(justify mirror)
			)
		)
		(sheetname "/Ethernet/")
		(sheetfile "ethernet.kicad_sch")
		(attr smd)
		(fp_rect
			(start -0.9659 0.481258)
			(end 0.9649 -0.458742)
			(stroke
				(width 0.05)
				(type solid)
			)
			(fill no)
			(layer "B.CrtYd")
		)
		(fp_line
			(start 0.499 -0.248)
			(end -0.499 -0.248)
			(stroke
				(width 0.15)
				(type solid)
			)
			(layer "B.Fab")
		)
		(fp_line
			(start -0.499 -0.248)
			(end -0.499 0.25)
			(stroke
				(width 0.15)
				(type solid)
			)
			(layer "B.Fab")
		)
		(fp_line
			(start 0.499 0.25)
			(end 0.499 -0.248)
			(stroke
				(width 0.15)
				(type solid)
			)
			(layer "B.Fab")
		)
		(fp_line
			(start -0.499 0.25)
			(end 0.499 0.25)
			(stroke
				(width 0.15)
				(type solid)
			)
			(layer "B.Fab")
		)
		(pad "1" smd roundrect
			(at -0.484 0 90)
			(size 0.59 0.64)
			(layers "B.Cu" "B.Mask" "B.Paste")
			(roundrect_rratio 0.25)
			(net 199 "+1V2")
			(pintype "passive")
		)
		(pad "2" smd roundrect
			(at 0.484 0 90)
			(size 0.59 0.64)
			(layers "B.Cu" "B.Mask" "B.Paste")
			(roundrect_rratio 0.25)
			(net 1 "GND")
			(pintype "passive")
		)
	)
	(footprint "antmicro-footprints:C_0402_1005Metric"
		(layer "B.Cu")
		(at 89.086829 149.633157 90)
		(descr "Capacitor SMD 0402")
		(tags "capacitor SMD 0402")
		(property "Reference" "C158"
			(at 0 0.699 270)
			(layer "B.SilkS")
			(hide yes)
			(effects
				(font
					(size 0.7 0.7)
					(thickness 0.15)
				)
				(justify left bottom mirror)
			)
		)
		(property "Value" "C_4u7_0402"
			(at -1.022927 -2.155213 270)
			(layer "B.Fab")
			(effects
				(font
					(size 0.7 0.7)
					(thickness 0.15)
				)
				(justify left bottom mirror)
			)
		)
		(property "Datasheet" "https://www.murata.com/products/productdetail?partno=GRM155R61A475MEAA%23"
			(at 0 0 90)
			(layer "F.Fab")
			(hide yes)
			(effects
				(font
					(size 1.27 1.27)
					(thickness 0.15)
				)
			)
		)
		(property "Author" "Antmicro"
			(at 238.719986 60.546328 0)
			(layer "B.Fab")
			(hide yes)
			(effects
				(font
					(size 1 1)
					(thickness 0.15)
				)
				(justify mirror)
			)
		)
		(property "Dielectric" ""
			(at 238.719986 60.546328 0)
			(layer "B.Fab")
			(hide yes)
			(effects
				(font
					(size 1 1)
					(thickness 0.15)
				)
				(justify mirror)
			)
		)
		(property "License" "Apache-2.0"
			(at 238.719986 60.546328 0)
			(layer "B.Fab")
			(hide yes)
			(effects
				(font
					(size 1 1)
					(thickness 0.15)
				)
				(justify mirror)
			)
		)
		(property "MPN" "GRM155R61A475MEAAD"
			(at 238.719986 60.546328 0)
			(layer "B.Fab")
			(hide yes)
			(effects
				(font
					(size 1 1)
					(thickness 0.15)
				)
				(justify mirror)
			)
		)
		(property "Manufacturer" "Murata"
			(at 238.719986 60.546328 0)
			(layer "B.Fab")
			(hide yes)
			(effects
				(font
					(size 1 1)
					(thickness 0.15)
				)
				(justify mirror)
			)
		)
		(property "Val" "4u7"
			(at 238.719986 60.546328 0)
			(layer "B.Fab")
			(hide yes)
			(effects
				(font
					(size 1 1)
					(thickness 0.15)
				)
				(justify mirror)
			)
		)
		(property "Voltage" ""
			(at 238.719986 60.546328 0)
			(layer "B.Fab")
			(hide yes)
			(effects
				(font
					(size 1 1)
					(thickness 0.15)
				)
				(justify mirror)
			)
		)
		(sheetname "/Ethernet/")
		(sheetfile "ethernet.kicad_sch")
		(attr smd)
		(fp_rect
			(start -0.9659 0.481258)
			(end 0.9649 -0.458742)
			(stroke
				(width 0.05)
				(type solid)
			)
			(fill no)
			(layer "B.CrtYd")
		)
		(fp_line
			(start 0.499 -0.248)
			(end -0.499 -0.248)
			(stroke
				(width 0.15)
				(type solid)
			)
			(layer "B.Fab")
		)
		(fp_line
			(start -0.499 -0.248)
			(end -0.499 0.25)
			(stroke
				(width 0.15)
				(type solid)
			)
			(layer "B.Fab")
		)
		(fp_line
			(start 0.499 0.25)
			(end 0.499 -0.248)
			(stroke
				(width 0.15)
				(type solid)
			)
			(layer "B.Fab")
		)
		(fp_line
			(start -0.499 0.25)
			(end 0.499 0.25)
			(stroke
				(width 0.15)
				(type solid)
			)
			(layer "B.Fab")
		)
		(pad "1" smd roundrect
			(at -0.484 0 90)
			(size 0.59 0.64)
			(layers "B.Cu" "B.Mask" "B.Paste")
			(roundrect_rratio 0.25)
			(net 134 "/Ethernet/AVDDH")
			(pintype "passive")
		)
		(pad "2" smd roundrect
			(at 0.484 0 90)
			(size 0.59 0.64)
			(layers "B.Cu" "B.Mask" "B.Paste")
			(roundrect_rratio 0.25)
			(net 1 "GND")
			(pintype "passive")
		)
	)
	(footprint "antmicro-footprints:C_0402_1005Metric"
		(layer "B.Cu")
		(at 90.108672 158.004992 90)
		(descr "Capacitor SMD 0402")
		(tags "capacitor SMD 0402")
		(property "Reference" "C153"
			(at 0 0.699 270)
			(layer "B.SilkS")
			(hide yes)
			(effects
				(font
					(size 0.7 0.7)
					(thickness 0.15)
				)
				(justify left bottom mirror)
			)
		)
		(property "Value" "C_10n_0402"
			(at -1.022927 -2.155213 270)
			(layer "B.Fab")
			(effects
				(font
					(size 0.7 0.7)
					(thickness 0.15)
				)
				(justify left bottom mirror)
			)
		)
		(property "Datasheet" "https://www.murata.com/products/productdetail?partno=GRM155R71H103KA88%23"
			(at 0 0 90)
			(layer "F.Fab")
			(hide yes)
			(effects
				(font
					(size 1.27 1.27)
					(thickness 0.15)
				)
			)
		)
		(property "Author" "Antmicro"
			(at 248.113664 67.89632 0)
			(layer "B.Fab")
			(hide yes)
			(effects
				(font
					(size 1 1)
					(thickness 0.15)
				)
				(justify mirror)
			)
		)
		(property "Dielectric" "X7R"
			(at 248.113664 67.89632 0)
			(layer "B.Fab")
			(hide yes)
			(effects
				(font
					(size 1 1)
					(thickness 0.15)
				)
				(justify mirror)
			)
		)
		(property "License" "Apache-2.0"
			(at 248.113664 67.89632 0)
			(layer "B.Fab")
			(hide yes)
			(effects
				(font
					(size 1 1)
					(thickness 0.15)
				)
				(justify mirror)
			)
		)
		(property "MPN" "GRM155R71H103KA88D"
			(at 248.113664 67.89632 0)
			(layer "B.Fab")
			(hide yes)
			(effects
				(font
					(size 1 1)
					(thickness 0.15)
				)
				(justify mirror)
			)
		)
		(property "Manufacturer" "Murata"
			(at 248.113664 67.89632 0)
			(layer "B.Fab")
			(hide yes)
			(effects
				(font
					(size 1 1)
					(thickness 0.15)
				)
				(justify mirror)
			)
		)
		(property "Val" "10n"
			(at 248.113664 67.89632 0)
			(layer "B.Fab")
			(hide yes)
			(effects
				(font
					(size 1 1)
					(thickness 0.15)
				)
				(justify mirror)
			)
		)
		(property "Voltage" "50V"
			(at 248.113664 67.89632 0)
			(layer "B.Fab")
			(hide yes)
			(effects
				(font
					(size 1 1)
					(thickness 0.15)
				)
				(justify mirror)
			)
		)
		(sheetname "/Ethernet/")
		(sheetfile "ethernet.kicad_sch")
		(attr smd)
		(fp_rect
			(start -0.9659 0.481258)
			(end 0.9649 -0.458742)
			(stroke
				(width 0.05)
				(type solid)
			)
			(fill no)
			(layer "B.CrtYd")
		)
		(fp_line
			(start 0.499 -0.248)
			(end -0.499 -0.248)
			(stroke
				(width 0.15)
				(type solid)
			)
			(layer "B.Fab")
		)
		(fp_line
			(start -0.499 -0.248)
			(end -0.499 0.25)
			(stroke
				(width 0.15)
				(type solid)
			)
			(layer "B.Fab")
		)
		(fp_line
			(start 0.499 0.25)
			(end 0.499 -0.248)
			(stroke
				(width 0.15)
				(type solid)
			)
			(layer "B.Fab")
		)
		(fp_line
			(start -0.499 0.25)
			(end 0.499 0.25)
			(stroke
				(width 0.15)
				(type solid)
			)
			(layer "B.Fab")
		)
		(pad "1" smd roundrect
			(at -0.484 0 90)
			(size 0.59 0.64)
			(layers "B.Cu" "B.Mask" "B.Paste")
			(roundrect_rratio 0.25)
			(net 199 "+1V2")
			(pintype "passive")
		)
		(pad "2" smd roundrect
			(at 0.484 0 90)
			(size 0.59 0.64)
			(layers "B.Cu" "B.Mask" "B.Paste")
			(roundrect_rratio 0.25)
			(net 1 "GND")
			(pintype "passive")
		)
	)
	(footprint "antmicro-footprints:FB_0603_1608Metric"
		(layer "B.Cu")
		(at 98.200501 149.558851 180)
		(property "Reference" "FB5"
			(at 0 0.8 0)
			(layer "B.SilkS")
			(hide yes)
			(effects
				(font
					(size 0.7 0.7)
					(thickness 0.15)
				)
				(justify left bottom mirror)
			)
		)
		(property "Value" "FB_120Z_2A_Murata-BLM18PG_0603"
			(at 0 -1.5 0)
			(layer "B.Fab")
			(effects
				(font
					(size 0.7 0.7)
					(thickness 0.15)
				)
				(justify left bottom mirror)
			)
		)
		(property "Datasheet" "https://www.murata.com/en-us/products/productdata/8796738650142/ENFA0003.pdf"
			(at 0 0 180)
			(layer "F.Fab")
			(hide yes)
			(effects
				(font
					(size 1.27 1.27)
					(thickness 0.15)
				)
			)
		)
		(property "Author" "Antmicro"
			(at 196.401002 299.117702 0)
			(layer "B.Fab")
			(hide yes)
			(effects
				(font
					(size 1 1)
					(thickness 0.15)
				)
				(justify mirror)
			)
		)
		(property "License" "Apache-2.0"
			(at 196.401002 299.117702 0)
			(layer "B.Fab")
			(hide yes)
			(effects
				(font
					(size 1 1)
					(thickness 0.15)
				)
				(justify mirror)
			)
		)
		(property "MPN" "BLM18PG121SN1D"
			(at 196.401002 299.117702 0)
			(layer "B.Fab")
			(hide yes)
			(effects
				(font
					(size 1 1)
					(thickness 0.15)
				)
				(justify mirror)
			)
		)
		(property "Manufacturer" "Murata"
			(at 196.401002 299.117702 0)
			(layer "B.Fab")
			(hide yes)
			(effects
				(font
					(size 1 1)
					(thickness 0.15)
				)
				(justify mirror)
			)
		)
		(property "Val" "120Z/2A"
			(at 196.401002 299.117702 0)
			(layer "B.Fab")
			(hide yes)
			(effects
				(font
					(size 1 1)
					(thickness 0.15)
				)
				(justify mirror)
			)
		)
		(sheetname "/Ethernet/")
		(sheetfile "ethernet.kicad_sch")
		(attr smd)
		(fp_line
			(start -0.196 0.408)
			(end 0.193 0.408)
			(stroke
				(width 0.15)
				(type solid)
			)
			(layer "B.SilkS")
		)
		(fp_line
			(start -0.196 -0.406)
			(end 0.193 -0.406)
			(stroke
				(width 0.15)
				(type solid)
			)
			(layer "B.SilkS")
		)
		(fp_rect
			(start -1.3 0.6)
			(end 1.3 -0.6)
			(stroke
				(width 0.05)
				(type solid)
			)
			(fill no)
			(layer "B.CrtYd")
		)
		(fp_line
			(start 0.8 0.408)
			(end 0.8 -0.406)
			(stroke
				(width 0.15)
				(type solid)
			)
			(layer "B.Fab")
		)
		(fp_line
			(start 0.8 0.408)
			(end -0.803 0.408)
			(stroke
				(width 0.15)
				(type solid)
			)
			(layer "B.Fab")
		)
		(fp_line
			(start 0.8 -0.406)
			(end -0.803 -0.406)
			(stroke
				(width 0.15)
				(type solid)
			)
			(layer "B.Fab")
		)
		(fp_line
			(start -0.803 -0.406)
			(end -0.803 0.408)
			(stroke
				(width 0.15)
				(type solid)
			)
			(layer "B.Fab")
		)
		(pad "1" smd roundrect
			(at -0.891 0 180)
			(size 0.762 1.09)
			(layers "B.Cu" "B.Mask" "B.Paste")
			(roundrect_rratio 0.15)
			(net 200 "+3V3")
			(pintype "passive")
		)
		(pad "2" smd roundrect
			(at 0.888 0 180)
			(size 0.762 1.09)
			(layers "B.Cu" "B.Mask" "B.Paste")
			(roundrect_rratio 0.15)
			(net 134 "/Ethernet/AVDDH")
			(pintype "passive")
		)
	)
	(footprint "antmicro-footprints:FB_0603_1608Metric"
		(layer "B.Cu")
		(at 93.086829 152.558157)
		(property "Reference" "FB4"
			(at 0 0.8 180)
			(layer "B.SilkS")
			(hide yes)
			(effects
				(font
					(size 0.7 0.7)
					(thickness 0.15)
				)
				(justify left bottom mirror)
			)
		)
		(property "Value" "FB_120Z_2A_Murata-BLM18PG_0603"
			(at 0 -1.5 180)
			(layer "B.Fab")
			(effects
				(font
					(size 0.7 0.7)
					(thickness 0.15)
				)
				(justify left bottom mirror)
			)
		)
		(property "Datasheet" "https://www.murata.com/en-us/products/productdata/8796738650142/ENFA0003.pdf"
			(at 0 0 0)
			(layer "F.Fab")
			(hide yes)
			(effects
				(font
					(size 1.27 1.27)
					(thickness 0.15)
				)
			)
		)
		(property "Author" "Antmicro"
			(at 0 0 0)
			(layer "B.Fab")
			(hide yes)
			(effects
				(font
					(size 1 1)
					(thickness 0.15)
				)
				(justify mirror)
			)
		)
		(property "License" "Apache-2.0"
			(at 0 0 0)
			(layer "B.Fab")
			(hide yes)
			(effects
				(font
					(size 1 1)
					(thickness 0.15)
				)
				(justify mirror)
			)
		)
		(property "MPN" "BLM18PG121SN1D"
			(at 0 0 0)
			(layer "B.Fab")
			(hide yes)
			(effects
				(font
					(size 1 1)
					(thickness 0.15)
				)
				(justify mirror)
			)
		)
		(property "Manufacturer" "Murata"
			(at 0 0 0)
			(layer "B.Fab")
			(hide yes)
			(effects
				(font
					(size 1 1)
					(thickness 0.15)
				)
				(justify mirror)
			)
		)
		(property "Val" "120Z/2A"
			(at 0 0 0)
			(layer "B.Fab")
			(hide yes)
			(effects
				(font
					(size 1 1)
					(thickness 0.15)
				)
				(justify mirror)
			)
		)
		(sheetname "/Ethernet/")
		(sheetfile "ethernet.kicad_sch")
		(attr smd)
		(fp_line
			(start -0.196 -0.406)
			(end 0.193 -0.406)
			(stroke
				(width 0.15)
				(type solid)
			)
			(layer "B.SilkS")
		)
		(fp_line
			(start -0.196 0.408)
			(end 0.193 0.408)
			(stroke
				(width 0.15)
				(type solid)
			)
			(layer "B.SilkS")
		)
		(fp_rect
			(start -1.3 0.6)
			(end 1.3 -0.6)
			(stroke
				(width 0.05)
				(type solid)
			)
			(fill no)
			(layer "B.CrtYd")
		)
		(fp_line
			(start -0.803 -0.406)
			(end -0.803 0.408)
			(stroke
				(width 0.15)
				(type solid)
			)
			(layer "B.Fab")
		)
		(fp_line
			(start 0.8 -0.406)
			(end -0.803 -0.406)
			(stroke
				(width 0.15)
				(type solid)
			)
			(layer "B.Fab")
		)
		(fp_line
			(start 0.8 0.408)
			(end -0.803 0.408)
			(stroke
				(width 0.15)
				(type solid)
			)
			(layer "B.Fab")
		)
		(fp_line
			(start 0.8 0.408)
			(end 0.8 -0.406)
			(stroke
				(width 0.15)
				(type solid)
			)
			(layer "B.Fab")
		)
		(pad "1" smd roundrect
			(at -0.891 0)
			(size 0.762 1.09)
			(layers "B.Cu" "B.Mask" "B.Paste")
			(roundrect_rratio 0.15)
			(net 199 "+1V2")
			(pintype "passive")
		)
		(pad "2" smd roundrect
			(at 0.888 0)
			(size 0.762 1.09)
			(layers "B.Cu" "B.Mask" "B.Paste")
			(roundrect_rratio 0.15)
			(net 132 "/Ethernet/AVDDL")
			(pintype "passive")
		)
	)
	(footprint "antmicro-footprints:R_0402_1005Metric"
		(layer "B.Cu")
		(at 75.75 140.3 90)
		(descr "Resistor SMD 0402")
		(tags "resistor SMD 0402")
		(property "Reference" "R98"
			(at -1.122484 0.772697 270)
			(layer "B.SilkS")
			(hide yes)
			(effects
				(font
					(size 0.7 0.7)
					(thickness 0.15)
				)
				(justify left bottom mirror)
			)
		)
		(property "Value" "R_220R_0402"
			(at -1.011843 -1.772047 270)
			(layer "B.Fab")
			(effects
				(font
					(size 0.7 0.7)
					(thickness 0.15)
				)
				(justify left bottom mirror)
			)
		)
		(property "Datasheet" "https://www.bourns.com/docs/product-datasheets/cr.pdf"
			(at 0 0 90)
			(layer "F.Fab")
			(hide yes)
			(effects
				(font
					(size 1.27 1.27)
					(thickness 0.15)
				)
			)
		)
		(property "Author" "Antmicro"
			(at 216.05 64.55 0)
			(layer "B.Fab")
			(hide yes)
			(effects
				(font
					(size 1 1)
					(thickness 0.15)
				)
				(justify mirror)
			)
		)
		(property "License" "Apache-2.0"
			(at 216.05 64.55 0)
			(layer "B.Fab")
			(hide yes)
			(effects
				(font
					(size 1 1)
					(thickness 0.15)
				)
				(justify mirror)
			)
		)
		(property "MPN" "CR0402-FX-2200GLF"
			(at 216.05 64.55 0)
			(layer "B.Fab")
			(hide yes)
			(effects
				(font
					(size 1 1)
					(thickness 0.15)
				)
				(justify mirror)
			)
		)
		(property "Manufacturer" "Bourns"
			(at 216.05 64.55 0)
			(layer "B.Fab")
			(hide yes)
			(effects
				(font
					(size 1 1)
					(thickness 0.15)
				)
				(justify mirror)
			)
		)
		(property "Tolerance" "1%"
			(at 216.05 64.55 0)
			(layer "B.Fab")
			(hide yes)
			(effects
				(font
					(size 1 1)
					(thickness 0.15)
				)
				(justify mirror)
			)
		)
		(property "Val" "220R"
			(at 216.05 64.55 0)
			(layer "B.Fab")
			(hide yes)
			(effects
				(font
					(size 1 1)
					(thickness 0.15)
				)
				(justify mirror)
			)
		)
		(sheetname "/Ethernet/")
		(sheetfile "ethernet.kicad_sch")
		(attr smd)
		(fp_rect
			(start -0.93 0.47)
			(end 0.93 -0.47)
			(stroke
				(width 0.05)
				(type solid)
			)
			(fill no)
			(layer "B.CrtYd")
		)
		(fp_rect
			(start -0.5 0.25)
			(end 0.5 -0.25)
			(stroke
				(width 0.15)
				(type solid)
			)
			(fill no)
			(layer "B.Fab")
		)
		(pad "1" smd roundrect
			(at -0.485 0 90)
			(size 0.59 0.64)
			(layers "B.Cu" "B.Mask" "B.Paste")
			(roundrect_rratio 0.25)
			(net 757 "Net-(J6-LED_Y+)")
			(pintype "passive")
		)
		(pad "2" smd roundrect
			(at 0.485 0 90)
			(size 0.59 0.64)
			(layers "B.Cu" "B.Mask" "B.Paste")
			(roundrect_rratio 0.25)
			(net 200 "+3V3")
			(pintype "passive")
		)
	)
	(footprint "antmicro-footprints:R_0402_1005Metric"
		(layer "B.Cu")
		(at 75.770501 133.886 -90)
		(descr "Resistor SMD 0402")
		(tags "resistor SMD 0402")
		(property "Reference" "R99"
			(at -1.122484 0.772697 90)
			(layer "B.SilkS")
			(hide yes)
			(effects
				(font
					(size 0.7 0.7)
					(thickness 0.15)
				)
				(justify left bottom mirror)
			)
		)
		(property "Value" "R_220R_0402"
			(at -1.011843 -1.772047 90)
			(layer "B.Fab")
			(effects
				(font
					(size 0.7 0.7)
					(thickness 0.15)
				)
				(justify left bottom mirror)
			)
		)
		(property "Datasheet" "https://www.bourns.com/docs/product-datasheets/cr.pdf"
			(at 0 0 270)
			(layer "F.Fab")
			(hide yes)
			(effects
				(font
					(size 1.27 1.27)
					(thickness 0.15)
				)
			)
		)
		(property "Author" "Antmicro"
			(at -58.115499 209.656501 0)
			(layer "B.Fab")
			(hide yes)
			(effects
				(font
					(size 1 1)
					(thickness 0.15)
				)
				(justify mirror)
			)
		)
		(property "License" "Apache-2.0"
			(at -58.115499 209.656501 0)
			(layer "B.Fab")
			(hide yes)
			(effects
				(font
					(size 1 1)
					(thickness 0.15)
				)
				(justify mirror)
			)
		)
		(property "MPN" "CR0402-FX-2200GLF"
			(at -58.115499 209.656501 0)
			(layer "B.Fab")
			(hide yes)
			(effects
				(font
					(size 1 1)
					(thickness 0.15)
				)
				(justify mirror)
			)
		)
		(property "Manufacturer" "Bourns"
			(at -58.115499 209.656501 0)
			(layer "B.Fab")
			(hide yes)
			(effects
				(font
					(size 1 1)
					(thickness 0.15)
				)
				(justify mirror)
			)
		)
		(property "Tolerance" "1%"
			(at -58.115499 209.656501 0)
			(layer "B.Fab")
			(hide yes)
			(effects
				(font
					(size 1 1)
					(thickness 0.15)
				)
				(justify mirror)
			)
		)
		(property "Val" "220R"
			(at -58.115499 209.656501 0)
			(layer "B.Fab")
			(hide yes)
			(effects
				(font
					(size 1 1)
					(thickness 0.15)
				)
				(justify mirror)
			)
		)
		(sheetname "/Ethernet/")
		(sheetfile "ethernet.kicad_sch")
		(attr smd)
		(fp_rect
			(start -0.93 0.47)
			(end 0.93 -0.47)
			(stroke
				(width 0.05)
				(type solid)
			)
			(fill no)
			(layer "B.CrtYd")
		)
		(fp_rect
			(start -0.5 0.25)
			(end 0.5 -0.25)
			(stroke
				(width 0.15)
				(type solid)
			)
			(fill no)
			(layer "B.Fab")
		)
		(pad "1" smd roundrect
			(at -0.485 0 270)
			(size 0.59 0.64)
			(layers "B.Cu" "B.Mask" "B.Paste")
			(roundrect_rratio 0.25)
			(net 758 "Net-(J6-LED_G+)")
			(pintype "passive")
		)
		(pad "2" smd roundrect
			(at 0.485 0 270)
			(size 0.59 0.64)
			(layers "B.Cu" "B.Mask" "B.Paste")
			(roundrect_rratio 0.25)
			(net 200 "+3V3")
			(pintype "passive")
		)
	)
	(footprint "antmicro-footprints:R_0402_1005Metric"
		(layer "B.Cu")
		(at 99.525501 163.951 -90)
		(descr "Resistor SMD 0402")
		(tags "resistor SMD 0402")
		(property "Reference" "R113"
			(at -1.122484 0.772697 90)
			(layer "B.SilkS")
			(hide yes)
			(effects
				(font
					(size 0.7 0.7)
					(thickness 0.15)
				)
				(justify left bottom mirror)
			)
		)
		(property "Value" "R_2k2_0402"
			(at -1.011843 -1.772047 90)
			(layer "B.Fab")
			(effects
				(font
					(size 0.7 0.7)
					(thickness 0.15)
				)
				(justify left bottom mirror)
			)
		)
		(property "Datasheet" "https://www.bourns.com/docs/product-datasheets/cr.pdf"
			(at 0 0 270)
			(layer "F.Fab")
			(hide yes)
			(effects
				(font
					(size 1.27 1.27)
					(thickness 0.15)
				)
			)
		)
		(property "Author" "Antmicro"
			(at -64.425499 263.476501 0)
			(layer "B.Fab")
			(hide yes)
			(effects
				(font
					(size 1 1)
					(thickness 0.15)
				)
				(justify mirror)
			)
		)
		(property "License" "Apache-2.0"
			(at -64.425499 263.476501 0)
			(layer "B.Fab")
			(hide yes)
			(effects
				(font
					(size 1 1)
					(thickness 0.15)
				)
				(justify mirror)
			)
		)
		(property "MPN" "CR0402-FX-2201GLF"
			(at -64.425499 263.476501 0)
			(layer "B.Fab")
			(hide yes)
			(effects
				(font
					(size 1 1)
					(thickness 0.15)
				)
				(justify mirror)
			)
		)
		(property "Manufacturer" "Bourns"
			(at -64.425499 263.476501 0)
			(layer "B.Fab")
			(hide yes)
			(effects
				(font
					(size 1 1)
					(thickness 0.15)
				)
				(justify mirror)
			)
		)
		(property "Tolerance" "1%"
			(at -64.425499 263.476501 0)
			(layer "B.Fab")
			(hide yes)
			(effects
				(font
					(size 1 1)
					(thickness 0.15)
				)
				(justify mirror)
			)
		)
		(property "Val" "2k2"
			(at -64.425499 263.476501 0)
			(layer "B.Fab")
			(hide yes)
			(effects
				(font
					(size 1 1)
					(thickness 0.15)
				)
				(justify mirror)
			)
		)
		(sheetname "/Ethernet/")
		(sheetfile "ethernet.kicad_sch")
		(attr smd)
		(fp_rect
			(start -0.93 0.47)
			(end 0.93 -0.47)
			(stroke
				(width 0.05)
				(type solid)
			)
			(fill no)
			(layer "B.CrtYd")
		)
		(fp_rect
			(start -0.5 0.25)
			(end 0.5 -0.25)
			(stroke
				(width 0.15)
				(type solid)
			)
			(fill no)
			(layer "B.Fab")
		)
		(pad "1" smd roundrect
			(at -0.485 0 270)
			(size 0.59 0.64)
			(layers "B.Cu" "B.Mask" "B.Paste")
			(roundrect_rratio 0.25)
			(net 673 "/Ethernet/ETH.RXD0")
			(pintype "passive")
		)
		(pad "2" smd roundrect
			(at 0.485 0 270)
			(size 0.59 0.64)
			(layers "B.Cu" "B.Mask" "B.Paste")
			(roundrect_rratio 0.25)
			(net 1 "GND")
			(pintype "passive")
		)
	)
	(footprint "antmicro-footprints:R_0402_1005Metric"
		(layer "B.Cu")
		(at 98.1 158.1 180)
		(descr "Resistor SMD 0402")
		(tags "resistor SMD 0402")
		(property "Reference" "R110"
			(at -1.122484 0.772697 0)
			(layer "B.SilkS")
			(hide yes)
			(effects
				(font
					(size 0.7 0.7)
					(thickness 0.15)
				)
				(justify left bottom mirror)
			)
		)
		(property "Value" "R_1k_0402"
			(at -1.011843 -1.772047 0)
			(layer "B.Fab")
			(effects
				(font
					(size 0.7 0.7)
					(thickness 0.15)
				)
				(justify left bottom mirror)
			)
		)
		(property "Datasheet" "https://www.bourns.com/docs/product-datasheets/cr.pdf"
			(at 0 0 180)
			(layer "F.Fab")
			(hide yes)
			(effects
				(font
					(size 1.27 1.27)
					(thickness 0.15)
				)
			)
		)
		(property "Author" "Antmicro"
			(at 196.2 316.2 0)
			(layer "B.Fab")
			(hide yes)
			(effects
				(font
					(size 1 1)
					(thickness 0.15)
				)
				(justify mirror)
			)
		)
		(property "License" "Apache-2.0"
			(at 196.2 316.2 0)
			(layer "B.Fab")
			(hide yes)
			(effects
				(font
					(size 1 1)
					(thickness 0.15)
				)
				(justify mirror)
			)
		)
		(property "MPN" "CR0402-FX-1001GLF"
			(at 196.2 316.2 0)
			(layer "B.Fab")
			(hide yes)
			(effects
				(font
					(size 1 1)
					(thickness 0.15)
				)
				(justify mirror)
			)
		)
		(property "Manufacturer" "Bourns"
			(at 196.2 316.2 0)
			(layer "B.Fab")
			(hide yes)
			(effects
				(font
					(size 1 1)
					(thickness 0.15)
				)
				(justify mirror)
			)
		)
		(property "Tolerance" "1%"
			(at 196.2 316.2 0)
			(layer "B.Fab")
			(hide yes)
			(effects
				(font
					(size 1 1)
					(thickness 0.15)
				)
				(justify mirror)
			)
		)
		(property "Val" "1k"
			(at 196.2 316.2 0)
			(layer "B.Fab")
			(hide yes)
			(effects
				(font
					(size 1 1)
					(thickness 0.15)
				)
				(justify mirror)
			)
		)
		(sheetname "/Ethernet/")
		(sheetfile "ethernet.kicad_sch")
		(attr smd)
		(fp_rect
			(start -0.93 0.47)
			(end 0.93 -0.47)
			(stroke
				(width 0.05)
				(type solid)
			)
			(fill no)
			(layer "B.CrtYd")
		)
		(fp_rect
			(start -0.5 0.25)
			(end 0.5 -0.25)
			(stroke
				(width 0.15)
				(type solid)
			)
			(fill no)
			(layer "B.Fab")
		)
		(pad "1" smd roundrect
			(at -0.485 0 180)
			(size 0.59 0.64)
			(layers "B.Cu" "B.Mask" "B.Paste")
			(roundrect_rratio 0.25)
			(net 680 "/Ethernet/ETH.MDIO")
			(pintype "passive")
		)
		(pad "2" smd roundrect
			(at 0.485 0 180)
			(size 0.59 0.64)
			(layers "B.Cu" "B.Mask" "B.Paste")
			(roundrect_rratio 0.25)
			(net 200 "+3V3")
			(pintype "passive")
		)
	)
	(footprint "antmicro-footprints:R_0402_1005Metric"
		(layer "B.Cu")
		(at 97.425501 163.951 -90)
		(descr "Resistor SMD 0402")
		(tags "resistor SMD 0402")
		(property "Reference" "R115"
			(at -1.122484 0.772697 90)
			(layer "B.SilkS")
			(hide yes)
			(effects
				(font
					(size 0.7 0.7)
					(thickness 0.15)
				)
				(justify left bottom mirror)
			)
		)
		(property "Value" "R_2k2_0402"
			(at -1.011843 -1.772047 90)
			(layer "B.Fab")
			(effects
				(font
					(size 0.7 0.7)
					(thickness 0.15)
				)
				(justify left bottom mirror)
			)
		)
		(property "Datasheet" "https://www.bourns.com/docs/product-datasheets/cr.pdf"
			(at 0 0 270)
			(layer "F.Fab")
			(hide yes)
			(effects
				(font
					(size 1.27 1.27)
					(thickness 0.15)
				)
			)
		)
		(property "Author" "Antmicro"
			(at -66.525499 261.376501 0)
			(layer "B.Fab")
			(hide yes)
			(effects
				(font
					(size 1 1)
					(thickness 0.15)
				)
				(justify mirror)
			)
		)
		(property "License" "Apache-2.0"
			(at -66.525499 261.376501 0)
			(layer "B.Fab")
			(hide yes)
			(effects
				(font
					(size 1 1)
					(thickness 0.15)
				)
				(justify mirror)
			)
		)
		(property "MPN" "CR0402-FX-2201GLF"
			(at -66.525499 261.376501 0)
			(layer "B.Fab")
			(hide yes)
			(effects
				(font
					(size 1 1)
					(thickness 0.15)
				)
				(justify mirror)
			)
		)
		(property "Manufacturer" "Bourns"
			(at -66.525499 261.376501 0)
			(layer "B.Fab")
			(hide yes)
			(effects
				(font
					(size 1 1)
					(thickness 0.15)
				)
				(justify mirror)
			)
		)
		(property "Tolerance" "1%"
			(at -66.525499 261.376501 0)
			(layer "B.Fab")
			(hide yes)
			(effects
				(font
					(size 1 1)
					(thickness 0.15)
				)
				(justify mirror)
			)
		)
		(property "Val" "2k2"
			(at -66.525499 261.376501 0)
			(layer "B.Fab")
			(hide yes)
			(effects
				(font
					(size 1 1)
					(thickness 0.15)
				)
				(justify mirror)
			)
		)
		(sheetname "/Ethernet/")
		(sheetfile "ethernet.kicad_sch")
		(attr exclude_from_pos_files exclude_from_bom dnp)
		(fp_rect
			(start -0.93 0.47)
			(end 0.93 -0.47)
			(stroke
				(width 0.05)
				(type solid)
			)
			(fill no)
			(layer "B.CrtYd")
		)
		(fp_rect
			(start -0.5 0.25)
			(end 0.5 -0.25)
			(stroke
				(width 0.15)
				(type solid)
			)
			(fill no)
			(layer "B.Fab")
		)
		(pad "1" smd roundrect
			(at -0.485 0 270)
			(size 0.59 0.64)
			(layers "B.Cu" "B.Mask" "B.Paste")
			(roundrect_rratio 0.25)
			(net 675 "/Ethernet/ETH.RXD2")
			(pintype "passive")
		)
		(pad "2" smd roundrect
			(at 0.485 0 270)
			(size 0.59 0.64)
			(layers "B.Cu" "B.Mask" "B.Paste")
			(roundrect_rratio 0.25)
			(net 1 "GND")
			(pintype "passive")
		)
	)
	(footprint "antmicro-footprints:R_0402_1005Metric"
		(layer "B.Cu")
		(at 101.625501 163.951 -90)
		(descr "Resistor SMD 0402")
		(tags "resistor SMD 0402")
		(property "Reference" "R117"
			(at -1.122484 0.772697 90)
			(layer "B.SilkS")
			(hide yes)
			(effects
				(font
					(size 0.7 0.7)
					(thickness 0.15)
				)
				(justify left bottom mirror)
			)
		)
		(property "Value" "R_2k2_0402"
			(at -1.011843 -1.772047 90)
			(layer "B.Fab")
			(effects
				(font
					(size 0.7 0.7)
					(thickness 0.15)
				)
				(justify left bottom mirror)
			)
		)
		(property "Datasheet" "https://www.bourns.com/docs/product-datasheets/cr.pdf"
			(at 0 0 270)
			(layer "F.Fab")
			(hide yes)
			(effects
				(font
					(size 1.27 1.27)
					(thickness 0.15)
				)
			)
		)
		(property "Author" "Antmicro"
			(at -62.325499 265.576501 0)
			(layer "B.Fab")
			(hide yes)
			(effects
				(font
					(size 1 1)
					(thickness 0.15)
				)
				(justify mirror)
			)
		)
		(property "License" "Apache-2.0"
			(at -62.325499 265.576501 0)
			(layer "B.Fab")
			(hide yes)
			(effects
				(font
					(size 1 1)
					(thickness 0.15)
				)
				(justify mirror)
			)
		)
		(property "MPN" "CR0402-FX-2201GLF"
			(at -62.325499 265.576501 0)
			(layer "B.Fab")
			(hide yes)
			(effects
				(font
					(size 1 1)
					(thickness 0.15)
				)
				(justify mirror)
			)
		)
		(property "Manufacturer" "Bourns"
			(at -62.325499 265.576501 0)
			(layer "B.Fab")
			(hide yes)
			(effects
				(font
					(size 1 1)
					(thickness 0.15)
				)
				(justify mirror)
			)
		)
		(property "Tolerance" "1%"
			(at -62.325499 265.576501 0)
			(layer "B.Fab")
			(hide yes)
			(effects
				(font
					(size 1 1)
					(thickness 0.15)
				)
				(justify mirror)
			)
		)
		(property "Val" "2k2"
			(at -62.325499 265.576501 0)
			(layer "B.Fab")
			(hide yes)
			(effects
				(font
					(size 1 1)
					(thickness 0.15)
				)
				(justify mirror)
			)
		)
		(sheetname "/Ethernet/")
		(sheetfile "ethernet.kicad_sch")
		(attr smd)
		(fp_rect
			(start -0.93 0.47)
			(end 0.93 -0.47)
			(stroke
				(width 0.05)
				(type solid)
			)
			(fill no)
			(layer "B.CrtYd")
		)
		(fp_rect
			(start -0.5 0.25)
			(end 0.5 -0.25)
			(stroke
				(width 0.15)
				(type solid)
			)
			(fill no)
			(layer "B.Fab")
		)
		(pad "1" smd roundrect
			(at -0.485 0 270)
			(size 0.59 0.64)
			(layers "B.Cu" "B.Mask" "B.Paste")
			(roundrect_rratio 0.25)
			(net 677 "/Ethernet/ETH.RX_CTL")
			(pintype "passive")
		)
		(pad "2" smd roundrect
			(at 0.485 0 270)
			(size 0.59 0.64)
			(layers "B.Cu" "B.Mask" "B.Paste")
			(roundrect_rratio 0.25)
			(net 1 "GND")
			(pintype "passive")
		)
	)
	(footprint "antmicro-footprints:R_0402_1005Metric"
		(layer "B.Cu")
		(at 100.550501 163.951 -90)
		(descr "Resistor SMD 0402")
		(tags "resistor SMD 0402")
		(property "Reference" "R118"
			(at -1.122484 0.772697 90)
			(layer "B.SilkS")
			(hide yes)
			(effects
				(font
					(size 0.7 0.7)
					(thickness 0.15)
				)
				(justify left bottom mirror)
			)
		)
		(property "Value" "R_2k2_0402"
			(at -1.011843 -1.772047 90)
			(layer "B.Fab")
			(effects
				(font
					(size 0.7 0.7)
					(thickness 0.15)
				)
				(justify left bottom mirror)
			)
		)
		(property "Datasheet" "https://www.bourns.com/docs/product-datasheets/cr.pdf"
			(at 0 0 270)
			(layer "F.Fab")
			(hide yes)
			(effects
				(font
					(size 1.27 1.27)
					(thickness 0.15)
				)
			)
		)
		(property "Author" "Antmicro"
			(at -63.400499 264.501501 0)
			(layer "B.Fab")
			(hide yes)
			(effects
				(font
					(size 1 1)
					(thickness 0.15)
				)
				(justify mirror)
			)
		)
		(property "License" "Apache-2.0"
			(at -63.400499 264.501501 0)
			(layer "B.Fab")
			(hide yes)
			(effects
				(font
					(size 1 1)
					(thickness 0.15)
				)
				(justify mirror)
			)
		)
		(property "MPN" "CR0402-FX-2201GLF"
			(at -63.400499 264.501501 0)
			(layer "B.Fab")
			(hide yes)
			(effects
				(font
					(size 1 1)
					(thickness 0.15)
				)
				(justify mirror)
			)
		)
		(property "Manufacturer" "Bourns"
			(at -63.400499 264.501501 0)
			(layer "B.Fab")
			(hide yes)
			(effects
				(font
					(size 1 1)
					(thickness 0.15)
				)
				(justify mirror)
			)
		)
		(property "Tolerance" "1%"
			(at -63.400499 264.501501 0)
			(layer "B.Fab")
			(hide yes)
			(effects
				(font
					(size 1 1)
					(thickness 0.15)
				)
				(justify mirror)
			)
		)
		(property "Val" "2k2"
			(at -63.400499 264.501501 0)
			(layer "B.Fab")
			(hide yes)
			(effects
				(font
					(size 1 1)
					(thickness 0.15)
				)
				(justify mirror)
			)
		)
		(sheetname "/Ethernet/")
		(sheetfile "ethernet.kicad_sch")
		(attr smd)
		(fp_rect
			(start -0.93 0.47)
			(end 0.93 -0.47)
			(stroke
				(width 0.05)
				(type solid)
			)
			(fill no)
			(layer "B.CrtYd")
		)
		(fp_rect
			(start -0.5 0.25)
			(end 0.5 -0.25)
			(stroke
				(width 0.15)
				(type solid)
			)
			(fill no)
			(layer "B.Fab")
		)
		(pad "1" smd roundrect
			(at -0.485 0 270)
			(size 0.59 0.64)
			(layers "B.Cu" "B.Mask" "B.Paste")
			(roundrect_rratio 0.25)
			(net 678 "/Ethernet/ETH.RXC")
			(pintype "passive")
		)
		(pad "2" smd roundrect
			(at 0.485 0 270)
			(size 0.59 0.64)
			(layers "B.Cu" "B.Mask" "B.Paste")
			(roundrect_rratio 0.25)
			(net 1 "GND")
			(pintype "passive")
		)
	)
	(footprint "antmicro-footprints:R_0402_1005Metric"
		(layer "B.Cu")
		(at 94.258672 154.95 90)
		(descr "Resistor SMD 0402")
		(tags "resistor SMD 0402")
		(property "Reference" "R119"
			(at -1.122484 0.772697 270)
			(layer "B.SilkS")
			(hide yes)
			(effects
				(font
					(size 0.7 0.7)
					(thickness 0.15)
				)
				(justify left bottom mirror)
			)
		)
		(property "Value" "R_2k2_0402"
			(at -1.011843 -1.772047 270)
			(layer "B.Fab")
			(effects
				(font
					(size 0.7 0.7)
					(thickness 0.15)
				)
				(justify left bottom mirror)
			)
		)
		(property "Datasheet" "https://www.bourns.com/docs/product-datasheets/cr.pdf"
			(at 0 0 90)
			(layer "F.Fab")
			(hide yes)
			(effects
				(font
					(size 1.27 1.27)
					(thickness 0.15)
				)
			)
		)
		(property "Author" "Antmicro"
			(at 249.208672 60.691328 0)
			(layer "B.Fab")
			(hide yes)
			(effects
				(font
					(size 1 1)
					(thickness 0.15)
				)
				(justify mirror)
			)
		)
		(property "License" "Apache-2.0"
			(at 249.208672 60.691328 0)
			(layer "B.Fab")
			(hide yes)
			(effects
				(font
					(size 1 1)
					(thickness 0.15)
				)
				(justify mirror)
			)
		)
		(property "MPN" "CR0402-FX-2201GLF"
			(at 249.208672 60.691328 0)
			(layer "B.Fab")
			(hide yes)
			(effects
				(font
					(size 1 1)
					(thickness 0.15)
				)
				(justify mirror)
			)
		)
		(property "Manufacturer" "Bourns"
			(at 249.208672 60.691328 0)
			(layer "B.Fab")
			(hide yes)
			(effects
				(font
					(size 1 1)
					(thickness 0.15)
				)
				(justify mirror)
			)
		)
		(property "Tolerance" "1%"
			(at 249.208672 60.691328 0)
			(layer "B.Fab")
			(hide yes)
			(effects
				(font
					(size 1 1)
					(thickness 0.15)
				)
				(justify mirror)
			)
		)
		(property "Val" "2k2"
			(at 249.208672 60.691328 0)
			(layer "B.Fab")
			(hide yes)
			(effects
				(font
					(size 1 1)
					(thickness 0.15)
				)
				(justify mirror)
			)
		)
		(sheetname "/Ethernet/")
		(sheetfile "ethernet.kicad_sch")
		(attr exclude_from_pos_files exclude_from_bom dnp)
		(fp_rect
			(start -0.93 0.47)
			(end 0.93 -0.47)
			(stroke
				(width 0.05)
				(type solid)
			)
			(fill no)
			(layer "B.CrtYd")
		)
		(fp_rect
			(start -0.5 0.25)
			(end 0.5 -0.25)
			(stroke
				(width 0.15)
				(type solid)
			)
			(fill no)
			(layer "B.Fab")
		)
		(pad "1" smd roundrect
			(at -0.485 0 90)
			(size 0.59 0.64)
			(layers "B.Cu" "B.Mask" "B.Paste")
			(roundrect_rratio 0.25)
			(net 679 "/Ethernet/ETH.REF_CLK")
			(pintype "passive")
		)
		(pad "2" smd roundrect
			(at 0.485 0 90)
			(size 0.59 0.64)
			(layers "B.Cu" "B.Mask" "B.Paste")
			(roundrect_rratio 0.25)
			(net 1 "GND")
			(pintype "passive")
		)
	)
	(footprint "antmicro-footprints:R_0402_1005Metric"
		(layer "B.Cu")
		(at 85.680501 151.353149 90)
		(descr "Resistor SMD 0402")
		(tags "resistor SMD 0402")
		(property "Reference" "R120"
			(at -1.122484 0.772697 270)
			(layer "B.SilkS")
			(hide yes)
			(effects
				(font
					(size 0.7 0.7)
					(thickness 0.15)
				)
				(justify left bottom mirror)
			)
		)
		(property "Value" "R_2k2_0402"
			(at -1.011843 -1.772047 270)
			(layer "B.Fab")
			(effects
				(font
					(size 0.7 0.7)
					(thickness 0.15)
				)
				(justify left bottom mirror)
			)
		)
		(property "Datasheet" "https://www.bourns.com/docs/product-datasheets/cr.pdf"
			(at 0 0 90)
			(layer "F.Fab")
			(hide yes)
			(effects
				(font
					(size 1.27 1.27)
					(thickness 0.15)
				)
			)
		)
		(property "Author" "Antmicro"
			(at 237.03365 65.672648 0)
			(layer "B.Fab")
			(hide yes)
			(effects
				(font
					(size 1 1)
					(thickness 0.15)
				)
				(justify mirror)
			)
		)
		(property "License" "Apache-2.0"
			(at 237.03365 65.672648 0)
			(layer "B.Fab")
			(hide yes)
			(effects
				(font
					(size 1 1)
					(thickness 0.15)
				)
				(justify mirror)
			)
		)
		(property "MPN" "CR0402-FX-2201GLF"
			(at 237.03365 65.672648 0)
			(layer "B.Fab")
			(hide yes)
			(effects
				(font
					(size 1 1)
					(thickness 0.15)
				)
				(justify mirror)
			)
		)
		(property "Manufacturer" "Bourns"
			(at 237.03365 65.672648 0)
			(layer "B.Fab")
			(hide yes)
			(effects
				(font
					(size 1 1)
					(thickness 0.15)
				)
				(justify mirror)
			)
		)
		(property "Tolerance" "1%"
			(at 237.03365 65.672648 0)
			(layer "B.Fab")
			(hide yes)
			(effects
				(font
					(size 1 1)
					(thickness 0.15)
				)
				(justify mirror)
			)
		)
		(property "Val" "2k2"
			(at 237.03365 65.672648 0)
			(layer "B.Fab")
			(hide yes)
			(effects
				(font
					(size 1 1)
					(thickness 0.15)
				)
				(justify mirror)
			)
		)
		(sheetname "/Ethernet/")
		(sheetfile "ethernet.kicad_sch")
		(attr exclude_from_pos_files exclude_from_bom dnp)
		(fp_rect
			(start -0.93 0.47)
			(end 0.93 -0.47)
			(stroke
				(width 0.05)
				(type solid)
			)
			(fill no)
			(layer "B.CrtYd")
		)
		(fp_rect
			(start -0.5 0.25)
			(end 0.5 -0.25)
			(stroke
				(width 0.15)
				(type solid)
			)
			(fill no)
			(layer "B.Fab")
		)
		(pad "1" smd roundrect
			(at -0.485 0 90)
			(size 0.59 0.64)
			(layers "B.Cu" "B.Mask" "B.Paste")
			(roundrect_rratio 0.25)
			(net 602 "/Ethernet/LED_SPD")
			(pintype "passive")
		)
		(pad "2" smd roundrect
			(at 0.485 0 90)
			(size 0.59 0.64)
			(layers "B.Cu" "B.Mask" "B.Paste")
			(roundrect_rratio 0.25)
			(net 1 "GND")
			(pintype "passive")
		)
	)
	(footprint "antmicro-footprints:R_0402_1005Metric"
		(layer "B.Cu")
		(at 85.680501 155.763149 -90)
		(descr "Resistor SMD 0402")
		(tags "resistor SMD 0402")
		(property "Reference" "R121"
			(at -1.122484 0.772697 90)
			(layer "B.SilkS")
			(hide yes)
			(effects
				(font
					(size 0.7 0.7)
					(thickness 0.15)
				)
				(justify left bottom mirror)
			)
		)
		(property "Value" "R_2k2_0402"
			(at -1.011843 -1.772047 90)
			(layer "B.Fab")
			(effects
				(font
					(size 0.7 0.7)
					(thickness 0.15)
				)
				(justify left bottom mirror)
			)
		)
		(property "Datasheet" "https://www.bourns.com/docs/product-datasheets/cr.pdf"
			(at 0 0 270)
			(layer "F.Fab")
			(hide yes)
			(effects
				(font
					(size 1.27 1.27)
					(thickness 0.15)
				)
			)
		)
		(property "Author" "Antmicro"
			(at -70.082648 241.44365 0)
			(layer "B.Fab")
			(hide yes)
			(effects
				(font
					(size 1 1)
					(thickness 0.15)
				)
				(justify mirror)
			)
		)
		(property "License" "Apache-2.0"
			(at -70.082648 241.44365 0)
			(layer "B.Fab")
			(hide yes)
			(effects
				(font
					(size 1 1)
					(thickness 0.15)
				)
				(justify mirror)
			)
		)
		(property "MPN" "CR0402-FX-2201GLF"
			(at -70.082648 241.44365 0)
			(layer "B.Fab")
			(hide yes)
			(effects
				(font
					(size 1 1)
					(thickness 0.15)
				)
				(justify mirror)
			)
		)
		(property "Manufacturer" "Bourns"
			(at -70.082648 241.44365 0)
			(layer "B.Fab")
			(hide yes)
			(effects
				(font
					(size 1 1)
					(thickness 0.15)
				)
				(justify mirror)
			)
		)
		(property "Tolerance" "1%"
			(at -70.082648 241.44365 0)
			(layer "B.Fab")
			(hide yes)
			(effects
				(font
					(size 1 1)
					(thickness 0.15)
				)
				(justify mirror)
			)
		)
		(property "Val" "2k2"
			(at -70.082648 241.44365 0)
			(layer "B.Fab")
			(hide yes)
			(effects
				(font
					(size 1 1)
					(thickness 0.15)
				)
				(justify mirror)
			)
		)
		(sheetname "/Ethernet/")
		(sheetfile "ethernet.kicad_sch")
		(attr exclude_from_pos_files exclude_from_bom dnp)
		(fp_rect
			(start -0.93 0.47)
			(end 0.93 -0.47)
			(stroke
				(width 0.05)
				(type solid)
			)
			(fill no)
			(layer "B.CrtYd")
		)
		(fp_rect
			(start -0.5 0.25)
			(end 0.5 -0.25)
			(stroke
				(width 0.15)
				(type solid)
			)
			(fill no)
			(layer "B.Fab")
		)
		(pad "1" smd roundrect
			(at -0.485 0 270)
			(size 0.59 0.64)
			(layers "B.Cu" "B.Mask" "B.Paste")
			(roundrect_rratio 0.25)
			(net 603 "/Ethernet/LED_LINK")
			(pintype "passive")
		)
		(pad "2" smd roundrect
			(at 0.485 0 270)
			(size 0.59 0.64)
			(layers "B.Cu" "B.Mask" "B.Paste")
			(roundrect_rratio 0.25)
			(net 1 "GND")
			(pintype "passive")
		)
	)
	(footprint "antmicro-footprints:R_0402_1005Metric"
		(layer "B.Cu")
		(at 96.375501 161.576 90)
		(descr "Resistor SMD 0402")
		(tags "resistor SMD 0402")
		(property "Reference" "R104"
			(at -1.122484 0.772697 270)
			(layer "B.SilkS")
			(hide yes)
			(effects
				(font
					(size 0.7 0.7)
					(thickness 0.15)
				)
				(justify left bottom mirror)
			)
		)
		(property "Value" "R_10k_0402"
			(at -1.011843 -1.772047 270)
			(layer "B.Fab")
			(effects
				(font
					(size 0.7 0.7)
					(thickness 0.15)
				)
				(justify left bottom mirror)
			)
		)
		(property "Datasheet" "https://www.bourns.com/docs/product-datasheets/cr.pdf"
			(at 0 0 90)
			(layer "F.Fab")
			(hide yes)
			(effects
				(font
					(size 1.27 1.27)
					(thickness 0.15)
				)
			)
		)
		(property "Author" "Antmicro"
			(at 257.951501 65.200499 0)
			(layer "B.Fab")
			(hide yes)
			(effects
				(font
					(size 1 1)
					(thickness 0.15)
				)
				(justify mirror)
			)
		)
		(property "License" "Apache-2.0"
			(at 257.951501 65.200499 0)
			(layer "B.Fab")
			(hide yes)
			(effects
				(font
					(size 1 1)
					(thickness 0.15)
				)
				(justify mirror)
			)
		)
		(property "MPN" "CR0402-FX-1002GLF"
			(at 257.951501 65.200499 0)
			(layer "B.Fab")
			(hide yes)
			(effects
				(font
					(size 1 1)
					(thickness 0.15)
				)
				(justify mirror)
			)
		)
		(property "Manufacturer" "Bourns"
			(at 257.951501 65.200499 0)
			(layer "B.Fab")
			(hide yes)
			(effects
				(font
					(size 1 1)
					(thickness 0.15)
				)
				(justify mirror)
			)
		)
		(property "Tolerance" "1%"
			(at 257.951501 65.200499 0)
			(layer "B.Fab")
			(hide yes)
			(effects
				(font
					(size 1 1)
					(thickness 0.15)
				)
				(justify mirror)
			)
		)
		(property "Val" "10k"
			(at 257.951501 65.200499 0)
			(layer "B.Fab")
			(hide yes)
			(effects
				(font
					(size 1 1)
					(thickness 0.15)
				)
				(justify mirror)
			)
		)
		(sheetname "/Ethernet/")
		(sheetfile "ethernet.kicad_sch")
		(attr smd)
		(fp_rect
			(start -0.93 0.47)
			(end 0.93 -0.47)
			(stroke
				(width 0.05)
				(type solid)
			)
			(fill no)
			(layer "B.CrtYd")
		)
		(fp_rect
			(start -0.5 0.25)
			(end 0.5 -0.25)
			(stroke
				(width 0.15)
				(type solid)
			)
			(fill no)
			(layer "B.Fab")
		)
		(pad "1" smd roundrect
			(at -0.485 0 90)
			(size 0.59 0.64)
			(layers "B.Cu" "B.Mask" "B.Paste")
			(roundrect_rratio 0.25)
			(net 676 "/Ethernet/ETH.RXD3")
			(pintype "passive")
		)
		(pad "2" smd roundrect
			(at 0.485 0 90)
			(size 0.59 0.64)
			(layers "B.Cu" "B.Mask" "B.Paste")
			(roundrect_rratio 0.25)
			(net 200 "+3V3")
			(pintype "passive")
		)
	)
	(footprint "antmicro-footprints:R_0402_1005Metric"
		(layer "B.Cu")
		(at 96.375501 163.951 -90)
		(descr "Resistor SMD 0402")
		(tags "resistor SMD 0402")
		(property "Reference" "R116"
			(at -1.122484 0.772697 90)
			(layer "B.SilkS")
			(hide yes)
			(effects
				(font
					(size 0.7 0.7)
					(thickness 0.15)
				)
				(justify left bottom mirror)
			)
		)
		(property "Value" "R_2k2_0402"
			(at -1.011843 -1.772047 90)
			(layer "B.Fab")
			(effects
				(font
					(size 0.7 0.7)
					(thickness 0.15)
				)
				(justify left bottom mirror)
			)
		)
		(property "Datasheet" "https://www.bourns.com/docs/product-datasheets/cr.pdf"
			(at 0 0 270)
			(layer "F.Fab")
			(hide yes)
			(effects
				(font
					(size 1.27 1.27)
					(thickness 0.15)
				)
			)
		)
		(property "Author" "Antmicro"
			(at -67.575499 260.326501 0)
			(layer "B.Fab")
			(hide yes)
			(effects
				(font
					(size 1 1)
					(thickness 0.15)
				)
				(justify mirror)
			)
		)
		(property "License" "Apache-2.0"
			(at -67.575499 260.326501 0)
			(layer "B.Fab")
			(hide yes)
			(effects
				(font
					(size 1 1)
					(thickness 0.15)
				)
				(justify mirror)
			)
		)
		(property "MPN" "CR0402-FX-2201GLF"
			(at -67.575499 260.326501 0)
			(layer "B.Fab")
			(hide yes)
			(effects
				(font
					(size 1 1)
					(thickness 0.15)
				)
				(justify mirror)
			)
		)
		(property "Manufacturer" "Bourns"
			(at -67.575499 260.326501 0)
			(layer "B.Fab")
			(hide yes)
			(effects
				(font
					(size 1 1)
					(thickness 0.15)
				)
				(justify mirror)
			)
		)
		(property "Tolerance" "1%"
			(at -67.575499 260.326501 0)
			(layer "B.Fab")
			(hide yes)
			(effects
				(font
					(size 1 1)
					(thickness 0.15)
				)
				(justify mirror)
			)
		)
		(property "Val" "2k2"
			(at -67.575499 260.326501 0)
			(layer "B.Fab")
			(hide yes)
			(effects
				(font
					(size 1 1)
					(thickness 0.15)
				)
				(justify mirror)
			)
		)
		(sheetname "/Ethernet/")
		(sheetfile "ethernet.kicad_sch")
		(attr exclude_from_pos_files exclude_from_bom dnp)
		(fp_rect
			(start -0.93 0.47)
			(end 0.93 -0.47)
			(stroke
				(width 0.05)
				(type solid)
			)
			(fill no)
			(layer "B.CrtYd")
		)
		(fp_rect
			(start -0.5 0.25)
			(end 0.5 -0.25)
			(stroke
				(width 0.15)
				(type solid)
			)
			(fill no)
			(layer "B.Fab")
		)
		(pad "1" smd roundrect
			(at -0.485 0 270)
			(size 0.59 0.64)
			(layers "B.Cu" "B.Mask" "B.Paste")
			(roundrect_rratio 0.25)
			(net 676 "/Ethernet/ETH.RXD3")
			(pintype "passive")
		)
		(pad "2" smd roundrect
			(at 0.485 0 270)
			(size 0.59 0.64)
			(layers "B.Cu" "B.Mask" "B.Paste")
			(roundrect_rratio 0.25)
			(net 1 "GND")
			(pintype "passive")
		)
	)
	(footprint "antmicro-footprints:TP_SMD_1mm"
		(layer "B.Cu")
		(at 96.8 178.05 -90)
		(property "Reference" "TP1"
			(at -0.95 0.8 90)
			(layer "B.SilkS")
			(effects
				(font
					(size 0.7 0.7)
					(thickness 0.15)
				)
				(justify left bottom mirror)
			)
		)
		(property "Value" "TP_1mm_SMD"
			(at 0 -1.4 90)
			(layer "B.Fab")
			(effects
				(font
					(size 0.7 0.7)
					(thickness 0.15)
				)
				(justify left bottom mirror)
			)
		)
		(property "Author" "Antmicro"
			(at -81.25 274.85 0)
			(layer "B.Fab")
			(hide yes)
			(effects
				(font
					(size 1 1)
					(thickness 0.15)
				)
				(justify mirror)
			)
		)
		(property "License" "Apache-2.0"
			(at -81.25 274.85 0)
			(layer "B.Fab")
			(hide yes)
			(effects
				(font
					(size 1 1)
					(thickness 0.15)
				)
				(justify mirror)
			)
		)
		(property "MPN" ""
			(at -81.25 274.85 0)
			(layer "B.Fab")
			(hide yes)
			(effects
				(font
					(size 1 1)
					(thickness 0.15)
				)
				(justify mirror)
			)
		)
		(property "Manufacturer" ""
			(at -81.25 274.85 0)
			(layer "B.Fab")
			(hide yes)
			(effects
				(font
					(size 1 1)
					(thickness 0.15)
				)
				(justify mirror)
			)
		)
		(sheetname "/Debug FTDI/")
		(sheetfile "debug-ftdi.kicad_sch")
		(attr exclude_from_pos_files)
		(pad "1" smd circle
			(at 0 0 270)
			(size 1 1)
			(layers "B.Cu" "B.Mask")
			(net 692 "/Debug FTDI/FTDI_JTAG_RST")
			(pinfunction "1")
			(pintype "passive")
		)
	)
	(footprint "antmicro-footprints:R_0402_1005Metric"
		(layer "B.Cu")
		(at 98.475501 163.951 -90)
		(descr "Resistor SMD 0402")
		(tags "resistor SMD 0402")
		(property "Reference" "R114"
			(at -1.122484 0.772697 90)
			(layer "B.SilkS")
			(hide yes)
			(effects
				(font
					(size 0.7 0.7)
					(thickness 0.15)
				)
				(justify left bottom mirror)
			)
		)
		(property "Value" "R_2k2_0402"
			(at -1.011843 -1.772047 90)
			(layer "B.Fab")
			(effects
				(font
					(size 0.7 0.7)
					(thickness 0.15)
				)
				(justify left bottom mirror)
			)
		)
		(property "Datasheet" "https://www.bourns.com/docs/product-datasheets/cr.pdf"
			(at 0 0 270)
			(layer "F.Fab")
			(hide yes)
			(effects
				(font
					(size 1.27 1.27)
					(thickness 0.15)
				)
			)
		)
		(property "Author" "Antmicro"
			(at -65.475499 262.426501 0)
			(layer "B.Fab")
			(hide yes)
			(effects
				(font
					(size 1 1)
					(thickness 0.15)
				)
				(justify mirror)
			)
		)
		(property "License" "Apache-2.0"
			(at -65.475499 262.426501 0)
			(layer "B.Fab")
			(hide yes)
			(effects
				(font
					(size 1 1)
					(thickness 0.15)
				)
				(justify mirror)
			)
		)
		(property "MPN" "CR0402-FX-2201GLF"
			(at -65.475499 262.426501 0)
			(layer "B.Fab")
			(hide yes)
			(effects
				(font
					(size 1 1)
					(thickness 0.15)
				)
				(justify mirror)
			)
		)
		(property "Manufacturer" "Bourns"
			(at -65.475499 262.426501 0)
			(layer "B.Fab")
			(hide yes)
			(effects
				(font
					(size 1 1)
					(thickness 0.15)
				)
				(justify mirror)
			)
		)
		(property "Tolerance" "1%"
			(at -65.475499 262.426501 0)
			(layer "B.Fab")
			(hide yes)
			(effects
				(font
					(size 1 1)
					(thickness 0.15)
				)
				(justify mirror)
			)
		)
		(property "Val" "2k2"
			(at -65.475499 262.426501 0)
			(layer "B.Fab")
			(hide yes)
			(effects
				(font
					(size 1 1)
					(thickness 0.15)
				)
				(justify mirror)
			)
		)
		(sheetname "/Ethernet/")
		(sheetfile "ethernet.kicad_sch")
		(attr smd)
		(fp_rect
			(start -0.93 0.47)
			(end 0.93 -0.47)
			(stroke
				(width 0.05)
				(type solid)
			)
			(fill no)
			(layer "B.CrtYd")
		)
		(fp_rect
			(start -0.5 0.25)
			(end 0.5 -0.25)
			(stroke
				(width 0.15)
				(type solid)
			)
			(fill no)
			(layer "B.Fab")
		)
		(pad "1" smd roundrect
			(at -0.485 0 270)
			(size 0.59 0.64)
			(layers "B.Cu" "B.Mask" "B.Paste")
			(roundrect_rratio 0.25)
			(net 674 "/Ethernet/ETH.RXD1")
			(pintype "passive")
		)
		(pad "2" smd roundrect
			(at 0.485 0 270)
			(size 0.59 0.64)
			(layers "B.Cu" "B.Mask" "B.Paste")
			(roundrect_rratio 0.25)
			(net 1 "GND")
			(pintype "passive")
		)
	)
	(footprint "antmicro-footprints:R_0402_1005Metric"
		(layer "B.Cu")
		(at 97.425501 161.576 90)
		(descr "Resistor SMD 0402")
		(tags "resistor SMD 0402")
		(property "Reference" "R103"
			(at -1.122484 0.772697 270)
			(layer "B.SilkS")
			(hide yes)
			(effects
				(font
					(size 0.7 0.7)
					(thickness 0.15)
				)
				(justify left bottom mirror)
			)
		)
		(property "Value" "R_10k_0402"
			(at -1.011843 -1.772047 270)
			(layer "B.Fab")
			(effects
				(font
					(size 0.7 0.7)
					(thickness 0.15)
				)
				(justify left bottom mirror)
			)
		)
		(property "Datasheet" "https://www.bourns.com/docs/product-datasheets/cr.pdf"
			(at 0 0 90)
			(layer "F.Fab")
			(hide yes)
			(effects
				(font
					(size 1.27 1.27)
					(thickness 0.15)
				)
			)
		)
		(property "Author" "Antmicro"
			(at 259.001501 64.150499 0)
			(layer "B.Fab")
			(hide yes)
			(effects
				(font
					(size 1 1)
					(thickness 0.15)
				)
				(justify mirror)
			)
		)
		(property "License" "Apache-2.0"
			(at 259.001501 64.150499 0)
			(layer "B.Fab")
			(hide yes)
			(effects
				(font
					(size 1 1)
					(thickness 0.15)
				)
				(justify mirror)
			)
		)
		(property "MPN" "CR0402-FX-1002GLF"
			(at 259.001501 64.150499 0)
			(layer "B.Fab")
			(hide yes)
			(effects
				(font
					(size 1 1)
					(thickness 0.15)
				)
				(justify mirror)
			)
		)
		(property "Manufacturer" "Bourns"
			(at 259.001501 64.150499 0)
			(layer "B.Fab")
			(hide yes)
			(effects
				(font
					(size 1 1)
					(thickness 0.15)
				)
				(justify mirror)
			)
		)
		(property "Tolerance" "1%"
			(at 259.001501 64.150499 0)
			(layer "B.Fab")
			(hide yes)
			(effects
				(font
					(size 1 1)
					(thickness 0.15)
				)
				(justify mirror)
			)
		)
		(property "Val" "10k"
			(at 259.001501 64.150499 0)
			(layer "B.Fab")
			(hide yes)
			(effects
				(font
					(size 1 1)
					(thickness 0.15)
				)
				(justify mirror)
			)
		)
		(sheetname "/Ethernet/")
		(sheetfile "ethernet.kicad_sch")
		(attr smd)
		(fp_rect
			(start -0.93 0.47)
			(end 0.93 -0.47)
			(stroke
				(width 0.05)
				(type solid)
			)
			(fill no)
			(layer "B.CrtYd")
		)
		(fp_rect
			(start -0.5 0.25)
			(end 0.5 -0.25)
			(stroke
				(width 0.15)
				(type solid)
			)
			(fill no)
			(layer "B.Fab")
		)
		(pad "1" smd roundrect
			(at -0.485 0 90)
			(size 0.59 0.64)
			(layers "B.Cu" "B.Mask" "B.Paste")
			(roundrect_rratio 0.25)
			(net 675 "/Ethernet/ETH.RXD2")
			(pintype "passive")
		)
		(pad "2" smd roundrect
			(at 0.485 0 90)
			(size 0.59 0.64)
			(layers "B.Cu" "B.Mask" "B.Paste")
			(roundrect_rratio 0.25)
			(net 200 "+3V3")
			(pintype "passive")
		)
	)
	(footprint "antmicro-footprints:R_0402_1005Metric"
		(layer "B.Cu")
		(at 144.399998 142.4 90)
		(descr "Resistor SMD 0402")
		(tags "resistor SMD 0402")
		(property "Reference" "R29"
			(at 3 0.3 270)
			(layer "B.SilkS")
			(effects
				(font
					(size 0.7 0.7)
					(thickness 0.15)
				)
				(justify left bottom mirror)
			)
		)
		(property "Value" "R_0R_0402"
			(at -1.011843 -1.772047 270)
			(layer "B.Fab")
			(effects
				(font
					(size 0.7 0.7)
					(thickness 0.15)
				)
				(justify left bottom mirror)
			)
		)
		(property "Datasheet" "https://industrial.panasonic.com/cdbs/www-data/pdf/RDA0000/AOA0000C301.pdf"
			(at 0 0 90)
			(layer "F.Fab")
			(hide yes)
			(effects
				(font
					(size 1.27 1.27)
					(thickness 0.15)
				)
			)
		)
		(property "Author" "Antmicro"
			(at 286.799998 -1.999998 0)
			(layer "B.Fab")
			(hide yes)
			(effects
				(font
					(size 1 1)
					(thickness 0.15)
				)
				(justify mirror)
			)
		)
		(property "Current" "1A"
			(at 286.799998 -1.999998 0)
			(layer "B.Fab")
			(hide yes)
			(effects
				(font
					(size 1 1)
					(thickness 0.15)
				)
				(justify mirror)
			)
		)
		(property "License" "Apache-2.0"
			(at 286.799998 -1.999998 0)
			(layer "B.Fab")
			(hide yes)
			(effects
				(font
					(size 1 1)
					(thickness 0.15)
				)
				(justify mirror)
			)
		)
		(property "MPN" "ERJ2GE0R00X"
			(at 286.799998 -1.999998 0)
			(layer "B.Fab")
			(hide yes)
			(effects
				(font
					(size 1 1)
					(thickness 0.15)
				)
				(justify mirror)
			)
		)
		(property "Manufacturer" "Panasonic"
			(at 286.799998 -1.999998 0)
			(layer "B.Fab")
			(hide yes)
			(effects
				(font
					(size 1 1)
					(thickness 0.15)
				)
				(justify mirror)
			)
		)
		(property "Tolerance" ""
			(at 286.799998 -1.999998 0)
			(layer "B.Fab")
			(hide yes)
			(effects
				(font
					(size 1 1)
					(thickness 0.15)
				)
				(justify mirror)
			)
		)
		(property "Val" "0R"
			(at 286.799998 -1.999998 0)
			(layer "B.Fab")
			(hide yes)
			(effects
				(font
					(size 1 1)
					(thickness 0.15)
				)
				(justify mirror)
			)
		)
		(sheetname "/DDR5 SODIMM/")
		(sheetfile "ddr5-sodimm.kicad_sch")
		(attr exclude_from_pos_files exclude_from_bom dnp)
		(fp_rect
			(start -0.93 0.47)
			(end 0.93 -0.47)
			(stroke
				(width 0.05)
				(type solid)
			)
			(fill no)
			(layer "B.CrtYd")
		)
		(fp_rect
			(start -0.5 0.25)
			(end 0.5 -0.25)
			(stroke
				(width 0.15)
				(type solid)
			)
			(fill no)
			(layer "B.Fab")
		)
		(pad "1" smd roundrect
			(at -0.485 0 90)
			(size 0.59 0.64)
			(layers "B.Cu" "B.Mask" "B.Paste")
			(roundrect_rratio 0.25)
			(net 1 "GND")
			(pintype "passive")
		)
		(pad "2" smd roundrect
			(at 0.485 0 90)
			(size 0.59 0.64)
			(layers "B.Cu" "B.Mask" "B.Paste")
			(roundrect_rratio 0.25)
			(net 173 "/DDR5 SODIMM/RFU3")
			(pintype "passive")
		)
	)
	(footprint "antmicro-footprints:C_0402_1005Metric"
		(layer "B.Cu")
		(at 117.650501 172.866)
		(descr "Capacitor SMD 0402")
		(tags "capacitor SMD 0402")
		(property "Reference" "C3"
			(at 0 0.699 180)
			(layer "B.SilkS")
			(hide yes)
			(effects
				(font
					(size 0.7 0.7)
					(thickness 0.15)
				)
				(justify left bottom mirror)
			)
		)
		(property "Value" "C_100n_0402"
			(at -1.022927 -2.155213 180)
			(layer "B.Fab")
			(effects
				(font
					(size 0.7 0.7)
					(thickness 0.15)
				)
				(justify left bottom mirror)
			)
		)
		(property "Datasheet" "https://www.murata.com/products/productdetail?partno=GRM155R61H104KE14%23"
			(at 0 0 0)
			(layer "F.Fab")
			(hide yes)
			(effects
				(font
					(size 1.27 1.27)
					(thickness 0.15)
				)
			)
		)
		(property "Author" "Antmicro"
			(at 0 0 0)
			(layer "B.Fab")
			(hide yes)
			(effects
				(font
					(size 1 1)
					(thickness 0.15)
				)
				(justify mirror)
			)
		)
		(property "Dielectric" "X5R"
			(at 0 0 0)
			(layer "B.Fab")
			(hide yes)
			(effects
				(font
					(size 1 1)
					(thickness 0.15)
				)
				(justify mirror)
			)
		)
		(property "License" "Apache-2.0"
			(at 0 0 0)
			(layer "B.Fab")
			(hide yes)
			(effects
				(font
					(size 1 1)
					(thickness 0.15)
				)
				(justify mirror)
			)
		)
		(property "MPN" "GRM155R61H104KE14D"
			(at 0 0 0)
			(layer "B.Fab")
			(hide yes)
			(effects
				(font
					(size 1 1)
					(thickness 0.15)
				)
				(justify mirror)
			)
		)
		(property "Manufacturer" "Murata"
			(at 0 0 0)
			(layer "B.Fab")
			(hide yes)
			(effects
				(font
					(size 1 1)
					(thickness 0.15)
				)
				(justify mirror)
			)
		)
		(property "Val" "100n"
			(at 0 0 0)
			(layer "B.Fab")
			(hide yes)
			(effects
				(font
					(size 1 1)
					(thickness 0.15)
				)
				(justify mirror)
			)
		)
		(property "Voltage" "50V"
			(at 0 0 0)
			(layer "B.Fab")
			(hide yes)
			(effects
				(font
					(size 1 1)
					(thickness 0.15)
				)
				(justify mirror)
			)
		)
		(sheetname "/HyperRAM + QSPI Flash/")
		(sheetfile "hyperram-flash.kicad_sch")
		(attr smd)
		(fp_rect
			(start -0.9659 0.481258)
			(end 0.9649 -0.458742)
			(stroke
				(width 0.05)
				(type solid)
			)
			(fill no)
			(layer "B.CrtYd")
		)
		(fp_line
			(start -0.499 -0.248)
			(end -0.499 0.25)
			(stroke
				(width 0.15)
				(type solid)
			)
			(layer "B.Fab")
		)
		(fp_line
			(start -0.499 0.25)
			(end 0.499 0.25)
			(stroke
				(width 0.15)
				(type solid)
			)
			(layer "B.Fab")
		)
		(fp_line
			(start 0.499 -0.248)
			(end -0.499 -0.248)
			(stroke
				(width 0.15)
				(type solid)
			)
			(layer "B.Fab")
		)
		(fp_line
			(start 0.499 0.25)
			(end 0.499 -0.248)
			(stroke
				(width 0.15)
				(type solid)
			)
			(layer "B.Fab")
		)
		(pad "1" smd roundrect
			(at -0.484 0)
			(size 0.59 0.64)
			(layers "B.Cu" "B.Mask" "B.Paste")
			(roundrect_rratio 0.25)
			(net 200 "+3V3")
			(pintype "passive")
		)
		(pad "2" smd roundrect
			(at 0.484 0)
			(size 0.59 0.64)
			(layers "B.Cu" "B.Mask" "B.Paste")
			(roundrect_rratio 0.25)
			(net 1 "GND")
			(pintype "passive")
		)
	)
	(footprint "antmicro-footprints:C_0402_1005Metric"
		(layer "B.Cu")
		(at 147.875501 162.301 180)
		(descr "Capacitor SMD 0402 (1005 Metric), square (rectangular) end terminal, IPC_7351 nominal, (Body size source: IPC-SM-782 page 76, https://www.pcb-3d.com/wordpress/wp-content/uploads/ipc-sm-782a_amendment_1_and_2.pdf)")
		(tags "capacitor 0402")
		(property "Reference" "C87"
			(at 0 1.17 0)
			(layer "B.SilkS")
			(hide yes)
			(effects
				(font
					(size 0.7 0.7)
					(thickness 0.15)
				)
				(justify left bottom mirror)
			)
		)
		(property "Value" "C_100n_0402"
			(at 0 -1.169 0)
			(layer "B.Fab")
			(effects
				(font
					(size 0.7 0.7)
					(thickness 0.15)
				)
				(justify left bottom mirror)
			)
		)
		(property "Datasheet" "https://www.murata.com/products/productdetail?partno=GRM155R61H104KE14%23"
			(at 0 0 180)
			(layer "F.Fab")
			(hide yes)
			(effects
				(font
					(size 1.27 1.27)
					(thickness 0.15)
				)
			)
		)
		(property "Author" "Antmicro"
			(at 295.751002 324.602 0)
			(layer "B.Fab")
			(hide yes)
			(effects
				(font
					(size 1 1)
					(thickness 0.15)
				)
				(justify mirror)
			)
		)
		(property "Dielectric" "X5R"
			(at 295.751002 324.602 0)
			(layer "B.Fab")
			(hide yes)
			(effects
				(font
					(size 1 1)
					(thickness 0.15)
				)
				(justify mirror)
			)
		)
		(property "License" "Apache-2.0"
			(at 295.751002 324.602 0)
			(layer "B.Fab")
			(hide yes)
			(effects
				(font
					(size 1 1)
					(thickness 0.15)
				)
				(justify mirror)
			)
		)
		(property "MPN" "GRM155R61H104KE14D"
			(at 295.751002 324.602 0)
			(layer "B.Fab")
			(hide yes)
			(effects
				(font
					(size 1 1)
					(thickness 0.15)
				)
				(justify mirror)
			)
		)
		(property "Manufacturer" "Murata"
			(at 295.751002 324.602 0)
			(layer "B.Fab")
			(hide yes)
			(effects
				(font
					(size 1 1)
					(thickness 0.15)
				)
				(justify mirror)
			)
		)
		(property "Val" "100n"
			(at 295.751002 324.602 0)
			(layer "B.Fab")
			(hide yes)
			(effects
				(font
					(size 1 1)
					(thickness 0.15)
				)
				(justify mirror)
			)
		)
		(property "Voltage" "50V"
			(at 295.751002 324.602 0)
			(layer "B.Fab")
			(hide yes)
			(effects
				(font
					(size 1 1)
					(thickness 0.15)
				)
				(justify mirror)
			)
		)
		(sheetname "/FPGA power/")
		(sheetfile "fpga-power.kicad_sch")
		(attr smd)
		(fp_rect
			(start -0.9656 0.4572)
			(end 0.9652 -0.4828)
			(stroke
				(width 0.05)
				(type solid)
			)
			(fill no)
			(layer "B.CrtYd")
		)
		(fp_line
			(start 0.498 0.25)
			(end 0.498 -0.248)
			(stroke
				(width 0.15)
				(type solid)
			)
			(layer "B.Fab")
		)
		(fp_line
			(start 0.498 -0.248)
			(end -0.5 -0.248)
			(stroke
				(width 0.15)
				(type solid)
			)
			(layer "B.Fab")
		)
		(fp_line
			(start -0.5 0.25)
			(end 0.498 0.25)
			(stroke
				(width 0.15)
				(type solid)
			)
			(layer "B.Fab")
		)
		(fp_line
			(start -0.5 -0.248)
			(end -0.5 0.25)
			(stroke
				(width 0.15)
				(type solid)
			)
			(layer "B.Fab")
		)
		(pad "1" smd roundrect
			(at -0.5 0 90)
			(size 0.6 0.6)
			(layers "B.Cu" "B.Mask" "B.Paste")
			(roundrect_rratio 0.25)
			(net 1 "GND")
			(pintype "passive")
		)
		(pad "2" smd roundrect
			(at 0.498 0 180)
			(size 0.6 0.6)
			(layers "B.Cu" "B.Mask" "B.Paste")
			(roundrect_rratio 0.25)
			(net 206 "+1V1")
			(pintype "passive")
		)
	)
	(footprint "antmicro-footprints:R_0402_1005Metric"
		(layer "B.Cu")
		(at 180.8 197.4 180)
		(descr "Resistor SMD 0402")
		(tags "resistor SMD 0402")
		(property "Reference" "R150"
			(at -3.95 -0.5 0)
			(layer "B.SilkS")
			(effects
				(font
					(size 0.7 0.7)
					(thickness 0.15)
				)
				(justify left bottom mirror)
			)
		)
		(property "Value" "R_4k7_0402"
			(at -1.011843 -1.772047 0)
			(layer "B.Fab")
			(effects
				(font
					(size 0.7 0.7)
					(thickness 0.15)
				)
				(justify left bottom mirror)
			)
		)
		(property "Datasheet" "https://www.bourns.com/docs/product-datasheets/cr.pdf"
			(at 0 0 180)
			(layer "F.Fab")
			(hide yes)
			(effects
				(font
					(size 1.27 1.27)
					(thickness 0.15)
				)
			)
		)
		(property "Author" "Antmicro"
			(at 361.6 394.8 0)
			(layer "B.Fab")
			(hide yes)
			(effects
				(font
					(size 1 1)
					(thickness 0.15)
				)
				(justify mirror)
			)
		)
		(property "License" "Apache-2.0"
			(at 361.6 394.8 0)
			(layer "B.Fab")
			(hide yes)
			(effects
				(font
					(size 1 1)
					(thickness 0.15)
				)
				(justify mirror)
			)
		)
		(property "MPN" "CR0402-FX-4701GLF"
			(at 361.6 394.8 0)
			(layer "B.Fab")
			(hide yes)
			(effects
				(font
					(size 1 1)
					(thickness 0.15)
				)
				(justify mirror)
			)
		)
		(property "Manufacturer" "Bourns"
			(at 361.6 394.8 0)
			(layer "B.Fab")
			(hide yes)
			(effects
				(font
					(size 1 1)
					(thickness 0.15)
				)
				(justify mirror)
			)
		)
		(property "Tolerance" "1%"
			(at 361.6 394.8 0)
			(layer "B.Fab")
			(hide yes)
			(effects
				(font
					(size 1 1)
					(thickness 0.15)
				)
				(justify mirror)
			)
		)
		(property "Val" "4k7"
			(at 361.6 394.8 0)
			(layer "B.Fab")
			(hide yes)
			(effects
				(font
					(size 1 1)
					(thickness 0.15)
				)
				(justify mirror)
			)
		)
		(sheetname "/I^{2}C/")
		(sheetfile "i2c.kicad_sch")
		(attr smd)
		(fp_rect
			(start -0.93 0.47)
			(end 0.93 -0.47)
			(stroke
				(width 0.05)
				(type solid)
			)
			(fill no)
			(layer "B.CrtYd")
		)
		(fp_rect
			(start -0.5 0.25)
			(end 0.5 -0.25)
			(stroke
				(width 0.15)
				(type solid)
			)
			(fill no)
			(layer "B.Fab")
		)
		(pad "1" smd roundrect
			(at -0.485 0 180)
			(size 0.59 0.64)
			(layers "B.Cu" "B.Mask" "B.Paste")
			(roundrect_rratio 0.25)
			(net 200 "+3V3")
			(pintype "passive")
		)
		(pad "2" smd roundrect
			(at 0.485 0 180)
			(size 0.59 0.64)
			(layers "B.Cu" "B.Mask" "B.Paste")
			(roundrect_rratio 0.25)
			(net 688 "/FPGA bank 14/FPGA_PWR.SDA")
			(pintype "passive")
		)
	)
	(footprint "antmicro-footprints:C_0402_1005Metric"
		(layer "B.Cu")
		(at 144.875501 173.301 180)
		(descr "Capacitor SMD 0402 (1005 Metric), square (rectangular) end terminal, IPC_7351 nominal, (Body size source: IPC-SM-782 page 76, https://www.pcb-3d.com/wordpress/wp-content/uploads/ipc-sm-782a_amendment_1_and_2.pdf)")
		(tags "capacitor 0402")
		(property "Reference" "C77"
			(at 0 1.17 0)
			(layer "B.SilkS")
			(hide yes)
			(effects
				(font
					(size 0.7 0.7)
					(thickness 0.15)
				)
				(justify left bottom mirror)
			)
		)
		(property "Value" "C_100n_0402"
			(at 0 -1.169 0)
			(layer "B.Fab")
			(effects
				(font
					(size 0.7 0.7)
					(thickness 0.15)
				)
				(justify left bottom mirror)
			)
		)
		(property "Datasheet" "https://www.murata.com/products/productdetail?partno=GRM155R61H104KE14%23"
			(at 0 0 180)
			(layer "F.Fab")
			(hide yes)
			(effects
				(font
					(size 1.27 1.27)
					(thickness 0.15)
				)
			)
		)
		(property "Author" "Antmicro"
			(at 289.751002 346.602 0)
			(layer "B.Fab")
			(hide yes)
			(effects
				(font
					(size 1 1)
					(thickness 0.15)
				)
				(justify mirror)
			)
		)
		(property "Dielectric" "X5R"
			(at 289.751002 346.602 0)
			(layer "B.Fab")
			(hide yes)
			(effects
				(font
					(size 1 1)
					(thickness 0.15)
				)
				(justify mirror)
			)
		)
		(property "License" "Apache-2.0"
			(at 289.751002 346.602 0)
			(layer "B.Fab")
			(hide yes)
			(effects
				(font
					(size 1 1)
					(thickness 0.15)
				)
				(justify mirror)
			)
		)
		(property "MPN" "GRM155R61H104KE14D"
			(at 289.751002 346.602 0)
			(layer "B.Fab")
			(hide yes)
			(effects
				(font
					(size 1 1)
					(thickness 0.15)
				)
				(justify mirror)
			)
		)
		(property "Manufacturer" "Murata"
			(at 289.751002 346.602 0)
			(layer "B.Fab")
			(hide yes)
			(effects
				(font
					(size 1 1)
					(thickness 0.15)
				)
				(justify mirror)
			)
		)
		(property "Val" "100n"
			(at 289.751002 346.602 0)
			(layer "B.Fab")
			(hide yes)
			(effects
				(font
					(size 1 1)
					(thickness 0.15)
				)
				(justify mirror)
			)
		)
		(property "Voltage" "50V"
			(at 289.751002 346.602 0)
			(layer "B.Fab")
			(hide yes)
			(effects
				(font
					(size 1 1)
					(thickness 0.15)
				)
				(justify mirror)
			)
		)
		(sheetname "/FPGA power/")
		(sheetfile "fpga-power.kicad_sch")
		(attr smd)
		(fp_rect
			(start -0.9656 0.4572)
			(end 0.9652 -0.4828)
			(stroke
				(width 0.05)
				(type solid)
			)
			(fill no)
			(layer "B.CrtYd")
		)
		(fp_line
			(start 0.498 0.25)
			(end 0.498 -0.248)
			(stroke
				(width 0.15)
				(type solid)
			)
			(layer "B.Fab")
		)
		(fp_line
			(start 0.498 -0.248)
			(end -0.5 -0.248)
			(stroke
				(width 0.15)
				(type solid)
			)
			(layer "B.Fab")
		)
		(fp_line
			(start -0.5 0.25)
			(end 0.498 0.25)
			(stroke
				(width 0.15)
				(type solid)
			)
			(layer "B.Fab")
		)
		(fp_line
			(start -0.5 -0.248)
			(end -0.5 0.25)
			(stroke
				(width 0.15)
				(type solid)
			)
			(layer "B.Fab")
		)
		(pad "1" smd roundrect
			(at -0.5 0 90)
			(size 0.6 0.6)
			(layers "B.Cu" "B.Mask" "B.Paste")
			(roundrect_rratio 0.25)
			(net 1 "GND")
			(pintype "passive")
		)
		(pad "2" smd roundrect
			(at 0.498 0 180)
			(size 0.6 0.6)
			(layers "B.Cu" "B.Mask" "B.Paste")
			(roundrect_rratio 0.25)
			(net 188 "+1V8")
			(pintype "passive")
		)
	)
	(footprint "antmicro-footprints:C_0402_1005Metric"
		(layer "B.Cu")
		(at 149.875001 180.300501 180)
		(descr "Capacitor SMD 0402 (1005 Metric), square (rectangular) end terminal, IPC_7351 nominal, (Body size source: IPC-SM-782 page 76, https://www.pcb-3d.com/wordpress/wp-content/uploads/ipc-sm-782a_amendment_1_and_2.pdf)")
		(tags "capacitor 0402")
		(property "Reference" "C107"
			(at 0 1.17 0)
			(layer "B.SilkS")
			(hide yes)
			(effects
				(font
					(size 0.7 0.7)
					(thickness 0.15)
				)
				(justify left bottom mirror)
			)
		)
		(property "Value" "C_100n_0402"
			(at 0 -1.169 0)
			(layer "B.Fab")
			(effects
				(font
					(size 0.7 0.7)
					(thickness 0.15)
				)
				(justify left bottom mirror)
			)
		)
		(property "Datasheet" "https://www.murata.com/products/productdetail?partno=GRM155R61H104KE14%23"
			(at 0 0 180)
			(layer "F.Fab")
			(hide yes)
			(effects
				(font
					(size 1.27 1.27)
					(thickness 0.15)
				)
			)
		)
		(property "Author" "Antmicro"
			(at 299.750002 360.601002 0)
			(layer "B.Fab")
			(hide yes)
			(effects
				(font
					(size 1 1)
					(thickness 0.15)
				)
				(justify mirror)
			)
		)
		(property "Dielectric" "X5R"
			(at 299.750002 360.601002 0)
			(layer "B.Fab")
			(hide yes)
			(effects
				(font
					(size 1 1)
					(thickness 0.15)
				)
				(justify mirror)
			)
		)
		(property "License" "Apache-2.0"
			(at 299.750002 360.601002 0)
			(layer "B.Fab")
			(hide yes)
			(effects
				(font
					(size 1 1)
					(thickness 0.15)
				)
				(justify mirror)
			)
		)
		(property "MPN" "GRM155R61H104KE14D"
			(at 299.750002 360.601002 0)
			(layer "B.Fab")
			(hide yes)
			(effects
				(font
					(size 1 1)
					(thickness 0.15)
				)
				(justify mirror)
			)
		)
		(property "Manufacturer" "Murata"
			(at 299.750002 360.601002 0)
			(layer "B.Fab")
			(hide yes)
			(effects
				(font
					(size 1 1)
					(thickness 0.15)
				)
				(justify mirror)
			)
		)
		(property "Val" "100n"
			(at 299.750002 360.601002 0)
			(layer "B.Fab")
			(hide yes)
			(effects
				(font
					(size 1 1)
					(thickness 0.15)
				)
				(justify mirror)
			)
		)
		(property "Voltage" "50V"
			(at 299.750002 360.601002 0)
			(layer "B.Fab")
			(hide yes)
			(effects
				(font
					(size 1 1)
					(thickness 0.15)
				)
				(justify mirror)
			)
		)
		(sheetname "/FPGA power/")
		(sheetfile "fpga-power.kicad_sch")
		(attr smd)
		(fp_rect
			(start -0.9656 0.4572)
			(end 0.9652 -0.4828)
			(stroke
				(width 0.05)
				(type solid)
			)
			(fill no)
			(layer "B.CrtYd")
		)
		(fp_line
			(start 0.498 0.25)
			(end 0.498 -0.248)
			(stroke
				(width 0.15)
				(type solid)
			)
			(layer "B.Fab")
		)
		(fp_line
			(start 0.498 -0.248)
			(end -0.5 -0.248)
			(stroke
				(width 0.15)
				(type solid)
			)
			(layer "B.Fab")
		)
		(fp_line
			(start -0.5 0.25)
			(end 0.498 0.25)
			(stroke
				(width 0.15)
				(type solid)
			)
			(layer "B.Fab")
		)
		(fp_line
			(start -0.5 -0.248)
			(end -0.5 0.25)
			(stroke
				(width 0.15)
				(type solid)
			)
			(layer "B.Fab")
		)
		(pad "1" smd roundrect
			(at -0.5 0 90)
			(size 0.6 0.6)
			(layers "B.Cu" "B.Mask" "B.Paste")
			(roundrect_rratio 0.25)
			(net 1 "GND")
			(pintype "passive")
		)
		(pad "2" smd roundrect
			(at 0.498 0 180)
			(size 0.6 0.6)
			(layers "B.Cu" "B.Mask" "B.Paste")
			(roundrect_rratio 0.25)
			(net 226 "+1V2_MGTAVTT")
			(pintype "passive")
		)
	)
	(footprint "antmicro-footprints:C_0402_1005Metric"
		(layer "B.Cu")
		(at 99.270501 138.236 180)
		(descr "Capacitor SMD 0402")
		(tags "capacitor SMD 0402")
		(property "Reference" "C166"
			(at 0 0.699 0)
			(layer "B.SilkS")
			(hide yes)
			(effects
				(font
					(size 0.7 0.7)
					(thickness 0.15)
				)
				(justify left bottom mirror)
			)
		)
		(property "Value" "C_100n_0402"
			(at -1.022927 -2.155213 0)
			(layer "B.Fab")
			(effects
				(font
					(size 0.7 0.7)
					(thickness 0.15)
				)
				(justify left bottom mirror)
			)
		)
		(property "Datasheet" "https://www.murata.com/products/productdetail?partno=GRM155R61H104KE14%23"
			(at 0 0 180)
			(layer "F.Fab")
			(hide yes)
			(effects
				(font
					(size 1.27 1.27)
					(thickness 0.15)
				)
			)
		)
		(property "Author" "Antmicro"
			(at 198.541002 276.472 0)
			(layer "B.Fab")
			(hide yes)
			(effects
				(font
					(size 1 1)
					(thickness 0.15)
				)
				(justify mirror)
			)
		)
		(property "Dielectric" "X5R"
			(at 198.541002 276.472 0)
			(layer "B.Fab")
			(hide yes)
			(effects
				(font
					(size 1 1)
					(thickness 0.15)
				)
				(justify mirror)
			)
		)
		(property "License" "Apache-2.0"
			(at 198.541002 276.472 0)
			(layer "B.Fab")
			(hide yes)
			(effects
				(font
					(size 1 1)
					(thickness 0.15)
				)
				(justify mirror)
			)
		)
		(property "MPN" "GRM155R61H104KE14D"
			(at 198.541002 276.472 0)
			(layer "B.Fab")
			(hide yes)
			(effects
				(font
					(size 1 1)
					(thickness 0.15)
				)
				(justify mirror)
			)
		)
		(property "Manufacturer" "Murata"
			(at 198.541002 276.472 0)
			(layer "B.Fab")
			(hide yes)
			(effects
				(font
					(size 1 1)
					(thickness 0.15)
				)
				(justify mirror)
			)
		)
		(property "Val" "100n"
			(at 198.541002 276.472 0)
			(layer "B.Fab")
			(hide yes)
			(effects
				(font
					(size 1 1)
					(thickness 0.15)
				)
				(justify mirror)
			)
		)
		(property "Voltage" "50V"
			(at 198.541002 276.472 0)
			(layer "B.Fab")
			(hide yes)
			(effects
				(font
					(size 1 1)
					(thickness 0.15)
				)
				(justify mirror)
			)
		)
		(sheetname "/I^{2}C/")
		(sheetfile "i2c.kicad_sch")
		(attr smd)
		(fp_rect
			(start -0.9659 0.481258)
			(end 0.9649 -0.458742)
			(stroke
				(width 0.05)
				(type solid)
			)
			(fill no)
			(layer "B.CrtYd")
		)
		(fp_line
			(start 0.499 0.25)
			(end 0.499 -0.248)
			(stroke
				(width 0.15)
				(type solid)
			)
			(layer "B.Fab")
		)
		(fp_line
			(start 0.499 -0.248)
			(end -0.499 -0.248)
			(stroke
				(width 0.15)
				(type solid)
			)
			(layer "B.Fab")
		)
		(fp_line
			(start -0.499 0.25)
			(end 0.499 0.25)
			(stroke
				(width 0.15)
				(type solid)
			)
			(layer "B.Fab")
		)
		(fp_line
			(start -0.499 -0.248)
			(end -0.499 0.25)
			(stroke
				(width 0.15)
				(type solid)
			)
			(layer "B.Fab")
		)
		(pad "1" smd roundrect
			(at -0.484 0 180)
			(size 0.59 0.64)
			(layers "B.Cu" "B.Mask" "B.Paste")
			(roundrect_rratio 0.25)
			(net 267 "VDDSPD")
			(pintype "passive")
		)
		(pad "2" smd roundrect
			(at 0.484 0 180)
			(size 0.59 0.64)
			(layers "B.Cu" "B.Mask" "B.Paste")
			(roundrect_rratio 0.25)
			(net 1 "GND")
			(pintype "passive")
		)
	)
	(footprint "antmicro-footprints:R_0402_1005Metric"
		(layer "B.Cu")
		(at 180.8 194.05 180)
		(descr "Resistor SMD 0402")
		(tags "resistor SMD 0402")
		(property "Reference" "R159"
			(at 1.25 -0.4 0)
			(layer "B.SilkS")
			(effects
				(font
					(size 0.7 0.7)
					(thickness 0.15)
				)
				(justify left bottom mirror)
			)
		)
		(property "Value" "R_4k7_0402"
			(at -1.011843 -1.772047 0)
			(layer "B.Fab")
			(effects
				(font
					(size 0.7 0.7)
					(thickness 0.15)
				)
				(justify left bottom mirror)
			)
		)
		(property "Datasheet" "https://www.bourns.com/docs/product-datasheets/cr.pdf"
			(at 0 0 180)
			(layer "F.Fab")
			(hide yes)
			(effects
				(font
					(size 1.27 1.27)
					(thickness 0.15)
				)
			)
		)
		(property "Author" "Antmicro"
			(at 361.6 388.1 0)
			(layer "B.Fab")
			(hide yes)
			(effects
				(font
					(size 1 1)
					(thickness 0.15)
				)
				(justify mirror)
			)
		)
		(property "License" "Apache-2.0"
			(at 361.6 388.1 0)
			(layer "B.Fab")
			(hide yes)
			(effects
				(font
					(size 1 1)
					(thickness 0.15)
				)
				(justify mirror)
			)
		)
		(property "MPN" "CR0402-FX-4701GLF"
			(at 361.6 388.1 0)
			(layer "B.Fab")
			(hide yes)
			(effects
				(font
					(size 1 1)
					(thickness 0.15)
				)
				(justify mirror)
			)
		)
		(property "Manufacturer" "Bourns"
			(at 361.6 388.1 0)
			(layer "B.Fab")
			(hide yes)
			(effects
				(font
					(size 1 1)
					(thickness 0.15)
				)
				(justify mirror)
			)
		)
		(property "Tolerance" "1%"
			(at 361.6 388.1 0)
			(layer "B.Fab")
			(hide yes)
			(effects
				(font
					(size 1 1)
					(thickness 0.15)
				)
				(justify mirror)
			)
		)
		(property "Val" "4k7"
			(at 361.6 388.1 0)
			(layer "B.Fab")
			(hide yes)
			(effects
				(font
					(size 1 1)
					(thickness 0.15)
				)
				(justify mirror)
			)
		)
		(sheetname "/I^{2}C/")
		(sheetfile "i2c.kicad_sch")
		(attr smd)
		(fp_rect
			(start -0.93 0.47)
			(end 0.93 -0.47)
			(stroke
				(width 0.05)
				(type solid)
			)
			(fill no)
			(layer "B.CrtYd")
		)
		(fp_rect
			(start -0.5 0.25)
			(end 0.5 -0.25)
			(stroke
				(width 0.15)
				(type solid)
			)
			(fill no)
			(layer "B.Fab")
		)
		(pad "1" smd roundrect
			(at -0.485 0 180)
			(size 0.59 0.64)
			(layers "B.Cu" "B.Mask" "B.Paste")
			(roundrect_rratio 0.25)
			(net 200 "+3V3")
			(pintype "passive")
		)
		(pad "2" smd roundrect
			(at 0.485 0 180)
			(size 0.59 0.64)
			(layers "B.Cu" "B.Mask" "B.Paste")
			(roundrect_rratio 0.25)
			(net 689 "/FPGA bank 14/FPGA_PWR.SCL")
			(pintype "passive")
		)
	)
	(footprint "antmicro-footprints:R_0402_1005Metric"
		(layer "B.Cu")
		(at 196.950001 151.8 180)
		(descr "Resistor SMD 0402")
		(tags "resistor SMD 0402")
		(property "Reference" "R139"
			(at -1.122484 0.772697 0)
			(layer "B.SilkS")
			(hide yes)
			(effects
				(font
					(size 0.7 0.7)
					(thickness 0.15)
				)
				(justify left bottom mirror)
			)
		)
		(property "Value" "R_47k_0402"
			(at -1.011843 -1.772047 0)
			(layer "B.Fab")
			(effects
				(font
					(size 0.7 0.7)
					(thickness 0.15)
				)
				(justify left bottom mirror)
			)
		)
		(property "Datasheet" "https://www.bourns.com/docs/product-datasheets/cr.pdf"
			(at 0 0 180)
			(layer "F.Fab")
			(hide yes)
			(effects
				(font
					(size 1.27 1.27)
					(thickness 0.15)
				)
			)
		)
		(property "Author" "Antmicro"
			(at 393.900002 303.6 0)
			(layer "B.Fab")
			(hide yes)
			(effects
				(font
					(size 1 1)
					(thickness 0.15)
				)
				(justify mirror)
			)
		)
		(property "License" "Apache-2.0"
			(at 393.900002 303.6 0)
			(layer "B.Fab")
			(hide yes)
			(effects
				(font
					(size 1 1)
					(thickness 0.15)
				)
				(justify mirror)
			)
		)
		(property "MPN" "CR0402-FX-4702GLF"
			(at 393.900002 303.6 0)
			(layer "B.Fab")
			(hide yes)
			(effects
				(font
					(size 1 1)
					(thickness 0.15)
				)
				(justify mirror)
			)
		)
		(property "Manufacturer" "Bourns"
			(at 393.900002 303.6 0)
			(layer "B.Fab")
			(hide yes)
			(effects
				(font
					(size 1 1)
					(thickness 0.15)
				)
				(justify mirror)
			)
		)
		(property "Tolerance" "1%"
			(at 393.900002 303.6 0)
			(layer "B.Fab")
			(hide yes)
			(effects
				(font
					(size 1 1)
					(thickness 0.15)
				)
				(justify mirror)
			)
		)
		(property "Val" "47k"
			(at 393.900002 303.6 0)
			(layer "B.Fab")
			(hide yes)
			(effects
				(font
					(size 1 1)
					(thickness 0.15)
				)
				(justify mirror)
			)
		)
		(sheetname "/Supply/")
		(sheetfile "supply.kicad_sch")
		(attr smd)
		(fp_rect
			(start -0.93 0.47)
			(end 0.93 -0.47)
			(stroke
				(width 0.05)
				(type solid)
			)
			(fill no)
			(layer "B.CrtYd")
		)
		(fp_rect
			(start -0.5 0.25)
			(end 0.5 -0.25)
			(stroke
				(width 0.15)
				(type solid)
			)
			(fill no)
			(layer "B.Fab")
		)
		(pad "1" smd roundrect
			(at -0.485 0 180)
			(size 0.59 0.64)
			(layers "B.Cu" "B.Mask" "B.Paste")
			(roundrect_rratio 0.25)
			(net 686 "IN1")
			(pintype "passive")
		)
		(pad "2" smd roundrect
			(at 0.485 0 180)
			(size 0.59 0.64)
			(layers "B.Cu" "B.Mask" "B.Paste")
			(roundrect_rratio 0.25)
			(net 41 "+3V3_AON")
			(pintype "passive")
		)
	)
	(footprint "antmicro-footprints:C_0402_1005Metric"
		(layer "B.Cu")
		(at 141.875001 171.3025 180)
		(descr "Capacitor SMD 0402 (1005 Metric), square (rectangular) end terminal, IPC_7351 nominal, (Body size source: IPC-SM-782 page 76, https://www.pcb-3d.com/wordpress/wp-content/uploads/ipc-sm-782a_amendment_1_and_2.pdf)")
		(tags "capacitor 0402")
		(property "Reference" "C34"
			(at 0 1.17 0)
			(layer "B.SilkS")
			(hide yes)
			(effects
				(font
					(size 0.7 0.7)
					(thickness 0.15)
				)
				(justify left bottom mirror)
			)
		)
		(property "Value" "C_4u7_0402"
			(at 0 -1.169 0)
			(layer "B.Fab")
			(effects
				(font
					(size 0.7 0.7)
					(thickness 0.15)
				)
				(justify left bottom mirror)
			)
		)
		(property "Datasheet" "https://www.murata.com/products/productdetail?partno=GRM155R61A475MEAA%23"
			(at 0 0 180)
			(layer "F.Fab")
			(hide yes)
			(effects
				(font
					(size 1.27 1.27)
					(thickness 0.15)
				)
			)
		)
		(property "Author" "Antmicro"
			(at 283.750002 342.605 0)
			(layer "B.Fab")
			(hide yes)
			(effects
				(font
					(size 1 1)
					(thickness 0.15)
				)
				(justify mirror)
			)
		)
		(property "Dielectric" ""
			(at 283.750002 342.605 0)
			(layer "B.Fab")
			(hide yes)
			(effects
				(font
					(size 1 1)
					(thickness 0.15)
				)
				(justify mirror)
			)
		)
		(property "License" "Apache-2.0"
			(at 283.750002 342.605 0)
			(layer "B.Fab")
			(hide yes)
			(effects
				(font
					(size 1 1)
					(thickness 0.15)
				)
				(justify mirror)
			)
		)
		(property "MPN" "GRM155R61A475MEAAD"
			(at 283.750002 342.605 0)
			(layer "B.Fab")
			(hide yes)
			(effects
				(font
					(size 1 1)
					(thickness 0.15)
				)
				(justify mirror)
			)
		)
		(property "Manufacturer" "Murata"
			(at 283.750002 342.605 0)
			(layer "B.Fab")
			(hide yes)
			(effects
				(font
					(size 1 1)
					(thickness 0.15)
				)
				(justify mirror)
			)
		)
		(property "Val" "4u7"
			(at 283.750002 342.605 0)
			(layer "B.Fab")
			(hide yes)
			(effects
				(font
					(size 1 1)
					(thickness 0.15)
				)
				(justify mirror)
			)
		)
		(property "Voltage" ""
			(at 283.750002 342.605 0)
			(layer "B.Fab")
			(hide yes)
			(effects
				(font
					(size 1 1)
					(thickness 0.15)
				)
				(justify mirror)
			)
		)
		(sheetname "/FPGA power/")
		(sheetfile "fpga-power.kicad_sch")
		(attr smd)
		(fp_rect
			(start -0.9656 0.4572)
			(end 0.9652 -0.4828)
			(stroke
				(width 0.05)
				(type solid)
			)
			(fill no)
			(layer "B.CrtYd")
		)
		(fp_line
			(start 0.498 0.25)
			(end 0.498 -0.248)
			(stroke
				(width 0.15)
				(type solid)
			)
			(layer "B.Fab")
		)
		(fp_line
			(start 0.498 -0.248)
			(end -0.5 -0.248)
			(stroke
				(width 0.15)
				(type solid)
			)
			(layer "B.Fab")
		)
		(fp_line
			(start -0.5 0.25)
			(end 0.498 0.25)
			(stroke
				(width 0.15)
				(type solid)
			)
			(layer "B.Fab")
		)
		(fp_line
			(start -0.5 -0.248)
			(end -0.5 0.25)
			(stroke
				(width 0.15)
				(type solid)
			)
			(layer "B.Fab")
		)
		(pad "1" smd roundrect
			(at -0.5 0 90)
			(size 0.6 0.6)
			(layers "B.Cu" "B.Mask" "B.Paste")
			(roundrect_rratio 0.25)
			(net 188 "+1V8")
			(pintype "passive")
		)
		(pad "2" smd roundrect
			(at 0.498 0 180)
			(size 0.6 0.6)
			(layers "B.Cu" "B.Mask" "B.Paste")
			(roundrect_rratio 0.25)
			(net 1 "GND")
			(pintype "passive")
		)
	)
	(footprint "antmicro-footprints:C_0402_1005Metric"
		(layer "B.Cu")
		(at 136.525501 204.850501 90)
		(descr "Capacitor SMD 0402")
		(tags "capacitor SMD 0402")
		(property "Reference" "C228"
			(at 0 0.699 270)
			(layer "B.SilkS")
			(hide yes)
			(effects
				(font
					(size 0.7 0.7)
					(thickness 0.15)
				)
				(justify left bottom mirror)
			)
		)
		(property "Value" "C_100n_0402"
			(at -1.022927 -2.155213 270)
			(layer "B.Fab")
			(effects
				(font
					(size 0.7 0.7)
					(thickness 0.15)
				)
				(justify left bottom mirror)
			)
		)
		(property "Datasheet" "https://www.murata.com/products/productdetail?partno=GRM155R61H104KE14%23"
			(at 0 0 90)
			(layer "F.Fab")
			(hide yes)
			(effects
				(font
					(size 1.27 1.27)
					(thickness 0.15)
				)
			)
		)
		(property "Author" "Antmicro"
			(at 341.376002 68.325 0)
			(layer "B.Fab")
			(hide yes)
			(effects
				(font
					(size 1 1)
					(thickness 0.15)
				)
				(justify mirror)
			)
		)
		(property "Dielectric" "X5R"
			(at 341.376002 68.325 0)
			(layer "B.Fab")
			(hide yes)
			(effects
				(font
					(size 1 1)
					(thickness 0.15)
				)
				(justify mirror)
			)
		)
		(property "License" "Apache-2.0"
			(at 341.376002 68.325 0)
			(layer "B.Fab")
			(hide yes)
			(effects
				(font
					(size 1 1)
					(thickness 0.15)
				)
				(justify mirror)
			)
		)
		(property "MPN" "GRM155R61H104KE14D"
			(at 341.376002 68.325 0)
			(layer "B.Fab")
			(hide yes)
			(effects
				(font
					(size 1 1)
					(thickness 0.15)
				)
				(justify mirror)
			)
		)
		(property "Manufacturer" "Murata"
			(at 341.376002 68.325 0)
			(layer "B.Fab")
			(hide yes)
			(effects
				(font
					(size 1 1)
					(thickness 0.15)
				)
				(justify mirror)
			)
		)
		(property "Val" "100n"
			(at 341.376002 68.325 0)
			(layer "B.Fab")
			(hide yes)
			(effects
				(font
					(size 1 1)
					(thickness 0.15)
				)
				(justify mirror)
			)
		)
		(property "Voltage" "50V"
			(at 341.376002 68.325 0)
			(layer "B.Fab")
			(hide yes)
			(effects
				(font
					(size 1 1)
					(thickness 0.15)
				)
				(justify mirror)
			)
		)
		(sheetname "/FPGA MGT Interface/")
		(sheetfile "fpga-mgt.kicad_sch")
		(attr smd)
		(fp_rect
			(start -0.9659 0.481258)
			(end 0.9649 -0.458742)
			(stroke
				(width 0.05)
				(type solid)
			)
			(fill no)
			(layer "B.CrtYd")
		)
		(fp_line
			(start 0.499 -0.248)
			(end -0.499 -0.248)
			(stroke
				(width 0.15)
				(type solid)
			)
			(layer "B.Fab")
		)
		(fp_line
			(start -0.499 -0.248)
			(end -0.499 0.25)
			(stroke
				(width 0.15)
				(type solid)
			)
			(layer "B.Fab")
		)
		(fp_line
			(start 0.499 0.25)
			(end 0.499 -0.248)
			(stroke
				(width 0.15)
				(type solid)
			)
			(layer "B.Fab")
		)
		(fp_line
			(start -0.499 0.25)
			(end 0.499 0.25)
			(stroke
				(width 0.15)
				(type solid)
			)
			(layer "B.Fab")
		)
		(pad "1" smd roundrect
			(at -0.484 0 90)
			(size 0.59 0.64)
			(layers "B.Cu" "B.Mask" "B.Paste")
			(roundrect_rratio 0.25)
			(net 20 "/FPGA MGT Interface/PCIE.TXD1_P")
			(pintype "passive")
		)
		(pad "2" smd roundrect
			(at 0.484 0 90)
			(size 0.59 0.64)
			(layers "B.Cu" "B.Mask" "B.Paste")
			(roundrect_rratio 0.25)
			(net 21 "/FPGA MGT Interface/GTX_TX2_P")
			(pintype "passive")
		)
	)
	(footprint "antmicro-footprints:R_0402_1005Metric"
		(layer "B.Cu")
		(at 159.7005 180.676001)
		(descr "Resistor SMD 0402")
		(tags "resistor SMD 0402")
		(property "Reference" "R15"
			(at -1.122484 0.772697 180)
			(layer "B.SilkS")
			(hide yes)
			(effects
				(font
					(size 0.7 0.7)
					(thickness 0.15)
				)
				(justify left bottom mirror)
			)
		)
		(property "Value" "R_10k_0402"
			(at -1.011843 -1.772047 180)
			(layer "B.Fab")
			(effects
				(font
					(size 0.7 0.7)
					(thickness 0.15)
				)
				(justify left bottom mirror)
			)
		)
		(property "Datasheet" "https://www.bourns.com/docs/product-datasheets/cr.pdf"
			(at 0 0 0)
			(layer "F.Fab")
			(hide yes)
			(effects
				(font
					(size 1.27 1.27)
					(thickness 0.15)
				)
			)
		)
		(property "Author" "Antmicro"
			(at 0 0 0)
			(layer "B.Fab")
			(hide yes)
			(effects
				(font
					(size 1 1)
					(thickness 0.15)
				)
				(justify mirror)
			)
		)
		(property "License" "Apache-2.0"
			(at 0 0 0)
			(layer "B.Fab")
			(hide yes)
			(effects
				(font
					(size 1 1)
					(thickness 0.15)
				)
				(justify mirror)
			)
		)
		(property "MPN" "CR0402-FX-1002GLF"
			(at 0 0 0)
			(layer "B.Fab")
			(hide yes)
			(effects
				(font
					(size 1 1)
					(thickness 0.15)
				)
				(justify mirror)
			)
		)
		(property "Manufacturer" "Bourns"
			(at 0 0 0)
			(layer "B.Fab")
			(hide yes)
			(effects
				(font
					(size 1 1)
					(thickness 0.15)
				)
				(justify mirror)
			)
		)
		(property "Tolerance" "1%"
			(at 0 0 0)
			(layer "B.Fab")
			(hide yes)
			(effects
				(font
					(size 1 1)
					(thickness 0.15)
				)
				(justify mirror)
			)
		)
		(property "Val" "10k"
			(at 0 0 0)
			(layer "B.Fab")
			(hide yes)
			(effects
				(font
					(size 1 1)
					(thickness 0.15)
				)
				(justify mirror)
			)
		)
		(sheetname "/FPGA Config/")
		(sheetfile "fpga-config.kicad_sch")
		(attr smd)
		(fp_rect
			(start -0.93 0.47)
			(end 0.93 -0.47)
			(stroke
				(width 0.05)
				(type solid)
			)
			(fill no)
			(layer "B.CrtYd")
		)
		(fp_rect
			(start -0.5 0.25)
			(end 0.5 -0.25)
			(stroke
				(width 0.15)
				(type solid)
			)
			(fill no)
			(layer "B.Fab")
		)
		(pad "1" smd roundrect
			(at -0.485 0)
			(size 0.59 0.64)
			(layers "B.Cu" "B.Mask" "B.Paste")
			(roundrect_rratio 0.25)
			(net 632 "/FPGA Config/MODE1")
			(pintype "passive")
		)
		(pad "2" smd roundrect
			(at 0.485 0)
			(size 0.59 0.64)
			(layers "B.Cu" "B.Mask" "B.Paste")
			(roundrect_rratio 0.25)
			(net 200 "+3V3")
			(pintype "passive")
		)
	)
	(footprint "antmicro-footprints:TP_SMD_1mm"
		(layer "B.Cu")
		(at 165.25 199.15 180)
		(property "Reference" "TP27"
			(at 0 0.731898 0)
			(layer "B.SilkS")
			(hide yes)
			(effects
				(font
					(size 0.7 0.7)
					(thickness 0.15)
				)
				(justify left bottom mirror)
			)
		)
		(property "Value" "TP_1mm_SMD"
			(at 0 -1.4 0)
			(layer "B.Fab")
			(effects
				(font
					(size 0.7 0.7)
					(thickness 0.15)
				)
				(justify left bottom mirror)
			)
		)
		(property "MPN" ""
			(at 0 0 0)
			(unlocked yes)
			(layer "B.Fab")
			(hide yes)
			(effects
				(font
					(size 1 1)
					(thickness 0.15)
				)
				(justify mirror)
			)
		)
		(property "Manufacturer" ""
			(at 0 0 0)
			(unlocked yes)
			(layer "B.Fab")
			(hide yes)
			(effects
				(font
					(size 1 1)
					(thickness 0.15)
				)
				(justify mirror)
			)
		)
		(property "Author" "Antmicro"
			(at 0 0 0)
			(unlocked yes)
			(layer "B.Fab")
			(hide yes)
			(effects
				(font
					(size 1 1)
					(thickness 0.15)
				)
				(justify mirror)
			)
		)
		(property "License" "Apache-2.0"
			(at 0 0 0)
			(unlocked yes)
			(layer "B.Fab")
			(hide yes)
			(effects
				(font
					(size 1 1)
					(thickness 0.15)
				)
				(justify mirror)
			)
		)
		(sheetname "/Supply/")
		(sheetfile "supply.kicad_sch")
		(attr exclude_from_pos_files)
		(fp_circle
			(center 0 0)
			(end 0.6 0)
			(stroke
				(width 0.05)
				(type default)
			)
			(fill no)
			(layer "B.CrtYd")
		)
		(fp_text user "License: Apache-2.0"
			(at -0.5 -5.2 0)
			(layer "B.Fab")
			(effects
				(font
					(size 0.7 0.7)
					(thickness 0.15)
				)
				(justify left bottom mirror)
			)
		)
		(fp_text user "Author: Antmicro"
			(at -0.5 -4 0)
			(layer "B.Fab")
			(effects
				(font
					(size 0.7 0.7)
					(thickness 0.15)
				)
				(justify left bottom mirror)
			)
		)
		(fp_text user "${REFERENCE}"
			(at -0.5 -2.8 0)
			(layer "B.Fab")
			(effects
				(font
					(size 0.7 0.7)
					(thickness 0.15)
				)
				(justify left bottom mirror)
			)
		)
		(pad "1" smd circle
			(at 0 0 180)
			(size 1 1)
			(layers "B.Cu" "B.Mask")
			(net 227 "+1V0")
			(pinfunction "1")
			(pintype "passive")
		)
	)
	(footprint "antmicro-footprints:C_0402_1005Metric"
		(layer "B.Cu")
		(at 143.375501 172.801 -90)
		(descr "Capacitor SMD 0402 (1005 Metric), square (rectangular) end terminal, IPC_7351 nominal, (Body size source: IPC-SM-782 page 76, https://www.pcb-3d.com/wordpress/wp-content/uploads/ipc-sm-782a_amendment_1_and_2.pdf)")
		(tags "capacitor 0402")
		(property "Reference" "C72"
			(at 0 1.17 90)
			(layer "B.SilkS")
			(hide yes)
			(effects
				(font
					(size 0.7 0.7)
					(thickness 0.15)
				)
				(justify left bottom mirror)
			)
		)
		(property "Value" "C_100n_0402"
			(at 0 -1.169 90)
			(layer "B.Fab")
			(effects
				(font
					(size 0.7 0.7)
					(thickness 0.15)
				)
				(justify left bottom mirror)
			)
		)
		(property "Datasheet" "https://www.murata.com/products/productdetail?partno=GRM155R61H104KE14%23"
			(at 0 0 270)
			(layer "F.Fab")
			(hide yes)
			(effects
				(font
					(size 1.27 1.27)
					(thickness 0.15)
				)
			)
		)
		(property "Author" "Antmicro"
			(at -29.425499 316.176501 0)
			(layer "B.Fab")
			(hide yes)
			(effects
				(font
					(size 1 1)
					(thickness 0.15)
				)
				(justify mirror)
			)
		)
		(property "Dielectric" "X5R"
			(at -29.425499 316.176501 0)
			(layer "B.Fab")
			(hide yes)
			(effects
				(font
					(size 1 1)
					(thickness 0.15)
				)
				(justify mirror)
			)
		)
		(property "License" "Apache-2.0"
			(at -29.425499 316.176501 0)
			(layer "B.Fab")
			(hide yes)
			(effects
				(font
					(size 1 1)
					(thickness 0.15)
				)
				(justify mirror)
			)
		)
		(property "MPN" "GRM155R61H104KE14D"
			(at -29.425499 316.176501 0)
			(layer "B.Fab")
			(hide yes)
			(effects
				(font
					(size 1 1)
					(thickness 0.15)
				)
				(justify mirror)
			)
		)
		(property "Manufacturer" "Murata"
			(at -29.425499 316.176501 0)
			(layer "B.Fab")
			(hide yes)
			(effects
				(font
					(size 1 1)
					(thickness 0.15)
				)
				(justify mirror)
			)
		)
		(property "Val" "100n"
			(at -29.425499 316.176501 0)
			(layer "B.Fab")
			(hide yes)
			(effects
				(font
					(size 1 1)
					(thickness 0.15)
				)
				(justify mirror)
			)
		)
		(property "Voltage" "50V"
			(at -29.425499 316.176501 0)
			(layer "B.Fab")
			(hide yes)
			(effects
				(font
					(size 1 1)
					(thickness 0.15)
				)
				(justify mirror)
			)
		)
		(sheetname "/FPGA power/")
		(sheetfile "fpga-power.kicad_sch")
		(attr smd)
		(fp_rect
			(start -0.9656 0.4572)
			(end 0.9652 -0.4828)
			(stroke
				(width 0.05)
				(type solid)
			)
			(fill no)
			(layer "B.CrtYd")
		)
		(fp_line
			(start -0.5 0.25)
			(end 0.498 0.25)
			(stroke
				(width 0.15)
				(type solid)
			)
			(layer "B.Fab")
		)
		(fp_line
			(start 0.498 0.25)
			(end 0.498 -0.248)
			(stroke
				(width 0.15)
				(type solid)
			)
			(layer "B.Fab")
		)
		(fp_line
			(start -0.5 -0.248)
			(end -0.5 0.25)
			(stroke
				(width 0.15)
				(type solid)
			)
			(layer "B.Fab")
		)
		(fp_line
			(start 0.498 -0.248)
			(end -0.5 -0.248)
			(stroke
				(width 0.15)
				(type solid)
			)
			(layer "B.Fab")
		)
		(pad "1" smd roundrect
			(at -0.5 0 180)
			(size 0.6 0.6)
			(layers "B.Cu" "B.Mask" "B.Paste")
			(roundrect_rratio 0.25)
			(net 1 "GND")
			(pintype "passive")
		)
		(pad "2" smd roundrect
			(at 0.498 0 270)
			(size 0.6 0.6)
			(layers "B.Cu" "B.Mask" "B.Paste")
			(roundrect_rratio 0.25)
			(net 188 "+1V8")
			(pintype "passive")
		)
	)
	(footprint "antmicro-footprints:R_0402_1005Metric"
		(layer "B.Cu")
		(at 146.05 142.4 90)
		(descr "Resistor SMD 0402")
		(tags "resistor SMD 0402")
		(property "Reference" "R31"
			(at 3 0.3 270)
			(layer "B.SilkS")
			(effects
				(font
					(size 0.7 0.7)
					(thickness 0.15)
				)
				(justify left bottom mirror)
			)
		)
		(property "Value" "R_0R_0402"
			(at -1.011843 -1.772047 270)
			(layer "B.Fab")
			(effects
				(font
					(size 0.7 0.7)
					(thickness 0.15)
				)
				(justify left bottom mirror)
			)
		)
		(property "Datasheet" "https://industrial.panasonic.com/cdbs/www-data/pdf/RDA0000/AOA0000C301.pdf"
			(at 0 0 90)
			(layer "F.Fab")
			(hide yes)
			(effects
				(font
					(size 1.27 1.27)
					(thickness 0.15)
				)
			)
		)
		(property "Author" "Antmicro"
			(at 288.45 -3.65 0)
			(layer "B.Fab")
			(hide yes)
			(effects
				(font
					(size 1 1)
					(thickness 0.15)
				)
				(justify mirror)
			)
		)
		(property "Current" "1A"
			(at 288.45 -3.65 0)
			(layer "B.Fab")
			(hide yes)
			(effects
				(font
					(size 1 1)
					(thickness 0.15)
				)
				(justify mirror)
			)
		)
		(property "License" "Apache-2.0"
			(at 288.45 -3.65 0)
			(layer "B.Fab")
			(hide yes)
			(effects
				(font
					(size 1 1)
					(thickness 0.15)
				)
				(justify mirror)
			)
		)
		(property "MPN" "ERJ2GE0R00X"
			(at 288.45 -3.65 0)
			(layer "B.Fab")
			(hide yes)
			(effects
				(font
					(size 1 1)
					(thickness 0.15)
				)
				(justify mirror)
			)
		)
		(property "Manufacturer" "Panasonic"
			(at 288.45 -3.65 0)
			(layer "B.Fab")
			(hide yes)
			(effects
				(font
					(size 1 1)
					(thickness 0.15)
				)
				(justify mirror)
			)
		)
		(property "Tolerance" ""
			(at 288.45 -3.65 0)
			(layer "B.Fab")
			(hide yes)
			(effects
				(font
					(size 1 1)
					(thickness 0.15)
				)
				(justify mirror)
			)
		)
		(property "Val" "0R"
			(at 288.45 -3.65 0)
			(layer "B.Fab")
			(hide yes)
			(effects
				(font
					(size 1 1)
					(thickness 0.15)
				)
				(justify mirror)
			)
		)
		(sheetname "/DDR5 SODIMM/")
		(sheetfile "ddr5-sodimm.kicad_sch")
		(attr smd)
		(fp_rect
			(start -0.93 0.47)
			(end 0.93 -0.47)
			(stroke
				(width 0.05)
				(type solid)
			)
			(fill no)
			(layer "B.CrtYd")
		)
		(fp_rect
			(start -0.5 0.25)
			(end 0.5 -0.25)
			(stroke
				(width 0.15)
				(type solid)
			)
			(fill no)
			(layer "B.Fab")
		)
		(pad "1" smd roundrect
			(at -0.485 0 90)
			(size 0.59 0.64)
			(layers "B.Cu" "B.Mask" "B.Paste")
			(roundrect_rratio 0.25)
			(net 636 "/DDR5 SODIMM/Control.PWR_GOOD")
			(pintype "passive")
		)
		(pad "2" smd roundrect
			(at 0.485 0 90)
			(size 0.59 0.64)
			(layers "B.Cu" "B.Mask" "B.Paste")
			(roundrect_rratio 0.25)
			(net 313 "Net-(J2C-PWR_GOOD)")
			(pintype "passive")
		)
	)
	(footprint "antmicro-footprints:C_0402_1005Metric"
		(layer "B.Cu")
		(at 143.375001 177.8005 90)
		(descr "Capacitor SMD 0402 (1005 Metric), square (rectangular) end terminal, IPC_7351 nominal, (Body size source: IPC-SM-782 page 76, https://www.pcb-3d.com/wordpress/wp-content/uploads/ipc-sm-782a_amendment_1_and_2.pdf)")
		(tags "capacitor 0402")
		(property "Reference" "C88"
			(at 0 1.17 270)
			(layer "B.SilkS")
			(hide yes)
			(effects
				(font
					(size 0.7 0.7)
					(thickness 0.15)
				)
				(justify left bottom mirror)
			)
		)
		(property "Value" "C_100n_0402"
			(at 0 -1.169 270)
			(layer "B.Fab")
			(effects
				(font
					(size 0.7 0.7)
					(thickness 0.15)
				)
				(justify left bottom mirror)
			)
		)
		(property "Datasheet" "https://www.murata.com/products/productdetail?partno=GRM155R61H104KE14%23"
			(at 0 0 90)
			(layer "F.Fab")
			(hide yes)
			(effects
				(font
					(size 1.27 1.27)
					(thickness 0.15)
				)
			)
		)
		(property "Author" "Antmicro"
			(at 321.175501 34.425499 0)
			(layer "B.Fab")
			(hide yes)
			(effects
				(font
					(size 1 1)
					(thickness 0.15)
				)
				(justify mirror)
			)
		)
		(property "Dielectric" "X5R"
			(at 321.175501 34.425499 0)
			(layer "B.Fab")
			(hide yes)
			(effects
				(font
					(size 1 1)
					(thickness 0.15)
				)
				(justify mirror)
			)
		)
		(property "License" "Apache-2.0"
			(at 321.175501 34.425499 0)
			(layer "B.Fab")
			(hide yes)
			(effects
				(font
					(size 1 1)
					(thickness 0.15)
				)
				(justify mirror)
			)
		)
		(property "MPN" "GRM155R61H104KE14D"
			(at 321.175501 34.425499 0)
			(layer "B.Fab")
			(hide yes)
			(effects
				(font
					(size 1 1)
					(thickness 0.15)
				)
				(justify mirror)
			)
		)
		(property "Manufacturer" "Murata"
			(at 321.175501 34.425499 0)
			(layer "B.Fab")
			(hide yes)
			(effects
				(font
					(size 1 1)
					(thickness 0.15)
				)
				(justify mirror)
			)
		)
		(property "Val" "100n"
			(at 321.175501 34.425499 0)
			(layer "B.Fab")
			(hide yes)
			(effects
				(font
					(size 1 1)
					(thickness 0.15)
				)
				(justify mirror)
			)
		)
		(property "Voltage" "50V"
			(at 321.175501 34.425499 0)
			(layer "B.Fab")
			(hide yes)
			(effects
				(font
					(size 1 1)
					(thickness 0.15)
				)
				(justify mirror)
			)
		)
		(sheetname "/FPGA power/")
		(sheetfile "fpga-power.kicad_sch")
		(attr smd)
		(fp_rect
			(start -0.9656 0.4572)
			(end 0.9652 -0.4828)
			(stroke
				(width 0.05)
				(type solid)
			)
			(fill no)
			(layer "B.CrtYd")
		)
		(fp_line
			(start 0.498 -0.248)
			(end -0.5 -0.248)
			(stroke
				(width 0.15)
				(type solid)
			)
			(layer "B.Fab")
		)
		(fp_line
			(start -0.5 -0.248)
			(end -0.5 0.25)
			(stroke
				(width 0.15)
				(type solid)
			)
			(layer "B.Fab")
		)
		(fp_line
			(start 0.498 0.25)
			(end 0.498 -0.248)
			(stroke
				(width 0.15)
				(type solid)
			)
			(layer "B.Fab")
		)
		(fp_line
			(start -0.5 0.25)
			(end 0.498 0.25)
			(stroke
				(width 0.15)
				(type solid)
			)
			(layer "B.Fab")
		)
		(pad "1" smd roundrect
			(at -0.5 0)
			(size 0.6 0.6)
			(layers "B.Cu" "B.Mask" "B.Paste")
			(roundrect_rratio 0.25)
			(net 1 "GND")
			(pintype "passive")
		)
		(pad "2" smd roundrect
			(at 0.498 0 90)
			(size 0.6 0.6)
			(layers "B.Cu" "B.Mask" "B.Paste")
			(roundrect_rratio 0.25)
			(net 227 "+1V0")
			(pintype "passive")
		)
	)
	(footprint "antmicro-footprints:R_0402_1005Metric"
		(layer "B.Cu")
		(at 125 201.825 180)
		(descr "Resistor SMD 0402")
		(tags "resistor SMD 0402")
		(property "Reference" "R192"
			(at 1.1 -0.275 0)
			(layer "B.SilkS")
			(effects
				(font
					(size 0.7 0.7)
					(thickness 0.15)
				)
				(justify left bottom mirror)
			)
		)
		(property "Value" "R_10k_0402"
			(at -1.011843 -1.772047 0)
			(layer "B.Fab")
			(effects
				(font
					(size 0.7 0.7)
					(thickness 0.15)
				)
				(justify left bottom mirror)
			)
		)
		(property "Datasheet" "https://www.bourns.com/docs/product-datasheets/cr.pdf"
			(at 0 0 180)
			(layer "F.Fab")
			(hide yes)
			(effects
				(font
					(size 1.27 1.27)
					(thickness 0.15)
				)
			)
		)
		(property "Author" "Antmicro"
			(at 250 403.65 0)
			(layer "B.Fab")
			(hide yes)
			(effects
				(font
					(size 1 1)
					(thickness 0.15)
				)
				(justify mirror)
			)
		)
		(property "License" "Apache-2.0"
			(at 250 403.65 0)
			(layer "B.Fab")
			(hide yes)
			(effects
				(font
					(size 1 1)
					(thickness 0.15)
				)
				(justify mirror)
			)
		)
		(property "MPN" "CR0402-FX-1002GLF"
			(at 250 403.65 0)
			(layer "B.Fab")
			(hide yes)
			(effects
				(font
					(size 1 1)
					(thickness 0.15)
				)
				(justify mirror)
			)
		)
		(property "Manufacturer" "Bourns"
			(at 250 403.65 0)
			(layer "B.Fab")
			(hide yes)
			(effects
				(font
					(size 1 1)
					(thickness 0.15)
				)
				(justify mirror)
			)
		)
		(property "Tolerance" "1%"
			(at 250 403.65 0)
			(layer "B.Fab")
			(hide yes)
			(effects
				(font
					(size 1 1)
					(thickness 0.15)
				)
				(justify mirror)
			)
		)
		(property "Val" "10k"
			(at 250 403.65 0)
			(layer "B.Fab")
			(hide yes)
			(effects
				(font
					(size 1 1)
					(thickness 0.15)
				)
				(justify mirror)
			)
		)
		(sheetname "/PCIe connector/")
		(sheetfile "pcie-connector.kicad_sch")
		(attr exclude_from_pos_files exclude_from_bom dnp)
		(fp_rect
			(start -0.93 0.47)
			(end 0.93 -0.47)
			(stroke
				(width 0.05)
				(type solid)
			)
			(fill no)
			(layer "B.CrtYd")
		)
		(fp_rect
			(start -0.5 0.25)
			(end 0.5 -0.25)
			(stroke
				(width 0.15)
				(type solid)
			)
			(fill no)
			(layer "B.Fab")
		)
		(pad "1" smd roundrect
			(at -0.485 0 180)
			(size 0.59 0.64)
			(layers "B.Cu" "B.Mask" "B.Paste")
			(roundrect_rratio 0.25)
			(net 1 "GND")
			(pintype "passive")
		)
		(pad "2" smd roundrect
			(at 0.485 0 180)
			(size 0.59 0.64)
			(layers "B.Cu" "B.Mask" "B.Paste")
			(roundrect_rratio 0.25)
			(net 135 "PCIE.PWRGD")
			(pintype "passive")
		)
	)
	(footprint "antmicro-footprints:TP_SMD_1mm"
		(layer "B.Cu")
		(at 200.6 151.8 90)
		(property "Reference" "TP40"
			(at 0.5 -0.3 90)
			(layer "B.SilkS")
			(effects
				(font
					(size 0.7 0.7)
					(thickness 0.15)
				)
				(justify right top mirror)
			)
		)
		(property "Value" "TP_1mm_SMD"
			(at 0 -1.4 90)
			(layer "B.Fab")
			(effects
				(font
					(size 0.7 0.7)
					(thickness 0.15)
				)
				(justify right top mirror)
			)
		)
		(property "MPN" ""
			(at 0 0 270)
			(unlocked yes)
			(layer "B.Fab")
			(hide yes)
			(effects
				(font
					(size 1 1)
					(thickness 0.15)
				)
				(justify mirror)
			)
		)
		(property "Manufacturer" ""
			(at 0 0 270)
			(unlocked yes)
			(layer "B.Fab")
			(hide yes)
			(effects
				(font
					(size 1 1)
					(thickness 0.15)
				)
				(justify mirror)
			)
		)
		(property "Author" "Antmicro"
			(at 0 0 270)
			(unlocked yes)
			(layer "B.Fab")
			(hide yes)
			(effects
				(font
					(size 1 1)
					(thickness 0.15)
				)
				(justify mirror)
			)
		)
		(property "License" "Apache-2.0"
			(at 0 0 270)
			(unlocked yes)
			(layer "B.Fab")
			(hide yes)
			(effects
				(font
					(size 1 1)
					(thickness 0.15)
				)
				(justify mirror)
			)
		)
		(sheetname "/I^{2}C/")
		(sheetfile "i2c.kicad_sch")
		(attr exclude_from_pos_files)
		(fp_circle
			(center 0 0)
			(end 0.6 0)
			(stroke
				(width 0.05)
				(type default)
			)
			(fill no)
			(layer "B.CrtYd")
		)
		(fp_text user "${REFERENCE}"
			(at -0.5 -2.8 90)
			(layer "B.Fab")
			(effects
				(font
					(size 0.7 0.7)
					(thickness 0.15)
				)
				(justify right top mirror)
			)
		)
		(fp_text user "Author: Antmicro"
			(at -0.5 -4 90)
			(layer "B.Fab")
			(effects
				(font
					(size 0.7 0.7)
					(thickness 0.15)
				)
				(justify right top mirror)
			)
		)
		(fp_text user "License: Apache-2.0"
			(at -0.5 -5.2 90)
			(layer "B.Fab")
			(effects
				(font
					(size 0.7 0.7)
					(thickness 0.15)
				)
				(justify right top mirror)
			)
		)
		(pad "1" smd circle
			(at 0 0 90)
			(size 1 1)
			(layers "B.Cu" "B.Mask")
			(net 686 "IN1")
			(pinfunction "1")
			(pintype "passive")
		)
	)
	(footprint "antmicro-footprints:C_0402_1005Metric"
		(layer "B.Cu")
		(at 157.4 142.4 -90)
		(descr "Capacitor SMD 0402")
		(tags "capacitor SMD 0402")
		(property "Reference" "C9"
			(at 0 0.699 90)
			(layer "B.SilkS")
			(hide yes)
			(effects
				(font
					(size 0.7 0.7)
					(thickness 0.15)
				)
				(justify left bottom mirror)
			)
		)
		(property "Value" "C_100n_0402"
			(at -1.022927 -2.155213 90)
			(layer "B.Fab")
			(effects
				(font
					(size 0.7 0.7)
					(thickness 0.15)
				)
				(justify left bottom mirror)
			)
		)
		(property "Datasheet" "https://www.murata.com/products/productdetail?partno=GRM155R61H104KE14%23"
			(at 0 0 270)
			(layer "F.Fab")
			(hide yes)
			(effects
				(font
					(size 1.27 1.27)
					(thickness 0.15)
				)
			)
		)
		(property "Author" "Antmicro"
			(at 15 299.8 0)
			(layer "B.Fab")
			(hide yes)
			(effects
				(font
					(size 1 1)
					(thickness 0.15)
				)
				(justify mirror)
			)
		)
		(property "Dielectric" "X5R"
			(at 15 299.8 0)
			(layer "B.Fab")
			(hide yes)
			(effects
				(font
					(size 1 1)
					(thickness 0.15)
				)
				(justify mirror)
			)
		)
		(property "License" "Apache-2.0"
			(at 15 299.8 0)
			(layer "B.Fab")
			(hide yes)
			(effects
				(font
					(size 1 1)
					(thickness 0.15)
				)
				(justify mirror)
			)
		)
		(property "MPN" "GRM155R61H104KE14D"
			(at 15 299.8 0)
			(layer "B.Fab")
			(hide yes)
			(effects
				(font
					(size 1 1)
					(thickness 0.15)
				)
				(justify mirror)
			)
		)
		(property "Manufacturer" "Murata"
			(at 15 299.8 0)
			(layer "B.Fab")
			(hide yes)
			(effects
				(font
					(size 1 1)
					(thickness 0.15)
				)
				(justify mirror)
			)
		)
		(property "Val" "100n"
			(at 15 299.8 0)
			(layer "B.Fab")
			(hide yes)
			(effects
				(font
					(size 1 1)
					(thickness 0.15)
				)
				(justify mirror)
			)
		)
		(property "Voltage" "50V"
			(at 15 299.8 0)
			(layer "B.Fab")
			(hide yes)
			(effects
				(font
					(size 1 1)
					(thickness 0.15)
				)
				(justify mirror)
			)
		)
		(sheetname "/DDR5 SODIMM/")
		(sheetfile "ddr5-sodimm.kicad_sch")
		(attr smd)
		(fp_rect
			(start -0.9659 0.481258)
			(end 0.9649 -0.458742)
			(stroke
				(width 0.05)
				(type solid)
			)
			(fill no)
			(layer "B.CrtYd")
		)
		(fp_line
			(start -0.499 0.25)
			(end 0.499 0.25)
			(stroke
				(width 0.15)
				(type solid)
			)
			(layer "B.Fab")
		)
		(fp_line
			(start 0.499 0.25)
			(end 0.499 -0.248)
			(stroke
				(width 0.15)
				(type solid)
			)
			(layer "B.Fab")
		)
		(fp_line
			(start -0.499 -0.248)
			(end -0.499 0.25)
			(stroke
				(width 0.15)
				(type solid)
			)
			(layer "B.Fab")
		)
		(fp_line
			(start 0.499 -0.248)
			(end -0.499 -0.248)
			(stroke
				(width 0.15)
				(type solid)
			)
			(layer "B.Fab")
		)
		(pad "1" smd roundrect
			(at -0.484 0 270)
			(size 0.59 0.64)
			(layers "B.Cu" "B.Mask" "B.Paste")
			(roundrect_rratio 0.25)
			(net 1 "GND")
			(pintype "passive")
		)
		(pad "2" smd roundrect
			(at 0.484 0 270)
			(size 0.59 0.64)
			(layers "B.Cu" "B.Mask" "B.Paste")
			(roundrect_rratio 0.25)
			(net 206 "+1V1")
			(pintype "passive")
		)
	)
	(footprint "antmicro-footprints:C_0402_1005Metric"
		(layer "B.Cu")
		(at 146.375001 183.8005 -90)
		(descr "Capacitor SMD 0402 (1005 Metric), square (rectangular) end terminal, IPC_7351 nominal, (Body size source: IPC-SM-782 page 76, https://www.pcb-3d.com/wordpress/wp-content/uploads/ipc-sm-782a_amendment_1_and_2.pdf)")
		(tags "capacitor 0402")
		(property "Reference" "C101"
			(at 0 1.17 90)
			(layer "B.SilkS")
			(hide yes)
			(effects
				(font
					(size 0.7 0.7)
					(thickness 0.15)
				)
				(justify left bottom mirror)
			)
		)
		(property "Value" "C_100n_0402"
			(at 0 -1.169 90)
			(layer "B.Fab")
			(effects
				(font
					(size 0.7 0.7)
					(thickness 0.15)
				)
				(justify left bottom mirror)
			)
		)
		(property "Datasheet" "https://www.murata.com/products/productdetail?partno=GRM155R61H104KE14%23"
			(at 0 0 270)
			(layer "F.Fab")
			(hide yes)
			(effects
				(font
					(size 1.27 1.27)
					(thickness 0.15)
				)
			)
		)
		(property "Author" "Antmicro"
			(at -37.425499 330.175501 0)
			(layer "B.Fab")
			(hide yes)
			(effects
				(font
					(size 1 1)
					(thickness 0.15)
				)
				(justify mirror)
			)
		)
		(property "Dielectric" "X5R"
			(at -37.425499 330.175501 0)
			(layer "B.Fab")
			(hide yes)
			(effects
				(font
					(size 1 1)
					(thickness 0.15)
				)
				(justify mirror)
			)
		)
		(property "License" "Apache-2.0"
			(at -37.425499 330.175501 0)
			(layer "B.Fab")
			(hide yes)
			(effects
				(font
					(size 1 1)
					(thickness 0.15)
				)
				(justify mirror)
			)
		)
		(property "MPN" "GRM155R61H104KE14D"
			(at -37.425499 330.175501 0)
			(layer "B.Fab")
			(hide yes)
			(effects
				(font
					(size 1 1)
					(thickness 0.15)
				)
				(justify mirror)
			)
		)
		(property "Manufacturer" "Murata"
			(at -37.425499 330.175501 0)
			(layer "B.Fab")
			(hide yes)
			(effects
				(font
					(size 1 1)
					(thickness 0.15)
				)
				(justify mirror)
			)
		)
		(property "Val" "100n"
			(at -37.425499 330.175501 0)
			(layer "B.Fab")
			(hide yes)
			(effects
				(font
					(size 1 1)
					(thickness 0.15)
				)
				(justify mirror)
			)
		)
		(property "Voltage" "50V"
			(at -37.425499 330.175501 0)
			(layer "B.Fab")
			(hide yes)
			(effects
				(font
					(size 1 1)
					(thickness 0.15)
				)
				(justify mirror)
			)
		)
		(sheetname "/FPGA power/")
		(sheetfile "fpga-power.kicad_sch")
		(attr smd)
		(fp_rect
			(start -0.9656 0.4572)
			(end 0.9652 -0.4828)
			(stroke
				(width 0.05)
				(type solid)
			)
			(fill no)
			(layer "B.CrtYd")
		)
		(fp_line
			(start -0.5 0.25)
			(end 0.498 0.25)
			(stroke
				(width 0.15)
				(type solid)
			)
			(layer "B.Fab")
		)
		(fp_line
			(start 0.498 0.25)
			(end 0.498 -0.248)
			(stroke
				(width 0.15)
				(type solid)
			)
			(layer "B.Fab")
		)
		(fp_line
			(start -0.5 -0.248)
			(end -0.5 0.25)
			(stroke
				(width 0.15)
				(type solid)
			)
			(layer "B.Fab")
		)
		(fp_line
			(start 0.498 -0.248)
			(end -0.5 -0.248)
			(stroke
				(width 0.15)
				(type solid)
			)
			(layer "B.Fab")
		)
		(pad "1" smd roundrect
			(at -0.5 0 180)
			(size 0.6 0.6)
			(layers "B.Cu" "B.Mask" "B.Paste")
			(roundrect_rratio 0.25)
			(net 1 "GND")
			(pintype "passive")
		)
		(pad "2" smd roundrect
			(at 0.498 0 270)
			(size 0.6 0.6)
			(layers "B.Cu" "B.Mask" "B.Paste")
			(roundrect_rratio 0.25)
			(net 187 "+1V0_MGTAVCC")
			(pintype "passive")
		)
	)
	(footprint "antmicro-footprints:R_0402_1005Metric"
		(layer "B.Cu")
		(at 196.7 171.725)
		(descr "Resistor SMD 0402")
		(tags "resistor SMD 0402")
		(property "Reference" "R156"
			(at 3.8 0.525 180)
			(layer "B.SilkS")
			(effects
				(font
					(size 0.7 0.7)
					(thickness 0.15)
				)
				(justify left bottom mirror)
			)
		)
		(property "Value" "R_0R_0402"
			(at -1.011843 -1.772047 180)
			(layer "B.Fab")
			(effects
				(font
					(size 0.7 0.7)
					(thickness 0.15)
				)
				(justify left bottom mirror)
			)
		)
		(property "Datasheet" "https://industrial.panasonic.com/cdbs/www-data/pdf/RDA0000/AOA0000C301.pdf"
			(at 0 0 0)
			(layer "F.Fab")
			(hide yes)
			(effects
				(font
					(size 1.27 1.27)
					(thickness 0.15)
				)
			)
		)
		(property "Author" "Antmicro"
			(at 0 0 0)
			(layer "B.Fab")
			(hide yes)
			(effects
				(font
					(size 1 1)
					(thickness 0.15)
				)
				(justify mirror)
			)
		)
		(property "Current" "1A"
			(at 0 0 0)
			(layer "B.Fab")
			(hide yes)
			(effects
				(font
					(size 1 1)
					(thickness 0.15)
				)
				(justify mirror)
			)
		)
		(property "License" "Apache-2.0"
			(at 0 0 0)
			(layer "B.Fab")
			(hide yes)
			(effects
				(font
					(size 1 1)
					(thickness 0.15)
				)
				(justify mirror)
			)
		)
		(property "MPN" "ERJ2GE0R00X"
			(at 0 0 0)
			(layer "B.Fab")
			(hide yes)
			(effects
				(font
					(size 1 1)
					(thickness 0.15)
				)
				(justify mirror)
			)
		)
		(property "Manufacturer" "Panasonic"
			(at 0 0 0)
			(layer "B.Fab")
			(hide yes)
			(effects
				(font
					(size 1 1)
					(thickness 0.15)
				)
				(justify mirror)
			)
		)
		(property "Tolerance" ""
			(at 0 0 0)
			(layer "B.Fab")
			(hide yes)
			(effects
				(font
					(size 1 1)
					(thickness 0.15)
				)
				(justify mirror)
			)
		)
		(property "Val" "0R"
			(at 0 0 0)
			(layer "B.Fab")
			(hide yes)
			(effects
				(font
					(size 1 1)
					(thickness 0.15)
				)
				(justify mirror)
			)
		)
		(sheetname "/Supply/")
		(sheetfile "supply.kicad_sch")
		(attr exclude_from_pos_files exclude_from_bom dnp)
		(fp_rect
			(start -0.93 0.47)
			(end 0.93 -0.47)
			(stroke
				(width 0.05)
				(type solid)
			)
			(fill no)
			(layer "B.CrtYd")
		)
		(fp_rect
			(start -0.5 0.25)
			(end 0.5 -0.25)
			(stroke
				(width 0.15)
				(type solid)
			)
			(fill no)
			(layer "B.Fab")
		)
		(pad "1" smd roundrect
			(at -0.485 0)
			(size 0.59 0.64)
			(layers "B.Cu" "B.Mask" "B.Paste")
			(roundrect_rratio 0.25)
			(net 1 "GND")
			(pintype "passive")
		)
		(pad "2" smd roundrect
			(at 0.485 0)
			(size 0.59 0.64)
			(layers "B.Cu" "B.Mask" "B.Paste")
			(roundrect_rratio 0.25)
			(net 209 "/Supply/FB5")
			(pintype "passive")
		)
	)
	(footprint "antmicro-footprints:R_0402_1005Metric"
		(layer "B.Cu")
		(at 137.777001 159.5755)
		(descr "Resistor SMD 0402")
		(tags "resistor SMD 0402")
		(property "Reference" "R130"
			(at -1.122484 0.772697 180)
			(layer "B.SilkS")
			(hide yes)
			(effects
				(font
					(size 0.7 0.7)
					(thickness 0.15)
				)
				(justify left bottom mirror)
			)
		)
		(property "Value" "R_1k_0402"
			(at -1.011843 -1.772047 180)
			(layer "B.Fab")
			(effects
				(font
					(size 0.7 0.7)
					(thickness 0.15)
				)
				(justify left bottom mirror)
			)
		)
		(property "Datasheet" "https://www.bourns.com/docs/product-datasheets/cr.pdf"
			(at 0 0 0)
			(layer "F.Fab")
			(hide yes)
			(effects
				(font
					(size 1.27 1.27)
					(thickness 0.15)
				)
			)
		)
		(property "Author" "Antmicro"
			(at 0 0 0)
			(layer "B.Fab")
			(hide yes)
			(effects
				(font
					(size 1 1)
					(thickness 0.15)
				)
				(justify mirror)
			)
		)
		(property "License" "Apache-2.0"
			(at 0 0 0)
			(layer "B.Fab")
			(hide yes)
			(effects
				(font
					(size 1 1)
					(thickness 0.15)
				)
				(justify mirror)
			)
		)
		(property "MPN" "CR0402-FX-1001GLF"
			(at 0 0 0)
			(layer "B.Fab")
			(hide yes)
			(effects
				(font
					(size 1 1)
					(thickness 0.15)
				)
				(justify mirror)
			)
		)
		(property "Manufacturer" "Bourns"
			(at 0 0 0)
			(layer "B.Fab")
			(hide yes)
			(effects
				(font
					(size 1 1)
					(thickness 0.15)
				)
				(justify mirror)
			)
		)
		(property "Tolerance" "1%"
			(at 0 0 0)
			(layer "B.Fab")
			(hide yes)
			(effects
				(font
					(size 1 1)
					(thickness 0.15)
				)
				(justify mirror)
			)
		)
		(property "Val" "1k"
			(at 0 0 0)
			(layer "B.Fab")
			(hide yes)
			(effects
				(font
					(size 1 1)
					(thickness 0.15)
				)
				(justify mirror)
			)
		)
		(sheetname "/FPGA banks HP/")
		(sheetfile "fpga-banks-32-34.kicad_sch")
		(attr smd)
		(fp_rect
			(start -0.93 0.47)
			(end 0.93 -0.47)
			(stroke
				(width 0.05)
				(type solid)
			)
			(fill no)
			(layer "B.CrtYd")
		)
		(fp_rect
			(start -0.5 0.25)
			(end 0.5 -0.25)
			(stroke
				(width 0.15)
				(type solid)
			)
			(fill no)
			(layer "B.Fab")
		)
		(pad "1" smd roundrect
			(at -0.485 0)
			(size 0.59 0.64)
			(layers "B.Cu" "B.Mask" "B.Paste")
			(roundrect_rratio 0.25)
			(net 1 "GND")
			(pintype "passive")
		)
		(pad "2" smd roundrect
			(at 0.485 0)
			(size 0.59 0.64)
			(layers "B.Cu" "B.Mask" "B.Paste")
			(roundrect_rratio 0.25)
			(net 379 "Net-(R129-Pad1)")
			(pintype "passive")
		)
	)
	(footprint "antmicro-footprints:TP_SMD_1mm"
		(layer "B.Cu")
		(at 172.3 184.4 180)
		(property "Reference" "TP67"
			(at 0.5 -0.4 0)
			(layer "B.SilkS")
			(effects
				(font
					(size 0.7 0.7)
					(thickness 0.15)
				)
				(justify left bottom mirror)
			)
		)
		(property "Value" "TP_1mm_SMD"
			(at 0 -1.4 0)
			(layer "B.Fab")
			(effects
				(font
					(size 0.7 0.7)
					(thickness 0.15)
				)
				(justify left bottom mirror)
			)
		)
		(property "MPN" ""
			(at 0 0 0)
			(unlocked yes)
			(layer "B.Fab")
			(hide yes)
			(effects
				(font
					(size 1 1)
					(thickness 0.15)
				)
				(justify mirror)
			)
		)
		(property "Manufacturer" ""
			(at 0 0 0)
			(unlocked yes)
			(layer "B.Fab")
			(hide yes)
			(effects
				(font
					(size 1 1)
					(thickness 0.15)
				)
				(justify mirror)
			)
		)
		(property "Author" "Antmicro"
			(at 0 0 0)
			(unlocked yes)
			(layer "B.Fab")
			(hide yes)
			(effects
				(font
					(size 1 1)
					(thickness 0.15)
				)
				(justify mirror)
			)
		)
		(property "License" "Apache-2.0"
			(at 0 0 0)
			(unlocked yes)
			(layer "B.Fab")
			(hide yes)
			(effects
				(font
					(size 1 1)
					(thickness 0.15)
				)
				(justify mirror)
			)
		)
		(sheetname "/I^{2}C/")
		(sheetfile "i2c.kicad_sch")
		(attr exclude_from_pos_files)
		(fp_circle
			(center 0 0)
			(end 0.6 0)
			(stroke
				(width 0.05)
				(type default)
			)
			(fill no)
			(layer "B.CrtYd")
		)
		(fp_text user "${REFERENCE}"
			(at -0.5 -2.8 0)
			(layer "B.Fab")
			(effects
				(font
					(size 0.7 0.7)
					(thickness 0.15)
				)
				(justify left bottom mirror)
			)
		)
		(fp_text user "Author: Antmicro"
			(at -0.5 -4 0)
			(layer "B.Fab")
			(effects
				(font
					(size 0.7 0.7)
					(thickness 0.15)
				)
				(justify left bottom mirror)
			)
		)
		(fp_text user "License: Apache-2.0"
			(at -0.5 -5.2 0)
			(layer "B.Fab")
			(effects
				(font
					(size 0.7 0.7)
					(thickness 0.15)
				)
				(justify left bottom mirror)
			)
		)
		(pad "1" smd circle
			(at 0 0 180)
			(size 1 1)
			(layers "B.Cu" "B.Mask")
			(net 760 "Net-(D18-A)")
			(pinfunction "1")
			(pintype "passive")
		)
	)
	(footprint "antmicro-footprints:C_0402_1005Metric"
		(layer "B.Cu")
		(at 147.875501 167.301)
		(descr "Capacitor SMD 0402 (1005 Metric), square (rectangular) end terminal, IPC_7351 nominal, (Body size source: IPC-SM-782 page 76, https://www.pcb-3d.com/wordpress/wp-content/uploads/ipc-sm-782a_amendment_1_and_2.pdf)")
		(tags "capacitor 0402")
		(property "Reference" "C94"
			(at 0 1.17 180)
			(layer "B.SilkS")
			(hide yes)
			(effects
				(font
					(size 0.7 0.7)
					(thickness 0.15)
				)
				(justify left bottom mirror)
			)
		)
		(property "Value" "C_100n_0402"
			(at 0 -1.169 180)
			(layer "B.Fab")
			(effects
				(font
					(size 0.7 0.7)
					(thickness 0.15)
				)
				(justify left bottom mirror)
			)
		)
		(property "Datasheet" "https://www.murata.com/products/productdetail?partno=GRM155R61H104KE14%23"
			(at 0 0 0)
			(layer "F.Fab")
			(hide yes)
			(effects
				(font
					(size 1.27 1.27)
					(thickness 0.15)
				)
			)
		)
		(property "Author" "Antmicro"
			(at 0 0 0)
			(layer "B.Fab")
			(hide yes)
			(effects
				(font
					(size 1 1)
					(thickness 0.15)
				)
				(justify mirror)
			)
		)
		(property "Dielectric" "X5R"
			(at 0 0 0)
			(layer "B.Fab")
			(hide yes)
			(effects
				(font
					(size 1 1)
					(thickness 0.15)
				)
				(justify mirror)
			)
		)
		(property "License" "Apache-2.0"
			(at 0 0 0)
			(layer "B.Fab")
			(hide yes)
			(effects
				(font
					(size 1 1)
					(thickness 0.15)
				)
				(justify mirror)
			)
		)
		(property "MPN" "GRM155R61H104KE14D"
			(at 0 0 0)
			(layer "B.Fab")
			(hide yes)
			(effects
				(font
					(size 1 1)
					(thickness 0.15)
				)
				(justify mirror)
			)
		)
		(property "Manufacturer" "Murata"
			(at 0 0 0)
			(layer "B.Fab")
			(hide yes)
			(effects
				(font
					(size 1 1)
					(thickness 0.15)
				)
				(justify mirror)
			)
		)
		(property "Val" "100n"
			(at 0 0 0)
			(layer "B.Fab")
			(hide yes)
			(effects
				(font
					(size 1 1)
					(thickness 0.15)
				)
				(justify mirror)
			)
		)
		(property "Voltage" "50V"
			(at 0 0 0)
			(layer "B.Fab")
			(hide yes)
			(effects
				(font
					(size 1 1)
					(thickness 0.15)
				)
				(justify mirror)
			)
		)
		(sheetname "/FPGA power/")
		(sheetfile "fpga-power.kicad_sch")
		(attr smd)
		(fp_rect
			(start -0.9656 0.4572)
			(end 0.9652 -0.4828)
			(stroke
				(width 0.05)
				(type solid)
			)
			(fill no)
			(layer "B.CrtYd")
		)
		(fp_line
			(start -0.5 -0.248)
			(end -0.5 0.25)
			(stroke
				(width 0.15)
				(type solid)
			)
			(layer "B.Fab")
		)
		(fp_line
			(start -0.5 0.25)
			(end 0.498 0.25)
			(stroke
				(width 0.15)
				(type solid)
			)
			(layer "B.Fab")
		)
		(fp_line
			(start 0.498 -0.248)
			(end -0.5 -0.248)
			(stroke
				(width 0.15)
				(type solid)
			)
			(layer "B.Fab")
		)
		(fp_line
			(start 0.498 0.25)
			(end 0.498 -0.248)
			(stroke
				(width 0.15)
				(type solid)
			)
			(layer "B.Fab")
		)
		(pad "1" smd roundrect
			(at -0.5 0 270)
			(size 0.6 0.6)
			(layers "B.Cu" "B.Mask" "B.Paste")
			(roundrect_rratio 0.25)
			(net 1 "GND")
			(pintype "passive")
		)
		(pad "2" smd roundrect
			(at 0.498 0)
			(size 0.6 0.6)
			(layers "B.Cu" "B.Mask" "B.Paste")
			(roundrect_rratio 0.25)
			(net 206 "+1V1")
			(pintype "passive")
		)
	)
	(footprint "antmicro-footprints:C_0603_1608Metric"
		(layer "B.Cu")
		(at 117.150501 204.176 180)
		(descr "Capacitor SMD 0603")
		(tags "capacitor 0603")
		(property "Reference" "C224"
			(at -1.42757 1.000252 0)
			(layer "B.SilkS")
			(hide yes)
			(effects
				(font
					(size 0.7 0.7)
					(thickness 0.15)
				)
				(justify left bottom mirror)
			)
		)
		(property "Value" "C_10u_25V_0603"
			(at -1.42757 -1.770288 0)
			(layer "B.Fab")
			(effects
				(font
					(size 0.7 0.7)
					(thickness 0.15)
				)
				(justify left bottom mirror)
			)
		)
		(property "Datasheet" "https://product.tdk.com/en/search/capacitor/ceramic/mlcc/info?part_no=C1608X5R1E106M080AC"
			(at 0 0 180)
			(layer "F.Fab")
			(hide yes)
			(effects
				(font
					(size 1.27 1.27)
					(thickness 0.15)
				)
			)
		)
		(property "Author" "Antmicro"
			(at 234.301002 408.352 0)
			(layer "B.Fab")
			(hide yes)
			(effects
				(font
					(size 1 1)
					(thickness 0.15)
				)
				(justify mirror)
			)
		)
		(property "Dielectric" ""
			(at 234.301002 408.352 0)
			(layer "B.Fab")
			(hide yes)
			(effects
				(font
					(size 1 1)
					(thickness 0.15)
				)
				(justify mirror)
			)
		)
		(property "License" "Apache-2.0"
			(at 234.301002 408.352 0)
			(layer "B.Fab")
			(hide yes)
			(effects
				(font
					(size 1 1)
					(thickness 0.15)
				)
				(justify mirror)
			)
		)
		(property "MPN" "C1608X5R1E106M080AC"
			(at 234.301002 408.352 0)
			(layer "B.Fab")
			(hide yes)
			(effects
				(font
					(size 1 1)
					(thickness 0.15)
				)
				(justify mirror)
			)
		)
		(property "Manufacturer" "TDK"
			(at 234.301002 408.352 0)
			(layer "B.Fab")
			(hide yes)
			(effects
				(font
					(size 1 1)
					(thickness 0.15)
				)
				(justify mirror)
			)
		)
		(property "Val" "10u/25V"
			(at 234.301002 408.352 0)
			(layer "B.Fab")
			(hide yes)
			(effects
				(font
					(size 1 1)
					(thickness 0.15)
				)
				(justify mirror)
			)
		)
		(property "Voltage" ""
			(at 234.301002 408.352 0)
			(layer "B.Fab")
			(hide yes)
			(effects
				(font
					(size 1 1)
					(thickness 0.15)
				)
				(justify mirror)
			)
		)
		(sheetname "/PCIe connector/")
		(sheetfile "pcie-connector.kicad_sch")
		(attr smd)
		(fp_line
			(start -0.3 0.3)
			(end 0.3 0.3)
			(stroke
				(width 0.15)
				(type solid)
			)
			(layer "B.SilkS")
		)
		(fp_line
			(start -0.3 -0.3)
			(end 0.3 -0.3)
			(stroke
				(width 0.15)
				(type solid)
			)
			(layer "B.SilkS")
		)
		(fp_rect
			(start -1.24 0.7)
			(end 1.24 -0.7)
			(stroke
				(width 0.05)
				(type solid)
			)
			(fill no)
			(layer "B.CrtYd")
		)
		(fp_rect
			(start -0.8 0.4)
			(end 0.8 -0.4)
			(stroke
				(width 0.15)
				(type solid)
			)
			(fill no)
			(layer "B.Fab")
		)
		(pad "1" smd roundrect
			(at -0.7 0 180)
			(size 0.6 0.8)
			(layers "B.Cu" "B.Mask" "B.Paste")
			(roundrect_rratio 0.2)
			(net 1 "GND")
			(pintype "passive")
		)
		(pad "2" smd roundrect
			(at 0.7 0 180)
			(size 0.6 0.8)
			(layers "B.Cu" "B.Mask" "B.Paste")
			(roundrect_rratio 0.2)
			(net 11 "+12V")
			(pintype "passive")
		)
	)
	(footprint "antmicro-footprints:C_0402_1005Metric"
		(layer "B.Cu")
		(at 149.377001 181.8005 90)
		(descr "Capacitor SMD 0402 (1005 Metric), square (rectangular) end terminal, IPC_7351 nominal, (Body size source: IPC-SM-782 page 76, https://www.pcb-3d.com/wordpress/wp-content/uploads/ipc-sm-782a_amendment_1_and_2.pdf)")
		(tags "capacitor 0402")
		(property "Reference" "C106"
			(at 0 1.17 270)
			(layer "B.SilkS")
			(hide yes)
			(effects
				(font
					(size 0.7 0.7)
					(thickness 0.15)
				)
				(justify left bottom mirror)
			)
		)
		(property "Value" "C_100n_0402"
			(at 0 -1.169 270)
			(layer "B.Fab")
			(effects
				(font
					(size 0.7 0.7)
					(thickness 0.15)
				)
				(justify left bottom mirror)
			)
		)
		(property "Datasheet" "https://www.murata.com/products/productdetail?partno=GRM155R61H104KE14%23"
			(at 0 0 90)
			(layer "F.Fab")
			(hide yes)
			(effects
				(font
					(size 1.27 1.27)
					(thickness 0.15)
				)
			)
		)
		(property "Author" "Antmicro"
			(at 331.177501 32.423499 0)
			(layer "B.Fab")
			(hide yes)
			(effects
				(font
					(size 1 1)
					(thickness 0.15)
				)
				(justify mirror)
			)
		)
		(property "Dielectric" "X5R"
			(at 331.177501 32.423499 0)
			(layer "B.Fab")
			(hide yes)
			(effects
				(font
					(size 1 1)
					(thickness 0.15)
				)
				(justify mirror)
			)
		)
		(property "License" "Apache-2.0"
			(at 331.177501 32.423499 0)
			(layer "B.Fab")
			(hide yes)
			(effects
				(font
					(size 1 1)
					(thickness 0.15)
				)
				(justify mirror)
			)
		)
		(property "MPN" "GRM155R61H104KE14D"
			(at 331.177501 32.423499 0)
			(layer "B.Fab")
			(hide yes)
			(effects
				(font
					(size 1 1)
					(thickness 0.15)
				)
				(justify mirror)
			)
		)
		(property "Manufacturer" "Murata"
			(at 331.177501 32.423499 0)
			(layer "B.Fab")
			(hide yes)
			(effects
				(font
					(size 1 1)
					(thickness 0.15)
				)
				(justify mirror)
			)
		)
		(property "Val" "100n"
			(at 331.177501 32.423499 0)
			(layer "B.Fab")
			(hide yes)
			(effects
				(font
					(size 1 1)
					(thickness 0.15)
				)
				(justify mirror)
			)
		)
		(property "Voltage" "50V"
			(at 331.177501 32.423499 0)
			(layer "B.Fab")
			(hide yes)
			(effects
				(font
					(size 1 1)
					(thickness 0.15)
				)
				(justify mirror)
			)
		)
		(sheetname "/FPGA power/")
		(sheetfile "fpga-power.kicad_sch")
		(attr smd)
		(fp_rect
			(start -0.9656 0.4572)
			(end 0.9652 -0.4828)
			(stroke
				(width 0.05)
				(type solid)
			)
			(fill no)
			(layer "B.CrtYd")
		)
		(fp_line
			(start 0.498 -0.248)
			(end -0.5 -0.248)
			(stroke
				(width 0.15)
				(type solid)
			)
			(layer "B.Fab")
		)
		(fp_line
			(start -0.5 -0.248)
			(end -0.5 0.25)
			(stroke
				(width 0.15)
				(type solid)
			)
			(layer "B.Fab")
		)
		(fp_line
			(start 0.498 0.25)
			(end 0.498 -0.248)
			(stroke
				(width 0.15)
				(type solid)
			)
			(layer "B.Fab")
		)
		(fp_line
			(start -0.5 0.25)
			(end 0.498 0.25)
			(stroke
				(width 0.15)
				(type solid)
			)
			(layer "B.Fab")
		)
		(pad "1" smd roundrect
			(at -0.5 0)
			(size 0.6 0.6)
			(layers "B.Cu" "B.Mask" "B.Paste")
			(roundrect_rratio 0.25)
			(net 1 "GND")
			(pintype "passive")
		)
		(pad "2" smd roundrect
			(at 0.498 0 90)
			(size 0.6 0.6)
			(layers "B.Cu" "B.Mask" "B.Paste")
			(roundrect_rratio 0.25)
			(net 226 "+1V2_MGTAVTT")
			(pintype "passive")
		)
	)
	(footprint "antmicro-footprints:R_0402_1005Metric"
		(layer "B.Cu")
		(at 196.65 138.75 90)
		(descr "Resistor SMD 0402")
		(tags "resistor SMD 0402")
		(property "Reference" "R149"
			(at -1.122484 0.772697 270)
			(layer "B.SilkS")
			(hide yes)
			(effects
				(font
					(size 0.7 0.7)
					(thickness 0.15)
				)
				(justify left bottom mirror)
			)
		)
		(property "Value" "R_47k_0402"
			(at -1.011843 -1.772047 270)
			(layer "B.Fab")
			(effects
				(font
					(size 0.7 0.7)
					(thickness 0.15)
				)
				(justify left bottom mirror)
			)
		)
		(property "Datasheet" "https://www.bourns.com/docs/product-datasheets/cr.pdf"
			(at 0 0 90)
			(layer "F.Fab")
			(hide yes)
			(effects
				(font
					(size 1.27 1.27)
					(thickness 0.15)
				)
			)
		)
		(property "Author" "Antmicro"
			(at 335.4 -57.9 0)
			(layer "B.Fab")
			(hide yes)
			(effects
				(font
					(size 1 1)
					(thickness 0.15)
				)
				(justify mirror)
			)
		)
		(property "License" "Apache-2.0"
			(at 335.4 -57.9 0)
			(layer "B.Fab")
			(hide yes)
			(effects
				(font
					(size 1 1)
					(thickness 0.15)
				)
				(justify mirror)
			)
		)
		(property "MPN" "CR0402-FX-4702GLF"
			(at 335.4 -57.9 0)
			(layer "B.Fab")
			(hide yes)
			(effects
				(font
					(size 1 1)
					(thickness 0.15)
				)
				(justify mirror)
			)
		)
		(property "Manufacturer" "Bourns"
			(at 335.4 -57.9 0)
			(layer "B.Fab")
			(hide yes)
			(effects
				(font
					(size 1 1)
					(thickness 0.15)
				)
				(justify mirror)
			)
		)
		(property "Tolerance" "1%"
			(at 335.4 -57.9 0)
			(layer "B.Fab")
			(hide yes)
			(effects
				(font
					(size 1 1)
					(thickness 0.15)
				)
				(justify mirror)
			)
		)
		(property "Val" "47k"
			(at 335.4 -57.9 0)
			(layer "B.Fab")
			(hide yes)
			(effects
				(font
					(size 1 1)
					(thickness 0.15)
				)
				(justify mirror)
			)
		)
		(sheetname "/Supply/")
		(sheetfile "supply.kicad_sch")
		(attr smd)
		(fp_rect
			(start -0.93 0.47)
			(end 0.93 -0.47)
			(stroke
				(width 0.05)
				(type solid)
			)
			(fill no)
			(layer "B.CrtYd")
		)
		(fp_rect
			(start -0.5 0.25)
			(end 0.5 -0.25)
			(stroke
				(width 0.15)
				(type solid)
			)
			(fill no)
			(layer "B.Fab")
		)
		(pad "1" smd roundrect
			(at -0.485 0 90)
			(size 0.59 0.64)
			(layers "B.Cu" "B.Mask" "B.Paste")
			(roundrect_rratio 0.25)
			(net 185 "/Supply/~{PB_CTRL_CLR}")
			(pintype "passive")
		)
		(pad "2" smd roundrect
			(at 0.485 0 90)
			(size 0.59 0.64)
			(layers "B.Cu" "B.Mask" "B.Paste")
			(roundrect_rratio 0.25)
			(net 186 "/Supply/PB_CTRL_OUT")
			(pintype "passive")
		)
	)
	(footprint "antmicro-footprints:C_0402_1005Metric"
		(layer "B.Cu")
		(at 137.875001 177.3025)
		(descr "Capacitor SMD 0402 (1005 Metric), square (rectangular) end terminal, IPC_7351 nominal, (Body size source: IPC-SM-782 page 76, https://www.pcb-3d.com/wordpress/wp-content/uploads/ipc-sm-782a_amendment_1_and_2.pdf)")
		(tags "capacitor 0402")
		(property "Reference" "C70"
			(at 0 1.17 180)
			(layer "B.SilkS")
			(hide yes)
			(effects
				(font
					(size 0.7 0.7)
					(thickness 0.15)
				)
				(justify left bottom mirror)
			)
		)
		(property "Value" "C_100n_0402"
			(at 0 -1.169 180)
			(layer "B.Fab")
			(effects
				(font
					(size 0.7 0.7)
					(thickness 0.15)
				)
				(justify left bottom mirror)
			)
		)
		(property "Datasheet" "https://www.murata.com/products/productdetail?partno=GRM155R61H104KE14%23"
			(at 0 0 0)
			(layer "F.Fab")
			(hide yes)
			(effects
				(font
					(size 1.27 1.27)
					(thickness 0.15)
				)
			)
		)
		(property "Author" "Antmicro"
			(at 0 0 0)
			(layer "B.Fab")
			(hide yes)
			(effects
				(font
					(size 1 1)
					(thickness 0.15)
				)
				(justify mirror)
			)
		)
		(property "Dielectric" "X5R"
			(at 0 0 0)
			(layer "B.Fab")
			(hide yes)
			(effects
				(font
					(size 1 1)
					(thickness 0.15)
				)
				(justify mirror)
			)
		)
		(property "License" "Apache-2.0"
			(at 0 0 0)
			(layer "B.Fab")
			(hide yes)
			(effects
				(font
					(size 1 1)
					(thickness 0.15)
				)
				(justify mirror)
			)
		)
		(property "MPN" "GRM155R61H104KE14D"
			(at 0 0 0)
			(layer "B.Fab")
			(hide yes)
			(effects
				(font
					(size 1 1)
					(thickness 0.15)
				)
				(justify mirror)
			)
		)
		(property "Manufacturer" "Murata"
			(at 0 0 0)
			(layer "B.Fab")
			(hide yes)
			(effects
				(font
					(size 1 1)
					(thickness 0.15)
				)
				(justify mirror)
			)
		)
		(property "Val" "100n"
			(at 0 0 0)
			(layer "B.Fab")
			(hide yes)
			(effects
				(font
					(size 1 1)
					(thickness 0.15)
				)
				(justify mirror)
			)
		)
		(property "Voltage" "50V"
			(at 0 0 0)
			(layer "B.Fab")
			(hide yes)
			(effects
				(font
					(size 1 1)
					(thickness 0.15)
				)
				(justify mirror)
			)
		)
		(sheetname "/FPGA power/")
		(sheetfile "fpga-power.kicad_sch")
		(attr smd)
		(fp_rect
			(start -0.9656 0.4572)
			(end 0.9652 -0.4828)
			(stroke
				(width 0.05)
				(type solid)
			)
			(fill no)
			(layer "B.CrtYd")
		)
		(fp_line
			(start -0.5 -0.248)
			(end -0.5 0.25)
			(stroke
				(width 0.15)
				(type solid)
			)
			(layer "B.Fab")
		)
		(fp_line
			(start -0.5 0.25)
			(end 0.498 0.25)
			(stroke
				(width 0.15)
				(type solid)
			)
			(layer "B.Fab")
		)
		(fp_line
			(start 0.498 -0.248)
			(end -0.5 -0.248)
			(stroke
				(width 0.15)
				(type solid)
			)
			(layer "B.Fab")
		)
		(fp_line
			(start 0.498 0.25)
			(end 0.498 -0.248)
			(stroke
				(width 0.15)
				(type solid)
			)
			(layer "B.Fab")
		)
		(pad "1" smd roundrect
			(at -0.5 0 270)
			(size 0.6 0.6)
			(layers "B.Cu" "B.Mask" "B.Paste")
			(roundrect_rratio 0.25)
			(net 1 "GND")
			(pintype "passive")
		)
		(pad "2" smd roundrect
			(at 0.498 0)
			(size 0.6 0.6)
			(layers "B.Cu" "B.Mask" "B.Paste")
			(roundrect_rratio 0.25)
			(net 227 "+1V0")
			(pintype "passive")
		)
	)
	(footprint "antmicro-footprints:C_0402_1005Metric"
		(layer "B.Cu")
		(at 136.877001 173.3025)
		(descr "Capacitor SMD 0402 (1005 Metric), square (rectangular) end terminal, IPC_7351 nominal, (Body size source: IPC-SM-782 page 76, https://www.pcb-3d.com/wordpress/wp-content/uploads/ipc-sm-782a_amendment_1_and_2.pdf)")
		(tags "capacitor 0402")
		(property "Reference" "C62"
			(at 0 1.17 180)
			(layer "B.SilkS")
			(hide yes)
			(effects
				(font
					(size 0.7 0.7)
					(thickness 0.15)
				)
				(justify left bottom mirror)
			)
		)
		(property "Value" "C_4u7_0402"
			(at 0 -1.169 180)
			(layer "B.Fab")
			(effects
				(font
					(size 0.7 0.7)
					(thickness 0.15)
				)
				(justify left bottom mirror)
			)
		)
		(property "Datasheet" "https://www.murata.com/products/productdetail?partno=GRM155R61A475MEAA%23"
			(at 0 0 0)
			(layer "F.Fab")
			(hide yes)
			(effects
				(font
					(size 1.27 1.27)
					(thickness 0.15)
				)
			)
		)
		(property "Author" "Antmicro"
			(at 0 0 0)
			(layer "B.Fab")
			(hide yes)
			(effects
				(font
					(size 1 1)
					(thickness 0.15)
				)
				(justify mirror)
			)
		)
		(property "Dielectric" ""
			(at 0 0 0)
			(layer "B.Fab")
			(hide yes)
			(effects
				(font
					(size 1 1)
					(thickness 0.15)
				)
				(justify mirror)
			)
		)
		(property "License" "Apache-2.0"
			(at 0 0 0)
			(layer "B.Fab")
			(hide yes)
			(effects
				(font
					(size 1 1)
					(thickness 0.15)
				)
				(justify mirror)
			)
		)
		(property "MPN" "GRM155R61A475MEAAD"
			(at 0 0 0)
			(layer "B.Fab")
			(hide yes)
			(effects
				(font
					(size 1 1)
					(thickness 0.15)
				)
				(justify mirror)
			)
		)
		(property "Manufacturer" "Murata"
			(at 0 0 0)
			(layer "B.Fab")
			(hide yes)
			(effects
				(font
					(size 1 1)
					(thickness 0.15)
				)
				(justify mirror)
			)
		)
		(property "Val" "4u7"
			(at 0 0 0)
			(layer "B.Fab")
			(hide yes)
			(effects
				(font
					(size 1 1)
					(thickness 0.15)
				)
				(justify mirror)
			)
		)
		(property "Voltage" ""
			(at 0 0 0)
			(layer "B.Fab")
			(hide yes)
			(effects
				(font
					(size 1 1)
					(thickness 0.15)
				)
				(justify mirror)
			)
		)
		(sheetname "/FPGA power/")
		(sheetfile "fpga-power.kicad_sch")
		(attr smd)
		(fp_rect
			(start -0.9656 0.4572)
			(end 0.9652 -0.4828)
			(stroke
				(width 0.05)
				(type solid)
			)
			(fill no)
			(layer "B.CrtYd")
		)
		(fp_line
			(start -0.5 -0.248)
			(end -0.5 0.25)
			(stroke
				(width 0.15)
				(type solid)
			)
			(layer "B.Fab")
		)
		(fp_line
			(start -0.5 0.25)
			(end 0.498 0.25)
			(stroke
				(width 0.15)
				(type solid)
			)
			(layer "B.Fab")
		)
		(fp_line
			(start 0.498 -0.248)
			(end -0.5 -0.248)
			(stroke
				(width 0.15)
				(type solid)
			)
			(layer "B.Fab")
		)
		(fp_line
			(start 0.498 0.25)
			(end 0.498 -0.248)
			(stroke
				(width 0.15)
				(type solid)
			)
			(layer "B.Fab")
		)
		(pad "1" smd roundrect
			(at -0.5 0 270)
			(size 0.6 0.6)
			(layers "B.Cu" "B.Mask" "B.Paste")
			(roundrect_rratio 0.25)
			(net 227 "+1V0")
			(pintype "passive")
		)
		(pad "2" smd roundrect
			(at 0.498 0)
			(size 0.6 0.6)
			(layers "B.Cu" "B.Mask" "B.Paste")
			(roundrect_rratio 0.25)
			(net 1 "GND")
			(pintype "passive")
		)
	)
	(footprint "antmicro-footprints:C_0402_1005Metric"
		(layer "B.Cu")
		(at 195.85 128.15 180)
		(descr "Capacitor SMD 0402")
		(tags "capacitor SMD 0402")
		(property "Reference" "C169"
			(at 0 0.699 0)
			(layer "B.SilkS")
			(hide yes)
			(effects
				(font
					(size 0.7 0.7)
					(thickness 0.15)
				)
				(justify left bottom mirror)
			)
		)
		(property "Value" "C_100n_0402"
			(at -1.022927 -2.155213 0)
			(layer "B.Fab")
			(effects
				(font
					(size 0.7 0.7)
					(thickness 0.15)
				)
				(justify left bottom mirror)
			)
		)
		(property "Datasheet" "https://www.murata.com/products/productdetail?partno=GRM155R61H104KE14%23"
			(at 0 0 180)
			(layer "F.Fab")
			(hide yes)
			(effects
				(font
					(size 1.27 1.27)
					(thickness 0.15)
				)
			)
		)
		(property "Author" "Antmicro"
			(at 391.7 256.3 0)
			(layer "B.Fab")
			(hide yes)
			(effects
				(font
					(size 1 1)
					(thickness 0.15)
				)
				(justify mirror)
			)
		)
		(property "Dielectric" "X5R"
			(at 391.7 256.3 0)
			(layer "B.Fab")
			(hide yes)
			(effects
				(font
					(size 1 1)
					(thickness 0.15)
				)
				(justify mirror)
			)
		)
		(property "License" "Apache-2.0"
			(at 391.7 256.3 0)
			(layer "B.Fab")
			(hide yes)
			(effects
				(font
					(size 1 1)
					(thickness 0.15)
				)
				(justify mirror)
			)
		)
		(property "MPN" "GRM155R61H104KE14D"
			(at 391.7 256.3 0)
			(layer "B.Fab")
			(hide yes)
			(effects
				(font
					(size 1 1)
					(thickness 0.15)
				)
				(justify mirror)
			)
		)
		(property "Manufacturer" "Murata"
			(at 391.7 256.3 0)
			(layer "B.Fab")
			(hide yes)
			(effects
				(font
					(size 1 1)
					(thickness 0.15)
				)
				(justify mirror)
			)
		)
		(property "Val" "100n"
			(at 391.7 256.3 0)
			(layer "B.Fab")
			(hide yes)
			(effects
				(font
					(size 1 1)
					(thickness 0.15)
				)
				(justify mirror)
			)
		)
		(property "Voltage" "50V"
			(at 391.7 256.3 0)
			(layer "B.Fab")
			(hide yes)
			(effects
				(font
					(size 1 1)
					(thickness 0.15)
				)
				(justify mirror)
			)
		)
		(sheetname "/Supply/")
		(sheetfile "supply.kicad_sch")
		(attr smd)
		(fp_rect
			(start -0.9659 0.481258)
			(end 0.9649 -0.458742)
			(stroke
				(width 0.05)
				(type solid)
			)
			(fill no)
			(layer "B.CrtYd")
		)
		(fp_line
			(start 0.499 0.25)
			(end 0.499 -0.248)
			(stroke
				(width 0.15)
				(type solid)
			)
			(layer "B.Fab")
		)
		(fp_line
			(start 0.499 -0.248)
			(end -0.499 -0.248)
			(stroke
				(width 0.15)
				(type solid)
			)
			(layer "B.Fab")
		)
		(fp_line
			(start -0.499 0.25)
			(end 0.499 0.25)
			(stroke
				(width 0.15)
				(type solid)
			)
			(layer "B.Fab")
		)
		(fp_line
			(start -0.499 -0.248)
			(end -0.499 0.25)
			(stroke
				(width 0.15)
				(type solid)
			)
			(layer "B.Fab")
		)
		(pad "1" smd roundrect
			(at -0.484 0 180)
			(size 0.59 0.64)
			(layers "B.Cu" "B.Mask" "B.Paste")
			(roundrect_rratio 0.25)
			(net 1 "GND")
			(pintype "passive")
		)
		(pad "2" smd roundrect
			(at 0.484 0 180)
			(size 0.59 0.64)
			(layers "B.Cu" "B.Mask" "B.Paste")
			(roundrect_rratio 0.25)
			(net 597 "/Supply/12V_aux")
			(pintype "passive")
		)
	)
	(footprint "antmicro-footprints:TP_SMD_1mm"
		(layer "B.Cu")
		(at 186.4 182.1 180)
		(property "Reference" "TP34"
			(at 0 0.731898 0)
			(layer "B.SilkS")
			(hide yes)
			(effects
				(font
					(size 0.7 0.7)
					(thickness 0.15)
				)
				(justify left bottom mirror)
			)
		)
		(property "Value" "TP_1mm_SMD"
			(at 0 -1.4 0)
			(layer "B.Fab")
			(effects
				(font
					(size 0.7 0.7)
					(thickness 0.15)
				)
				(justify left bottom mirror)
			)
		)
		(property "MPN" ""
			(at 0 0 0)
			(unlocked yes)
			(layer "B.Fab")
			(hide yes)
			(effects
				(font
					(size 1 1)
					(thickness 0.15)
				)
				(justify mirror)
			)
		)
		(property "Manufacturer" ""
			(at 0 0 0)
			(unlocked yes)
			(layer "B.Fab")
			(hide yes)
			(effects
				(font
					(size 1 1)
					(thickness 0.15)
				)
				(justify mirror)
			)
		)
		(property "Author" "Antmicro"
			(at 0 0 0)
			(unlocked yes)
			(layer "B.Fab")
			(hide yes)
			(effects
				(font
					(size 1 1)
					(thickness 0.15)
				)
				(justify mirror)
			)
		)
		(property "License" "Apache-2.0"
			(at 0 0 0)
			(unlocked yes)
			(layer "B.Fab")
			(hide yes)
			(effects
				(font
					(size 1 1)
					(thickness 0.15)
				)
				(justify mirror)
			)
		)
		(sheetname "/Supply/")
		(sheetfile "supply.kicad_sch")
		(attr exclude_from_pos_files)
		(fp_circle
			(center 0 0)
			(end 0.6 0)
			(stroke
				(width 0.05)
				(type default)
			)
			(fill no)
			(layer "B.CrtYd")
		)
		(fp_text user "Author: Antmicro"
			(at -0.5 -4 0)
			(layer "B.Fab")
			(effects
				(font
					(size 0.7 0.7)
					(thickness 0.15)
				)
				(justify left bottom mirror)
			)
		)
		(fp_text user "${REFERENCE}"
			(at -0.5 -2.8 0)
			(layer "B.Fab")
			(effects
				(font
					(size 0.7 0.7)
					(thickness 0.15)
				)
				(justify left bottom mirror)
			)
		)
		(fp_text user "License: Apache-2.0"
			(at -0.5 -5.2 0)
			(layer "B.Fab")
			(effects
				(font
					(size 0.7 0.7)
					(thickness 0.15)
				)
				(justify left bottom mirror)
			)
		)
		(pad "1" smd circle
			(at 0 0 180)
			(size 1 1)
			(layers "B.Cu" "B.Mask")
			(net 188 "+1V8")
			(pinfunction "1")
			(pintype "passive")
		)
	)
	(footprint "antmicro-footprints:C_0402_1005Metric"
		(layer "B.Cu")
		(at 119.580501 175.926 90)
		(descr "Capacitor SMD 0402")
		(tags "capacitor SMD 0402")
		(property "Reference" "C4"
			(at 0 0.699 270)
			(layer "B.SilkS")
			(hide yes)
			(effects
				(font
					(size 0.7 0.7)
					(thickness 0.15)
				)
				(justify left bottom mirror)
			)
		)
		(property "Value" "C_100n_0402"
			(at -1.022927 -2.155213 270)
			(layer "B.Fab")
			(effects
				(font
					(size 0.7 0.7)
					(thickness 0.15)
				)
				(justify left bottom mirror)
			)
		)
		(property "Datasheet" "https://www.murata.com/products/productdetail?partno=GRM155R61H104KE14%23"
			(at 0 0 90)
			(layer "F.Fab")
			(hide yes)
			(effects
				(font
					(size 1.27 1.27)
					(thickness 0.15)
				)
			)
		)
		(property "Author" "Antmicro"
			(at 295.506501 56.345499 0)
			(layer "B.Fab")
			(hide yes)
			(effects
				(font
					(size 1 1)
					(thickness 0.15)
				)
				(justify mirror)
			)
		)
		(property "Dielectric" "X5R"
			(at 295.506501 56.345499 0)
			(layer "B.Fab")
			(hide yes)
			(effects
				(font
					(size 1 1)
					(thickness 0.15)
				)
				(justify mirror)
			)
		)
		(property "License" "Apache-2.0"
			(at 295.506501 56.345499 0)
			(layer "B.Fab")
			(hide yes)
			(effects
				(font
					(size 1 1)
					(thickness 0.15)
				)
				(justify mirror)
			)
		)
		(property "MPN" "GRM155R61H104KE14D"
			(at 295.506501 56.345499 0)
			(layer "B.Fab")
			(hide yes)
			(effects
				(font
					(size 1 1)
					(thickness 0.15)
				)
				(justify mirror)
			)
		)
		(property "Manufacturer" "Murata"
			(at 295.506501 56.345499 0)
			(layer "B.Fab")
			(hide yes)
			(effects
				(font
					(size 1 1)
					(thickness 0.15)
				)
				(justify mirror)
			)
		)
		(property "Val" "100n"
			(at 295.506501 56.345499 0)
			(layer "B.Fab")
			(hide yes)
			(effects
				(font
					(size 1 1)
					(thickness 0.15)
				)
				(justify mirror)
			)
		)
		(property "Voltage" "50V"
			(at 295.506501 56.345499 0)
			(layer "B.Fab")
			(hide yes)
			(effects
				(font
					(size 1 1)
					(thickness 0.15)
				)
				(justify mirror)
			)
		)
		(sheetname "/HyperRAM + QSPI Flash/")
		(sheetfile "hyperram-flash.kicad_sch")
		(attr smd)
		(fp_rect
			(start -0.9659 0.481258)
			(end 0.9649 -0.458742)
			(stroke
				(width 0.05)
				(type solid)
			)
			(fill no)
			(layer "B.CrtYd")
		)
		(fp_line
			(start 0.499 -0.248)
			(end -0.499 -0.248)
			(stroke
				(width 0.15)
				(type solid)
			)
			(layer "B.Fab")
		)
		(fp_line
			(start -0.499 -0.248)
			(end -0.499 0.25)
			(stroke
				(width 0.15)
				(type solid)
			)
			(layer "B.Fab")
		)
		(fp_line
			(start 0.499 0.25)
			(end 0.499 -0.248)
			(stroke
				(width 0.15)
				(type solid)
			)
			(layer "B.Fab")
		)
		(fp_line
			(start -0.499 0.25)
			(end 0.499 0.25)
			(stroke
				(width 0.15)
				(type solid)
			)
			(layer "B.Fab")
		)
		(pad "1" smd roundrect
			(at -0.484 0 90)
			(size 0.59 0.64)
			(layers "B.Cu" "B.Mask" "B.Paste")
			(roundrect_rratio 0.25)
			(net 200 "+3V3")
			(pintype "passive")
		)
		(pad "2" smd roundrect
			(at 0.484 0 90)
			(size 0.59 0.64)
			(layers "B.Cu" "B.Mask" "B.Paste")
			(roundrect_rratio 0.25)
			(net 1 "GND")
			(pintype "passive")
		)
	)
	(footprint "antmicro-footprints:R_0402_1005Metric_EIA"
		(layer "B.Cu")
		(at 141.875001 170.3025)
		(descr "Resistor SMD 0402 (1005 Metric), square (rectangular) end terminal, IPC_7351 nominal, (Body size source: IPC-SM-782 page 76, https://www.pcb-3d.com/wordpress/wp-content/uploads/ipc-sm-782a_amendment_1_and_2.pdf)")
		(tags "resistor 0402")
		(property "Reference" "R134"
			(at 0 1.17 180)
			(layer "B.SilkS")
			(hide yes)
			(effects
				(font
					(size 0.7 0.7)
					(thickness 0.15)
				)
				(justify left bottom mirror)
			)
		)
		(property "Value" "R_80R6_0402_EIA"
			(at 0 -1.169 180)
			(layer "B.Fab")
			(effects
				(font
					(size 0.7 0.7)
					(thickness 0.15)
				)
				(justify left bottom mirror)
			)
		)
		(property "Datasheet" "https://www.bourns.com/docs/product-datasheets/cr.pdf"
			(at 0 0 0)
			(layer "F.Fab")
			(hide yes)
			(effects
				(font
					(size 1.27 1.27)
					(thickness 0.15)
				)
			)
		)
		(property "Author" "Antmicro"
			(at 0 0 0)
			(layer "B.Fab")
			(hide yes)
			(effects
				(font
					(size 1 1)
					(thickness 0.15)
				)
				(justify mirror)
			)
		)
		(property "License" "Apache-2.0"
			(at 0 0 0)
			(layer "B.Fab")
			(hide yes)
			(effects
				(font
					(size 1 1)
					(thickness 0.15)
				)
				(justify mirror)
			)
		)
		(property "MPN" "MC00625W0402180R6"
			(at 0 0 0)
			(layer "B.Fab")
			(hide yes)
			(effects
				(font
					(size 1 1)
					(thickness 0.15)
				)
				(justify mirror)
			)
		)
		(property "Manufacturer" "Multicomp Pro"
			(at 0 0 0)
			(layer "B.Fab")
			(hide yes)
			(effects
				(font
					(size 1 1)
					(thickness 0.15)
				)
				(justify mirror)
			)
		)
		(property "Tolerance" "1%"
			(at 0 0 0)
			(layer "B.Fab")
			(hide yes)
			(effects
				(font
					(size 1 1)
					(thickness 0.15)
				)
				(justify mirror)
			)
		)
		(property "Val" "80R6"
			(at 0 0 0)
			(layer "B.Fab")
			(hide yes)
			(effects
				(font
					(size 1 1)
					(thickness 0.15)
				)
				(justify mirror)
			)
		)
		(sheetname "/FPGA banks HP/")
		(sheetfile "fpga-banks-32-34.kicad_sch")
		(attr smd)
		(fp_line
			(start -0.95 -0.45)
			(end -0.95 0.46)
			(stroke
				(width 0.05)
				(type solid)
			)
			(layer "B.CrtYd")
		)
		(fp_line
			(start -0.95 0.46)
			(end 0.9652 0.46)
			(stroke
				(width 0.05)
				(type solid)
			)
			(layer "B.CrtYd")
		)
		(fp_line
			(start 0.9652 -0.45)
			(end -0.95 -0.45)
			(stroke
				(width 0.05)
				(type solid)
			)
			(layer "B.CrtYd")
		)
		(fp_line
			(start 0.9652 0.46)
			(end 0.9652 -0.45)
			(stroke
				(width 0.05)
				(type solid)
			)
			(layer "B.CrtYd")
		)
		(fp_line
			(start -0.5 -0.249)
			(end -0.5 0.25)
			(stroke
				(width 0.15)
				(type solid)
			)
			(layer "B.Fab")
		)
		(fp_line
			(start -0.5 0.25)
			(end 0.499 0.25)
			(stroke
				(width 0.15)
				(type solid)
			)
			(layer "B.Fab")
		)
		(fp_line
			(start 0.499 -0.249)
			(end -0.5 -0.249)
			(stroke
				(width 0.15)
				(type solid)
			)
			(layer "B.Fab")
		)
		(fp_line
			(start 0.499 0.25)
			(end 0.499 -0.249)
			(stroke
				(width 0.15)
				(type solid)
			)
			(layer "B.Fab")
		)
		(pad "1" smd roundrect
			(at -0.5 0 270)
			(size 0.6 0.6)
			(layers "B.Cu" "B.Mask" "B.Paste")
			(roundrect_rratio 0.25)
			(net 685 "/FPGA banks HP/VRP")
			(pintype "passive")
		)
		(pad "2" smd roundrect
			(at 0.499 0)
			(size 0.6 0.6)
			(layers "B.Cu" "B.Mask" "B.Paste")
			(roundrect_rratio 0.25)
			(net 1 "GND")
			(pintype "passive")
		)
	)
	(footprint "antmicro-footprints:R_0402_1005Metric"
		(layer "B.Cu")
		(at 184.25 191.48 90)
		(descr "Resistor SMD 0402")
		(tags "resistor SMD 0402")
		(property "Reference" "R37"
			(at -1.42 0.6 90)
			(layer "B.SilkS")
			(effects
				(font
					(size 0.7 0.7)
					(thickness 0.15)
				)
				(justify right top mirror)
			)
		)
		(property "Value" "R_0R_0402"
			(at -1.011843 -1.772046 90)
			(layer "B.Fab")
			(effects
				(font
					(size 0.7 0.7)
					(thickness 0.15)
				)
				(justify right top mirror)
			)
		)
		(property "Datasheet" "https://industrial.panasonic.com/cdbs/www-data/pdf/RDA0000/AOA0000C301.pdf"
			(at 0 0 90)
			(layer "B.Fab")
			(hide yes)
			(effects
				(font
					(size 1.27 1.27)
					(thickness 0.15)
				)
				(justify mirror)
			)
		)
		(property "Manufacturer" "Panasonic"
			(at 0 0 270)
			(unlocked yes)
			(layer "B.Fab")
			(hide yes)
			(effects
				(font
					(size 1 1)
					(thickness 0.15)
				)
				(justify mirror)
			)
		)
		(property "MPN" "ERJ2GE0R00X"
			(at 0 0 270)
			(unlocked yes)
			(layer "B.Fab")
			(hide yes)
			(effects
				(font
					(size 1 1)
					(thickness 0.15)
				)
				(justify mirror)
			)
		)
		(property "Val" "0R"
			(at 0 0 270)
			(unlocked yes)
			(layer "B.Fab")
			(hide yes)
			(effects
				(font
					(size 1 1)
					(thickness 0.15)
				)
				(justify mirror)
			)
		)
		(property "License" "Apache-2.0"
			(at 0 0 270)
			(unlocked yes)
			(layer "B.Fab")
			(hide yes)
			(effects
				(font
					(size 1 1)
					(thickness 0.15)
				)
				(justify mirror)
			)
		)
		(property "Author" "Antmicro"
			(at 0 0 270)
			(unlocked yes)
			(layer "B.Fab")
			(hide yes)
			(effects
				(font
					(size 1 1)
					(thickness 0.15)
				)
				(justify mirror)
			)
		)
		(property "Tolerance" ""
			(at 0 0 270)
			(unlocked yes)
			(layer "B.Fab")
			(hide yes)
			(effects
				(font
					(size 1 1)
					(thickness 0.15)
				)
				(justify mirror)
			)
		)
		(property "Current" "1A"
			(at 0 0 270)
			(unlocked yes)
			(layer "B.Fab")
			(hide yes)
			(effects
				(font
					(size 1 1)
					(thickness 0.15)
				)
				(justify mirror)
			)
		)
		(sheetname "/I^{2}C/")
		(sheetfile "i2c.kicad_sch")
		(attr smd)
		(fp_poly
			(pts
				(xy -0.925 0.47) (xy -0.925 -0.47) (xy 0.925 -0.47) (xy 0.925 0.47)
			)
			(stroke
				(width 0.05)
				(type default)
			)
			(fill no)
			(layer "B.CrtYd")
		)
		(fp_poly
			(pts
				(xy -0.5 0.25) (xy -0.5 -0.25) (xy 0.5 -0.25) (xy 0.5 0.25)
			)
			(stroke
				(width 0.15)
				(type solid)
			)
			(fill no)
			(layer "B.Fab")
		)
		(fp_text user "Author: Antmicro"
			(at -0.95 -4.169 90)
			(layer "B.Fab")
			(effects
				(font
					(size 0.7 0.7)
					(thickness 0.15)
				)
				(justify right top mirror)
			)
		)
		(fp_text user "${REFERENCE}"
			(at -0.95 -3.168 90)
			(layer "B.Fab")
			(effects
				(font
					(size 0.7 0.7)
					(thickness 0.15)
				)
				(justify right top mirror)
			)
		)
		(fp_text user "License: Apache-2.0"
			(at -0.949999 -5.169 90)
			(layer "B.Fab")
			(effects
				(font
					(size 0.7 0.7)
					(thickness 0.15)
				)
				(justify right top mirror)
			)
		)
		(pad "1" smd roundrect
			(at -0.48 0 90)
			(size 0.59 0.64)
			(layers "B.Cu" "B.Mask" "B.Paste")
			(roundrect_rratio 0.25)
			(net 691 "/I^{2}C/PWR.SCL")
			(pintype "passive")
		)
		(pad "2" smd roundrect
			(at 0.48 0 90)
			(size 0.59 0.64)
			(layers "B.Cu" "B.Mask" "B.Paste")
			(roundrect_rratio 0.25)
			(net 762 "Net-(U34-SCL)")
			(pintype "passive")
		)
	)
	(footprint "antmicro-footprints:C_0402_1005Metric"
		(layer "B.Cu")
		(at 198.1 138.765 90)
		(descr "Capacitor SMD 0402")
		(tags "capacitor SMD 0402")
		(property "Reference" "C195"
			(at 0 0.699 270)
			(layer "B.SilkS")
			(hide yes)
			(effects
				(font
					(size 0.7 0.7)
					(thickness 0.15)
				)
				(justify left bottom mirror)
			)
		)
		(property "Value" "C_100n_0402"
			(at -1.022927 -2.155213 270)
			(layer "B.Fab")
			(effects
				(font
					(size 0.7 0.7)
					(thickness 0.15)
				)
				(justify left bottom mirror)
			)
		)
		(property "Datasheet" "https://www.murata.com/products/productdetail?partno=GRM155R61H104KE14%23"
			(at 0 0 90)
			(layer "F.Fab")
			(hide yes)
			(effects
				(font
					(size 1.27 1.27)
					(thickness 0.15)
				)
			)
		)
		(property "Author" "Antmicro"
			(at 336.865 -59.335 0)
			(layer "B.Fab")
			(hide yes)
			(effects
				(font
					(size 1 1)
					(thickness 0.15)
				)
				(justify mirror)
			)
		)
		(property "Dielectric" "X5R"
			(at 336.865 -59.335 0)
			(layer "B.Fab")
			(hide yes)
			(effects
				(font
					(size 1 1)
					(thickness 0.15)
				)
				(justify mirror)
			)
		)
		(property "License" "Apache-2.0"
			(at 336.865 -59.335 0)
			(layer "B.Fab")
			(hide yes)
			(effects
				(font
					(size 1 1)
					(thickness 0.15)
				)
				(justify mirror)
			)
		)
		(property "MPN" "GRM155R61H104KE14D"
			(at 336.865 -59.335 0)
			(layer "B.Fab")
			(hide yes)
			(effects
				(font
					(size 1 1)
					(thickness 0.15)
				)
				(justify mirror)
			)
		)
		(property "Manufacturer" "Murata"
			(at 336.865 -59.335 0)
			(layer "B.Fab")
			(hide yes)
			(effects
				(font
					(size 1 1)
					(thickness 0.15)
				)
				(justify mirror)
			)
		)
		(property "Val" "100n"
			(at 336.865 -59.335 0)
			(layer "B.Fab")
			(hide yes)
			(effects
				(font
					(size 1 1)
					(thickness 0.15)
				)
				(justify mirror)
			)
		)
		(property "Voltage" "50V"
			(at 336.865 -59.335 0)
			(layer "B.Fab")
			(hide yes)
			(effects
				(font
					(size 1 1)
					(thickness 0.15)
				)
				(justify mirror)
			)
		)
		(sheetname "/Supply/")
		(sheetfile "supply.kicad_sch")
		(attr smd)
		(fp_rect
			(start -0.9659 0.481258)
			(end 0.9649 -0.458742)
			(stroke
				(width 0.05)
				(type solid)
			)
			(fill no)
			(layer "B.CrtYd")
		)
		(fp_line
			(start 0.499 -0.248)
			(end -0.499 -0.248)
			(stroke
				(width 0.15)
				(type solid)
			)
			(layer "B.Fab")
		)
		(fp_line
			(start -0.499 -0.248)
			(end -0.499 0.25)
			(stroke
				(width 0.15)
				(type solid)
			)
			(layer "B.Fab")
		)
		(fp_line
			(start 0.499 0.25)
			(end 0.499 -0.248)
			(stroke
				(width 0.15)
				(type solid)
			)
			(layer "B.Fab")
		)
		(fp_line
			(start -0.499 0.25)
			(end 0.499 0.25)
			(stroke
				(width 0.15)
				(type solid)
			)
			(layer "B.Fab")
		)
		(pad "1" smd roundrect
			(at -0.484 0 90)
			(size 0.59 0.64)
			(layers "B.Cu" "B.Mask" "B.Paste")
			(roundrect_rratio 0.25)
			(net 1 "GND")
			(pintype "passive")
		)
		(pad "2" smd roundrect
			(at 0.484 0 90)
			(size 0.59 0.64)
			(layers "B.Cu" "B.Mask" "B.Paste")
			(roundrect_rratio 0.25)
			(net 41 "+3V3_AON")
			(pintype "passive")
		)
	)
	(footprint "antmicro-footprints:R_0402_1005Metric"
		(layer "B.Cu")
		(at 140.302001 160.1 90)
		(descr "Resistor SMD 0402")
		(tags "resistor SMD 0402")
		(property "Reference" "R132"
			(at -1.122484 0.772697 270)
			(layer "B.SilkS")
			(hide yes)
			(effects
				(font
					(size 0.7 0.7)
					(thickness 0.15)
				)
				(justify left bottom mirror)
			)
		)
		(property "Value" "R_0R_0402"
			(at -1.011843 -1.772047 270)
			(layer "B.Fab")
			(effects
				(font
					(size 0.7 0.7)
					(thickness 0.15)
				)
				(justify left bottom mirror)
			)
		)
		(property "Datasheet" "https://industrial.panasonic.com/cdbs/www-data/pdf/RDA0000/AOA0000C301.pdf"
			(at 0 0 90)
			(layer "F.Fab")
			(hide yes)
			(effects
				(font
					(size 1.27 1.27)
					(thickness 0.15)
				)
			)
		)
		(property "Author" "Antmicro"
			(at 300.402001 19.797999 0)
			(layer "B.Fab")
			(hide yes)
			(effects
				(font
					(size 1 1)
					(thickness 0.15)
				)
				(justify mirror)
			)
		)
		(property "Current" "1A"
			(at 300.402001 19.797999 0)
			(layer "B.Fab")
			(hide yes)
			(effects
				(font
					(size 1 1)
					(thickness 0.15)
				)
				(justify mirror)
			)
		)
		(property "License" "Apache-2.0"
			(at 300.402001 19.797999 0)
			(layer "B.Fab")
			(hide yes)
			(effects
				(font
					(size 1 1)
					(thickness 0.15)
				)
				(justify mirror)
			)
		)
		(property "MPN" "ERJ2GE0R00X"
			(at 300.402001 19.797999 0)
			(layer "B.Fab")
			(hide yes)
			(effects
				(font
					(size 1 1)
					(thickness 0.15)
				)
				(justify mirror)
			)
		)
		(property "Manufacturer" "Panasonic"
			(at 300.402001 19.797999 0)
			(layer "B.Fab")
			(hide yes)
			(effects
				(font
					(size 1 1)
					(thickness 0.15)
				)
				(justify mirror)
			)
		)
		(property "Tolerance" ""
			(at 300.402001 19.797999 0)
			(layer "B.Fab")
			(hide yes)
			(effects
				(font
					(size 1 1)
					(thickness 0.15)
				)
				(justify mirror)
			)
		)
		(property "Val" "0R"
			(at 300.402001 19.797999 0)
			(layer "B.Fab")
			(hide yes)
			(effects
				(font
					(size 1 1)
					(thickness 0.15)
				)
				(justify mirror)
			)
		)
		(sheetname "/FPGA banks HP/")
		(sheetfile "fpga-banks-32-34.kicad_sch")
		(attr smd exclude_from_pos_files exclude_from_bom dnp)
		(fp_rect
			(start -0.93 0.47)
			(end 0.93 -0.47)
			(stroke
				(width 0.05)
				(type solid)
			)
			(fill no)
			(layer "B.CrtYd")
		)
		(fp_rect
			(start -0.5 0.25)
			(end 0.5 -0.25)
			(stroke
				(width 0.15)
				(type solid)
			)
			(fill no)
			(layer "B.Fab")
		)
		(pad "1" smd roundrect
			(at -0.485 0 90)
			(size 0.59 0.64)
			(layers "B.Cu" "B.Mask" "B.Paste")
			(roundrect_rratio 0.25)
			(net 379 "Net-(R129-Pad1)")
			(pintype "passive")
		)
		(pad "2" smd roundrect
			(at 0.485 0 90)
			(size 0.59 0.64)
			(layers "B.Cu" "B.Mask" "B.Paste")
			(roundrect_rratio 0.25)
			(net 10 "/FPGA banks HP/VREF")
			(pintype "passive")
		)
	)
	(footprint "antmicro-footprints:C_0402_1005Metric"
		(layer "B.Cu")
		(at 149.377001 183.8005 -90)
		(descr "Capacitor SMD 0402 (1005 Metric), square (rectangular) end terminal, IPC_7351 nominal, (Body size source: IPC-SM-782 page 76, https://www.pcb-3d.com/wordpress/wp-content/uploads/ipc-sm-782a_amendment_1_and_2.pdf)")
		(tags "capacitor 0402")
		(property "Reference" "C108"
			(at 0 1.17 90)
			(layer "B.SilkS")
			(hide yes)
			(effects
				(font
					(size 0.7 0.7)
					(thickness 0.15)
				)
				(justify left bottom mirror)
			)
		)
		(property "Value" "C_100n_0402"
			(at 0 -1.169 90)
			(layer "B.Fab")
			(effects
				(font
					(size 0.7 0.7)
					(thickness 0.15)
				)
				(justify left bottom mirror)
			)
		)
		(property "Datasheet" "https://www.murata.com/products/productdetail?partno=GRM155R61H104KE14%23"
			(at 0 0 270)
			(layer "F.Fab")
			(hide yes)
			(effects
				(font
					(size 1.27 1.27)
					(thickness 0.15)
				)
			)
		)
		(property "Author" "Antmicro"
			(at -34.423499 333.177501 0)
			(layer "B.Fab")
			(hide yes)
			(effects
				(font
					(size 1 1)
					(thickness 0.15)
				)
				(justify mirror)
			)
		)
		(property "Dielectric" "X5R"
			(at -34.423499 333.177501 0)
			(layer "B.Fab")
			(hide yes)
			(effects
				(font
					(size 1 1)
					(thickness 0.15)
				)
				(justify mirror)
			)
		)
		(property "License" "Apache-2.0"
			(at -34.423499 333.177501 0)
			(layer "B.Fab")
			(hide yes)
			(effects
				(font
					(size 1 1)
					(thickness 0.15)
				)
				(justify mirror)
			)
		)
		(property "MPN" "GRM155R61H104KE14D"
			(at -34.423499 333.177501 0)
			(layer "B.Fab")
			(hide yes)
			(effects
				(font
					(size 1 1)
					(thickness 0.15)
				)
				(justify mirror)
			)
		)
		(property "Manufacturer" "Murata"
			(at -34.423499 333.177501 0)
			(layer "B.Fab")
			(hide yes)
			(effects
				(font
					(size 1 1)
					(thickness 0.15)
				)
				(justify mirror)
			)
		)
		(property "Val" "100n"
			(at -34.423499 333.177501 0)
			(layer "B.Fab")
			(hide yes)
			(effects
				(font
					(size 1 1)
					(thickness 0.15)
				)
				(justify mirror)
			)
		)
		(property "Voltage" "50V"
			(at -34.423499 333.177501 0)
			(layer "B.Fab")
			(hide yes)
			(effects
				(font
					(size 1 1)
					(thickness 0.15)
				)
				(justify mirror)
			)
		)
		(sheetname "/FPGA power/")
		(sheetfile "fpga-power.kicad_sch")
		(attr smd)
		(fp_rect
			(start -0.9656 0.4572)
			(end 0.9652 -0.4828)
			(stroke
				(width 0.05)
				(type solid)
			)
			(fill no)
			(layer "B.CrtYd")
		)
		(fp_line
			(start -0.5 0.25)
			(end 0.498 0.25)
			(stroke
				(width 0.15)
				(type solid)
			)
			(layer "B.Fab")
		)
		(fp_line
			(start 0.498 0.25)
			(end 0.498 -0.248)
			(stroke
				(width 0.15)
				(type solid)
			)
			(layer "B.Fab")
		)
		(fp_line
			(start -0.5 -0.248)
			(end -0.5 0.25)
			(stroke
				(width 0.15)
				(type solid)
			)
			(layer "B.Fab")
		)
		(fp_line
			(start 0.498 -0.248)
			(end -0.5 -0.248)
			(stroke
				(width 0.15)
				(type solid)
			)
			(layer "B.Fab")
		)
		(pad "1" smd roundrect
			(at -0.5 0 180)
			(size 0.6 0.6)
			(layers "B.Cu" "B.Mask" "B.Paste")
			(roundrect_rratio 0.25)
			(net 1 "GND")
			(pintype "passive")
		)
		(pad "2" smd roundrect
			(at 0.498 0 270)
			(size 0.6 0.6)
			(layers "B.Cu" "B.Mask" "B.Paste")
			(roundrect_rratio 0.25)
			(net 226 "+1V2_MGTAVTT")
			(pintype "passive")
		)
	)
	(footprint "antmicro-footprints:C_0603_1608Metric"
		(layer "B.Cu")
		(at 138.900501 185.276 90)
		(descr "Capacitor SMD 0603")
		(tags "capacitor 0603")
		(property "Reference" "C16"
			(at 0 0.9 90)
			(layer "B.SilkS")
			(hide yes)
			(effects
				(font
					(size 0.7 0.7)
					(thickness 0.15)
				)
				(justify right bottom mirror)
			)
		)
		(property "Value" "C_47u_0603"
			(at 0 -1.6 90)
			(layer "B.Fab")
			(effects
				(font
					(size 0.7 0.7)
					(thickness 0.15)
				)
				(justify right bottom mirror)
			)
		)
		(property "Datasheet" "https://www.murata.com/products/productdetail?partno=GRM188R60J476ME15%23"
			(at 0 0 90)
			(layer "F.Fab")
			(hide yes)
			(effects
				(font
					(size 1.27 1.27)
					(thickness 0.15)
				)
			)
		)
		(property "Author" "Antmicro"
			(at 324.176501 46.375499 0)
			(layer "B.Fab")
			(hide yes)
			(effects
				(font
					(size 1 1)
					(thickness 0.15)
				)
				(justify mirror)
			)
		)
		(property "Dielectric" ""
			(at 324.176501 46.375499 0)
			(layer "B.Fab")
			(hide yes)
			(effects
				(font
					(size 1 1)
					(thickness 0.15)
				)
				(justify mirror)
			)
		)
		(property "License" "Apache-2.0"
			(at 324.176501 46.375499 0)
			(layer "B.Fab")
			(hide yes)
			(effects
				(font
					(size 1 1)
					(thickness 0.15)
				)
				(justify mirror)
			)
		)
		(property "MPN" "GRM188R60J476ME15D"
			(at 324.176501 46.375499 0)
			(layer "B.Fab")
			(hide yes)
			(effects
				(font
					(size 1 1)
					(thickness 0.15)
				)
				(justify mirror)
			)
		)
		(property "Manufacturer" "Murata"
			(at 324.176501 46.375499 0)
			(layer "B.Fab")
			(hide yes)
			(effects
				(font
					(size 1 1)
					(thickness 0.15)
				)
				(justify mirror)
			)
		)
		(property "Val" "47u"
			(at 324.176501 46.375499 0)
			(layer "B.Fab")
			(hide yes)
			(effects
				(font
					(size 1 1)
					(thickness 0.15)
				)
				(justify mirror)
			)
		)
		(property "Voltage" ""
			(at 324.176501 46.375499 0)
			(layer "B.Fab")
			(hide yes)
			(effects
				(font
					(size 1 1)
					(thickness 0.15)
				)
				(justify mirror)
			)
		)
		(sheetname "/FPGA power/")
		(sheetfile "fpga-power.kicad_sch")
		(attr smd)
		(fp_line
			(start -0.3 -0.3)
			(end 0.3 -0.3)
			(stroke
				(width 0.15)
				(type solid)
			)
			(layer "B.SilkS")
		)
		(fp_line
			(start -0.3 0.3)
			(end 0.3 0.3)
			(stroke
				(width 0.15)
				(type solid)
			)
			(layer "B.SilkS")
		)
		(fp_rect
			(start -1.24 0.7)
			(end 1.24 -0.7)
			(stroke
				(width 0.05)
				(type solid)
			)
			(fill no)
			(layer "B.CrtYd")
		)
		(fp_rect
			(start -0.8 0.4)
			(end 0.8 -0.4)
			(stroke
				(width 0.15)
				(type solid)
			)
			(fill no)
			(layer "B.Fab")
		)
		(pad "1" smd roundrect
			(at -0.7 0 90)
			(size 0.6 0.8)
			(layers "B.Cu" "B.Mask" "B.Paste")
			(roundrect_rratio 0.2)
			(net 200 "+3V3")
			(pintype "passive")
		)
		(pad "2" smd roundrect
			(at 0.7 0 90)
			(size 0.6 0.8)
			(layers "B.Cu" "B.Mask" "B.Paste")
			(roundrect_rratio 0.2)
			(net 1 "GND")
			(pintype "passive")
		)
	)
	(footprint "antmicro-footprints:C_0402_1005Metric"
		(layer "B.Cu")
		(at 133.875501 163.301 180)
		(descr "Capacitor SMD 0402 (1005 Metric), square (rectangular) end terminal, IPC_7351 nominal, (Body size source: IPC-SM-782 page 76, https://www.pcb-3d.com/wordpress/wp-content/uploads/ipc-sm-782a_amendment_1_and_2.pdf)")
		(tags "capacitor 0402")
		(property "Reference" "C20"
			(at 0 1.17 0)
			(layer "B.SilkS")
			(hide yes)
			(effects
				(font
					(size 0.7 0.7)
					(thickness 0.15)
				)
				(justify left bottom mirror)
			)
		)
		(property "Value" "C_100n_0402"
			(at 0 -1.169 0)
			(layer "B.Fab")
			(effects
				(font
					(size 0.7 0.7)
					(thickness 0.15)
				)
				(justify left bottom mirror)
			)
		)
		(property "Datasheet" "https://www.murata.com/products/productdetail?partno=GRM155R61H104KE14%23"
			(at 0 0 180)
			(layer "F.Fab")
			(hide yes)
			(effects
				(font
					(size 1.27 1.27)
					(thickness 0.15)
				)
			)
		)
		(property "Author" "Antmicro"
			(at 267.751002 326.602 0)
			(layer "B.Fab")
			(hide yes)
			(effects
				(font
					(size 1 1)
					(thickness 0.15)
				)
				(justify mirror)
			)
		)
		(property "Dielectric" "X5R"
			(at 267.751002 326.602 0)
			(layer "B.Fab")
			(hide yes)
			(effects
				(font
					(size 1 1)
					(thickness 0.15)
				)
				(justify mirror)
			)
		)
		(property "License" "Apache-2.0"
			(at 267.751002 326.602 0)
			(layer "B.Fab")
			(hide yes)
			(effects
				(font
					(size 1 1)
					(thickness 0.15)
				)
				(justify mirror)
			)
		)
		(property "MPN" "GRM155R61H104KE14D"
			(at 267.751002 326.602 0)
			(layer "B.Fab")
			(hide yes)
			(effects
				(font
					(size 1 1)
					(thickness 0.15)
				)
				(justify mirror)
			)
		)
		(property "Manufacturer" "Murata"
			(at 267.751002 326.602 0)
			(layer "B.Fab")
			(hide yes)
			(effects
				(font
					(size 1 1)
					(thickness 0.15)
				)
				(justify mirror)
			)
		)
		(property "Val" "100n"
			(at 267.751002 326.602 0)
			(layer "B.Fab")
			(hide yes)
			(effects
				(font
					(size 1 1)
					(thickness 0.15)
				)
				(justify mirror)
			)
		)
		(property "Voltage" "50V"
			(at 267.751002 326.602 0)
			(layer "B.Fab")
			(hide yes)
			(effects
				(font
					(size 1 1)
					(thickness 0.15)
				)
				(justify mirror)
			)
		)
		(sheetname "/FPGA power/")
		(sheetfile "fpga-power.kicad_sch")
		(attr smd)
		(fp_rect
			(start -0.9656 0.4572)
			(end 0.9652 -0.4828)
			(stroke
				(width 0.05)
				(type solid)
			)
			(fill no)
			(layer "B.CrtYd")
		)
		(fp_line
			(start 0.498 0.25)
			(end 0.498 -0.248)
			(stroke
				(width 0.15)
				(type solid)
			)
			(layer "B.Fab")
		)
		(fp_line
			(start 0.498 -0.248)
			(end -0.5 -0.248)
			(stroke
				(width 0.15)
				(type solid)
			)
			(layer "B.Fab")
		)
		(fp_line
			(start -0.5 0.25)
			(end 0.498 0.25)
			(stroke
				(width 0.15)
				(type solid)
			)
			(layer "B.Fab")
		)
		(fp_line
			(start -0.5 -0.248)
			(end -0.5 0.25)
			(stroke
				(width 0.15)
				(type solid)
			)
			(layer "B.Fab")
		)
		(pad "1" smd roundrect
			(at -0.5 0 90)
			(size 0.6 0.6)
			(layers "B.Cu" "B.Mask" "B.Paste")
			(roundrect_rratio 0.25)
			(net 1 "GND")
			(pintype "passive")
		)
		(pad "2" smd roundrect
			(at 0.498 0 180)
			(size 0.6 0.6)
			(layers "B.Cu" "B.Mask" "B.Paste")
			(roundrect_rratio 0.25)
			(net 206 "+1V1")
			(pintype "passive")
		)
	)
	(footprint "antmicro-footprints:C_0402_1005Metric"
		(layer "B.Cu")
		(at 139.375001 178.8025 90)
		(descr "Capacitor SMD 0402 (1005 Metric), square (rectangular) end terminal, IPC_7351 nominal, (Body size source: IPC-SM-782 page 76, https://www.pcb-3d.com/wordpress/wp-content/uploads/ipc-sm-782a_amendment_1_and_2.pdf)")
		(tags "capacitor 0402")
		(property "Reference" "C79"
			(at 0 1.17 270)
			(layer "B.SilkS")
			(hide yes)
			(effects
				(font
					(size 0.7 0.7)
					(thickness 0.15)
				)
				(justify left bottom mirror)
			)
		)
		(property "Value" "C_100n_0402"
			(at 0 -1.169 270)
			(layer "B.Fab")
			(effects
				(font
					(size 0.7 0.7)
					(thickness 0.15)
				)
				(justify left bottom mirror)
			)
		)
		(property "Datasheet" "https://www.murata.com/products/productdetail?partno=GRM155R61H104KE14%23"
			(at 0 0 90)
			(layer "F.Fab")
			(hide yes)
			(effects
				(font
					(size 1.27 1.27)
					(thickness 0.15)
				)
			)
		)
		(property "Author" "Antmicro"
			(at 318.177501 39.427499 0)
			(layer "B.Fab")
			(hide yes)
			(effects
				(font
					(size 1 1)
					(thickness 0.15)
				)
				(justify mirror)
			)
		)
		(property "Dielectric" "X5R"
			(at 318.177501 39.427499 0)
			(layer "B.Fab")
			(hide yes)
			(effects
				(font
					(size 1 1)
					(thickness 0.15)
				)
				(justify mirror)
			)
		)
		(property "License" "Apache-2.0"
			(at 318.177501 39.427499 0)
			(layer "B.Fab")
			(hide yes)
			(effects
				(font
					(size 1 1)
					(thickness 0.15)
				)
				(justify mirror)
			)
		)
		(property "MPN" "GRM155R61H104KE14D"
			(at 318.177501 39.427499 0)
			(layer "B.Fab")
			(hide yes)
			(effects
				(font
					(size 1 1)
					(thickness 0.15)
				)
				(justify mirror)
			)
		)
		(property "Manufacturer" "Murata"
			(at 318.177501 39.427499 0)
			(layer "B.Fab")
			(hide yes)
			(effects
				(font
					(size 1 1)
					(thickness 0.15)
				)
				(justify mirror)
			)
		)
		(property "Val" "100n"
			(at 318.177501 39.427499 0)
			(layer "B.Fab")
			(hide yes)
			(effects
				(font
					(size 1 1)
					(thickness 0.15)
				)
				(justify mirror)
			)
		)
		(property "Voltage" "50V"
			(at 318.177501 39.427499 0)
			(layer "B.Fab")
			(hide yes)
			(effects
				(font
					(size 1 1)
					(thickness 0.15)
				)
				(justify mirror)
			)
		)
		(sheetname "/FPGA power/")
		(sheetfile "fpga-power.kicad_sch")
		(attr smd)
		(fp_rect
			(start -0.9656 0.4572)
			(end 0.9652 -0.4828)
			(stroke
				(width 0.05)
				(type solid)
			)
			(fill no)
			(layer "B.CrtYd")
		)
		(fp_line
			(start 0.498 -0.248)
			(end -0.5 -0.248)
			(stroke
				(width 0.15)
				(type solid)
			)
			(layer "B.Fab")
		)
		(fp_line
			(start -0.5 -0.248)
			(end -0.5 0.25)
			(stroke
				(width 0.15)
				(type solid)
			)
			(layer "B.Fab")
		)
		(fp_line
			(start 0.498 0.25)
			(end 0.498 -0.248)
			(stroke
				(width 0.15)
				(type solid)
			)
			(layer "B.Fab")
		)
		(fp_line
			(start -0.5 0.25)
			(end 0.498 0.25)
			(stroke
				(width 0.15)
				(type solid)
			)
			(layer "B.Fab")
		)
		(pad "1" smd roundrect
			(at -0.5 0)
			(size 0.6 0.6)
			(layers "B.Cu" "B.Mask" "B.Paste")
			(roundrect_rratio 0.25)
			(net 1 "GND")
			(pintype "passive")
		)
		(pad "2" smd roundrect
			(at 0.498 0 90)
			(size 0.6 0.6)
			(layers "B.Cu" "B.Mask" "B.Paste")
			(roundrect_rratio 0.25)
			(net 227 "+1V0")
			(pintype "passive")
		)
	)
	(footprint "antmicro-footprints:C_0402_1005Metric"
		(layer "B.Cu")
		(at 146.375001 185.800501 -90)
		(descr "Capacitor SMD 0402 (1005 Metric), square (rectangular) end terminal, IPC_7351 nominal, (Body size source: IPC-SM-782 page 76, https://www.pcb-3d.com/wordpress/wp-content/uploads/ipc-sm-782a_amendment_1_and_2.pdf)")
		(tags "capacitor 0402")
		(property "Reference" "C102"
			(at 0 1.17 90)
			(layer "B.SilkS")
			(hide yes)
			(effects
				(font
					(size 0.7 0.7)
					(thickness 0.15)
				)
				(justify left bottom mirror)
			)
		)
		(property "Value" "C_4u7_0402"
			(at 0 -1.169 90)
			(layer "B.Fab")
			(effects
				(font
					(size 0.7 0.7)
					(thickness 0.15)
				)
				(justify left bottom mirror)
			)
		)
		(property "Datasheet" "https://www.murata.com/products/productdetail?partno=GRM155R61A475MEAA%23"
			(at 0 0 270)
			(layer "F.Fab")
			(hide yes)
			(effects
				(font
					(size 1.27 1.27)
					(thickness 0.15)
				)
			)
		)
		(property "Author" "Antmicro"
			(at -39.4255 332.175502 0)
			(layer "B.Fab")
			(hide yes)
			(effects
				(font
					(size 1 1)
					(thickness 0.15)
				)
				(justify mirror)
			)
		)
		(property "Dielectric" ""
			(at -39.4255 332.175502 0)
			(layer "B.Fab")
			(hide yes)
			(effects
				(font
					(size 1 1)
					(thickness 0.15)
				)
				(justify mirror)
			)
		)
		(property "License" "Apache-2.0"
			(at -39.4255 332.175502 0)
			(layer "B.Fab")
			(hide yes)
			(effects
				(font
					(size 1 1)
					(thickness 0.15)
				)
				(justify mirror)
			)
		)
		(property "MPN" "GRM155R61A475MEAAD"
			(at -39.4255 332.175502 0)
			(layer "B.Fab")
			(hide yes)
			(effects
				(font
					(size 1 1)
					(thickness 0.15)
				)
				(justify mirror)
			)
		)
		(property "Manufacturer" "Murata"
			(at -39.4255 332.175502 0)
			(layer "B.Fab")
			(hide yes)
			(effects
				(font
					(size 1 1)
					(thickness 0.15)
				)
				(justify mirror)
			)
		)
		(property "Val" "4u7"
			(at -39.4255 332.175502 0)
			(layer "B.Fab")
			(hide yes)
			(effects
				(font
					(size 1 1)
					(thickness 0.15)
				)
				(justify mirror)
			)
		)
		(property "Voltage" ""
			(at -39.4255 332.175502 0)
			(layer "B.Fab")
			(hide yes)
			(effects
				(font
					(size 1 1)
					(thickness 0.15)
				)
				(justify mirror)
			)
		)
		(sheetname "/FPGA power/")
		(sheetfile "fpga-power.kicad_sch")
		(attr smd)
		(fp_rect
			(start -0.9656 0.4572)
			(end 0.9652 -0.4828)
			(stroke
				(width 0.05)
				(type solid)
			)
			(fill no)
			(layer "B.CrtYd")
		)
		(fp_line
			(start -0.5 0.25)
			(end 0.498 0.25)
			(stroke
				(width 0.15)
				(type solid)
			)
			(layer "B.Fab")
		)
		(fp_line
			(start 0.498 0.25)
			(end 0.498 -0.248)
			(stroke
				(width 0.15)
				(type solid)
			)
			(layer "B.Fab")
		)
		(fp_line
			(start -0.5 -0.248)
			(end -0.5 0.25)
			(stroke
				(width 0.15)
				(type solid)
			)
			(layer "B.Fab")
		)
		(fp_line
			(start 0.498 -0.248)
			(end -0.5 -0.248)
			(stroke
				(width 0.15)
				(type solid)
			)
			(layer "B.Fab")
		)
		(pad "1" smd roundrect
			(at -0.5 0 180)
			(size 0.6 0.6)
			(layers "B.Cu" "B.Mask" "B.Paste")
			(roundrect_rratio 0.25)
			(net 187 "+1V0_MGTAVCC")
			(pintype "passive")
		)
		(pad "2" smd roundrect
			(at 0.498 0 270)
			(size 0.6 0.6)
			(layers "B.Cu" "B.Mask" "B.Paste")
			(roundrect_rratio 0.25)
			(net 1 "GND")
			(pintype "passive")
		)
	)
	(footprint "antmicro-footprints:C_0402_1005Metric"
		(layer "B.Cu")
		(at 144.525501 204.800501 90)
		(descr "Capacitor SMD 0402")
		(tags "capacitor SMD 0402")
		(property "Reference" "C226"
			(at 0 0.699 270)
			(layer "B.SilkS")
			(hide yes)
			(effects
				(font
					(size 0.7 0.7)
					(thickness 0.15)
				)
				(justify left bottom mirror)
			)
		)
		(property "Value" "C_100n_0402"
			(at -1.022927 -2.155213 270)
			(layer "B.Fab")
			(effects
				(font
					(size 0.7 0.7)
					(thickness 0.15)
				)
				(justify left bottom mirror)
			)
		)
		(property "Datasheet" "https://www.murata.com/products/productdetail?partno=GRM155R61H104KE14%23"
			(at 0 0 90)
			(layer "F.Fab")
			(hide yes)
			(effects
				(font
					(size 1.27 1.27)
					(thickness 0.15)
				)
			)
		)
		(property "Author" "Antmicro"
			(at 349.326002 60.275 0)
			(layer "B.Fab")
			(hide yes)
			(effects
				(font
					(size 1 1)
					(thickness 0.15)
				)
				(justify mirror)
			)
		)
		(property "Dielectric" "X5R"
			(at 349.326002 60.275 0)
			(layer "B.Fab")
			(hide yes)
			(effects
				(font
					(size 1 1)
					(thickness 0.15)
				)
				(justify mirror)
			)
		)
		(property "License" "Apache-2.0"
			(at 349.326002 60.275 0)
			(layer "B.Fab")
			(hide yes)
			(effects
				(font
					(size 1 1)
					(thickness 0.15)
				)
				(justify mirror)
			)
		)
		(property "MPN" "GRM155R61H104KE14D"
			(at 349.326002 60.275 0)
			(layer "B.Fab")
			(hide yes)
			(effects
				(font
					(size 1 1)
					(thickness 0.15)
				)
				(justify mirror)
			)
		)
		(property "Manufacturer" "Murata"
			(at 349.326002 60.275 0)
			(layer "B.Fab")
			(hide yes)
			(effects
				(font
					(size 1 1)
					(thickness 0.15)
				)
				(justify mirror)
			)
		)
		(property "Val" "100n"
			(at 349.326002 60.275 0)
			(layer "B.Fab")
			(hide yes)
			(effects
				(font
					(size 1 1)
					(thickness 0.15)
				)
				(justify mirror)
			)
		)
		(property "Voltage" "50V"
			(at 349.326002 60.275 0)
			(layer "B.Fab")
			(hide yes)
			(effects
				(font
					(size 1 1)
					(thickness 0.15)
				)
				(justify mirror)
			)
		)
		(sheetname "/FPGA MGT Interface/")
		(sheetfile "fpga-mgt.kicad_sch")
		(attr smd)
		(fp_rect
			(start -0.9659 0.481258)
			(end 0.9649 -0.458742)
			(stroke
				(width 0.05)
				(type solid)
			)
			(fill no)
			(layer "B.CrtYd")
		)
		(fp_line
			(start 0.499 -0.248)
			(end -0.499 -0.248)
			(stroke
				(width 0.15)
				(type solid)
			)
			(layer "B.Fab")
		)
		(fp_line
			(start -0.499 -0.248)
			(end -0.499 0.25)
			(stroke
				(width 0.15)
				(type solid)
			)
			(layer "B.Fab")
		)
		(fp_line
			(start 0.499 0.25)
			(end 0.499 -0.248)
			(stroke
				(width 0.15)
				(type solid)
			)
			(layer "B.Fab")
		)
		(fp_line
			(start -0.499 0.25)
			(end 0.499 0.25)
			(stroke
				(width 0.15)
				(type solid)
			)
			(layer "B.Fab")
		)
		(pad "1" smd roundrect
			(at -0.484 0 90)
			(size 0.59 0.64)
			(layers "B.Cu" "B.Mask" "B.Paste")
			(roundrect_rratio 0.25)
			(net 16 "/FPGA MGT Interface/PCIE.TXD3_P")
			(pintype "passive")
		)
		(pad "2" smd roundrect
			(at 0.484 0 90)
			(size 0.59 0.64)
			(layers "B.Cu" "B.Mask" "B.Paste")
			(roundrect_rratio 0.25)
			(net 17 "/FPGA MGT Interface/GTX_TX0_P")
			(pintype "passive")
		)
	)
	(footprint "antmicro-footprints:C_0603_1608Metric"
		(layer "B.Cu")
		(at 142.175501 174.801)
		(descr "Capacitor SMD 0603")
		(tags "capacitor 0603")
		(property "Reference" "C11"
			(at 0 0.9 0)
			(layer "B.SilkS")
			(hide yes)
			(effects
				(font
					(size 0.7 0.7)
					(thickness 0.15)
				)
				(justify right bottom mirror)
			)
		)
		(property "Value" "C_47u_0603"
			(at 0 -1.6 0)
			(layer "B.Fab")
			(effects
				(font
					(size 0.7 0.7)
					(thickness 0.15)
				)
				(justify right bottom mirror)
			)
		)
		(property "Datasheet" "https://www.murata.com/products/productdetail?partno=GRM188R60J476ME15%23"
			(at 0 0 0)
			(layer "F.Fab")
			(hide yes)
			(effects
				(font
					(size 1.27 1.27)
					(thickness 0.15)
				)
			)
		)
		(property "Author" "Antmicro"
			(at 0 0 0)
			(layer "B.Fab")
			(hide yes)
			(effects
				(font
					(size 1 1)
					(thickness 0.15)
				)
				(justify mirror)
			)
		)
		(property "Dielectric" ""
			(at 0 0 0)
			(layer "B.Fab")
			(hide yes)
			(effects
				(font
					(size 1 1)
					(thickness 0.15)
				)
				(justify mirror)
			)
		)
		(property "License" "Apache-2.0"
			(at 0 0 0)
			(layer "B.Fab")
			(hide yes)
			(effects
				(font
					(size 1 1)
					(thickness 0.15)
				)
				(justify mirror)
			)
		)
		(property "MPN" "GRM188R60J476ME15D"
			(at 0 0 0)
			(layer "B.Fab")
			(hide yes)
			(effects
				(font
					(size 1 1)
					(thickness 0.15)
				)
				(justify mirror)
			)
		)
		(property "Manufacturer" "Murata"
			(at 0 0 0)
			(layer "B.Fab")
			(hide yes)
			(effects
				(font
					(size 1 1)
					(thickness 0.15)
				)
				(justify mirror)
			)
		)
		(property "Val" "47u"
			(at 0 0 0)
			(layer "B.Fab")
			(hide yes)
			(effects
				(font
					(size 1 1)
					(thickness 0.15)
				)
				(justify mirror)
			)
		)
		(property "Voltage" ""
			(at 0 0 0)
			(layer "B.Fab")
			(hide yes)
			(effects
				(font
					(size 1 1)
					(thickness 0.15)
				)
				(justify mirror)
			)
		)
		(sheetname "/FPGA power/")
		(sheetfile "fpga-power.kicad_sch")
		(attr smd)
		(fp_line
			(start -0.3 -0.3)
			(end 0.3 -0.3)
			(stroke
				(width 0.15)
				(type solid)
			)
			(layer "B.SilkS")
		)
		(fp_line
			(start -0.3 0.3)
			(end 0.3 0.3)
			(stroke
				(width 0.15)
				(type solid)
			)
			(layer "B.SilkS")
		)
		(fp_rect
			(start -1.24 0.7)
			(end 1.24 -0.7)
			(stroke
				(width 0.05)
				(type solid)
			)
			(fill no)
			(layer "B.CrtYd")
		)
		(fp_rect
			(start -0.8 0.4)
			(end 0.8 -0.4)
			(stroke
				(width 0.15)
				(type solid)
			)
			(fill no)
			(layer "B.Fab")
		)
		(pad "1" smd roundrect
			(at -0.7 0)
			(size 0.6 0.8)
			(layers "B.Cu" "B.Mask" "B.Paste")
			(roundrect_rratio 0.2)
			(net 188 "+1V8")
			(pintype "passive")
		)
		(pad "2" smd roundrect
			(at 0.7 0)
			(size 0.6 0.8)
			(layers "B.Cu" "B.Mask" "B.Paste")
			(roundrect_rratio 0.2)
			(net 1 "GND")
			(pintype "passive")
		)
	)
	(footprint "antmicro-footprints:TP_SMD_1mm"
		(layer "B.Cu")
		(at 198.4 161.6)
		(property "Reference" "TP71"
			(at 2.55 1.45 180)
			(layer "B.SilkS")
			(effects
				(font
					(size 0.7 0.7)
					(thickness 0.15)
				)
				(justify left bottom mirror)
			)
		)
		(property "Value" "TP_1mm_SMD"
			(at 0 -1.4 180)
			(layer "B.Fab")
			(effects
				(font
					(size 0.7 0.7)
					(thickness 0.15)
				)
				(justify left bottom mirror)
			)
		)
		(property "MPN" ""
			(at 0 0 180)
			(unlocked yes)
			(layer "B.Fab")
			(hide yes)
			(effects
				(font
					(size 1 1)
					(thickness 0.15)
				)
				(justify mirror)
			)
		)
		(property "Manufacturer" ""
			(at 0 0 180)
			(unlocked yes)
			(layer "B.Fab")
			(hide yes)
			(effects
				(font
					(size 1 1)
					(thickness 0.15)
				)
				(justify mirror)
			)
		)
		(property "Author" "Antmicro"
			(at 0 0 180)
			(unlocked yes)
			(layer "B.Fab")
			(hide yes)
			(effects
				(font
					(size 1 1)
					(thickness 0.15)
				)
				(justify mirror)
			)
		)
		(property "License" "Apache-2.0"
			(at 0 0 180)
			(unlocked yes)
			(layer "B.Fab")
			(hide yes)
			(effects
				(font
					(size 1 1)
					(thickness 0.15)
				)
				(justify mirror)
			)
		)
		(sheetname "/Supply/")
		(sheetfile "supply.kicad_sch")
		(attr exclude_from_pos_files)
		(fp_circle
			(center 0 0)
			(end 0.6 0)
			(stroke
				(width 0.05)
				(type default)
			)
			(fill no)
			(layer "B.CrtYd")
		)
		(fp_text user "Author: Antmicro"
			(at -0.5 -4 180)
			(layer "B.Fab")
			(effects
				(font
					(size 0.7 0.7)
					(thickness 0.15)
				)
				(justify left bottom mirror)
			)
		)
		(fp_text user "${REFERENCE}"
			(at -0.5 -2.8 180)
			(layer "B.Fab")
			(effects
				(font
					(size 0.7 0.7)
					(thickness 0.15)
				)
				(justify left bottom mirror)
			)
		)
		(fp_text user "License: Apache-2.0"
			(at -0.5 -5.2 180)
			(layer "B.Fab")
			(effects
				(font
					(size 0.7 0.7)
					(thickness 0.15)
				)
				(justify left bottom mirror)
			)
		)
		(pad "1" smd circle
			(at 0 0)
			(size 1 1)
			(layers "B.Cu" "B.Mask")
			(net 285 "/Supply/QDCDC2_SCL")
			(pinfunction "1")
			(pintype "passive")
		)
	)
	(footprint "antmicro-footprints:C_0402_1005Metric"
		(layer "B.Cu")
		(at 139.875001 171.3025)
		(descr "Capacitor SMD 0402 (1005 Metric), square (rectangular) end terminal, IPC_7351 nominal, (Body size source: IPC-SM-782 page 76, https://www.pcb-3d.com/wordpress/wp-content/uploads/ipc-sm-782a_amendment_1_and_2.pdf)")
		(tags "capacitor 0402")
		(property "Reference" "C83"
			(at 0 1.17 180)
			(layer "B.SilkS")
			(hide yes)
			(effects
				(font
					(size 0.7 0.7)
					(thickness 0.15)
				)
				(justify left bottom mirror)
			)
		)
		(property "Value" "C_100n_0402"
			(at 0 -1.169 180)
			(layer "B.Fab")
			(effects
				(font
					(size 0.7 0.7)
					(thickness 0.15)
				)
				(justify left bottom mirror)
			)
		)
		(property "Datasheet" "https://www.murata.com/products/productdetail?partno=GRM155R61H104KE14%23"
			(at 0 0 0)
			(layer "F.Fab")
			(hide yes)
			(effects
				(font
					(size 1.27 1.27)
					(thickness 0.15)
				)
			)
		)
		(property "Author" "Antmicro"
			(at 0 0 0)
			(layer "B.Fab")
			(hide yes)
			(effects
				(font
					(size 1 1)
					(thickness 0.15)
				)
				(justify mirror)
			)
		)
		(property "Dielectric" "X5R"
			(at 0 0 0)
			(layer "B.Fab")
			(hide yes)
			(effects
				(font
					(size 1 1)
					(thickness 0.15)
				)
				(justify mirror)
			)
		)
		(property "License" "Apache-2.0"
			(at 0 0 0)
			(layer "B.Fab")
			(hide yes)
			(effects
				(font
					(size 1 1)
					(thickness 0.15)
				)
				(justify mirror)
			)
		)
		(property "MPN" "GRM155R61H104KE14D"
			(at 0 0 0)
			(layer "B.Fab")
			(hide yes)
			(effects
				(font
					(size 1 1)
					(thickness 0.15)
				)
				(justify mirror)
			)
		)
		(property "Manufacturer" "Murata"
			(at 0 0 0)
			(layer "B.Fab")
			(hide yes)
			(effects
				(font
					(size 1 1)
					(thickness 0.15)
				)
				(justify mirror)
			)
		)
		(property "Val" "100n"
			(at 0 0 0)
			(layer "B.Fab")
			(hide yes)
			(effects
				(font
					(size 1 1)
					(thickness 0.15)
				)
				(justify mirror)
			)
		)
		(property "Voltage" "50V"
			(at 0 0 0)
			(layer "B.Fab")
			(hide yes)
			(effects
				(font
					(size 1 1)
					(thickness 0.15)
				)
				(justify mirror)
			)
		)
		(sheetname "/FPGA power/")
		(sheetfile "fpga-power.kicad_sch")
		(attr smd)
		(fp_rect
			(start -0.9656 0.4572)
			(end 0.9652 -0.4828)
			(stroke
				(width 0.05)
				(type solid)
			)
			(fill no)
			(layer "B.CrtYd")
		)
		(fp_line
			(start -0.5 -0.248)
			(end -0.5 0.25)
			(stroke
				(width 0.15)
				(type solid)
			)
			(layer "B.Fab")
		)
		(fp_line
			(start -0.5 0.25)
			(end 0.498 0.25)
			(stroke
				(width 0.15)
				(type solid)
			)
			(layer "B.Fab")
		)
		(fp_line
			(start 0.498 -0.248)
			(end -0.5 -0.248)
			(stroke
				(width 0.15)
				(type solid)
			)
			(layer "B.Fab")
		)
		(fp_line
			(start 0.498 0.25)
			(end 0.498 -0.248)
			(stroke
				(width 0.15)
				(type solid)
			)
			(layer "B.Fab")
		)
		(pad "1" smd roundrect
			(at -0.5 0 270)
			(size 0.6 0.6)
			(layers "B.Cu" "B.Mask" "B.Paste")
			(roundrect_rratio 0.25)
			(net 1 "GND")
			(pintype "passive")
		)
		(pad "2" smd roundrect
			(at 0.498 0)
			(size 0.6 0.6)
			(layers "B.Cu" "B.Mask" "B.Paste")
			(roundrect_rratio 0.25)
			(net 227 "+1V0")
			(pintype "passive")
		)
	)
	(footprint "antmicro-footprints:C_0402_1005Metric"
		(layer "B.Cu")
		(at 156.500501 175.276)
		(descr "Capacitor SMD 0402")
		(tags "capacitor SMD 0402")
		(property "Reference" "C198"
			(at 0 0.699 180)
			(layer "B.SilkS")
			(hide yes)
			(effects
				(font
					(size 0.7 0.7)
					(thickness 0.15)
				)
				(justify left bottom mirror)
			)
		)
		(property "Value" "C_1u_0402"
			(at -1.022927 -2.155213 180)
			(layer "B.Fab")
			(effects
				(font
					(size 0.7 0.7)
					(thickness 0.15)
				)
				(justify left bottom mirror)
			)
		)
		(property "Datasheet" "https://product.tdk.com/en/search/capacitor/ceramic/mlcc/info?part_no=C1005X6S1A105K050BC"
			(at 0 0 0)
			(layer "F.Fab")
			(hide yes)
			(effects
				(font
					(size 1.27 1.27)
					(thickness 0.15)
				)
			)
		)
		(property "Author" "Antmicro"
			(at 0 0 0)
			(layer "B.Fab")
			(hide yes)
			(effects
				(font
					(size 1 1)
					(thickness 0.15)
				)
				(justify mirror)
			)
		)
		(property "Dielectric" ""
			(at 0 0 0)
			(layer "B.Fab")
			(hide yes)
			(effects
				(font
					(size 1 1)
					(thickness 0.15)
				)
				(justify mirror)
			)
		)
		(property "License" "Apache-2.0"
			(at 0 0 0)
			(layer "B.Fab")
			(hide yes)
			(effects
				(font
					(size 1 1)
					(thickness 0.15)
				)
				(justify mirror)
			)
		)
		(property "MPN" "C1005X6S1A105K050BC"
			(at 0 0 0)
			(layer "B.Fab")
			(hide yes)
			(effects
				(font
					(size 1 1)
					(thickness 0.15)
				)
				(justify mirror)
			)
		)
		(property "Manufacturer" "TDK"
			(at 0 0 0)
			(layer "B.Fab")
			(hide yes)
			(effects
				(font
					(size 1 1)
					(thickness 0.15)
				)
				(justify mirror)
			)
		)
		(property "Val" "1u"
			(at 0 0 0)
			(layer "B.Fab")
			(hide yes)
			(effects
				(font
					(size 1 1)
					(thickness 0.15)
				)
				(justify mirror)
			)
		)
		(property "Voltage" ""
			(at 0 0 0)
			(layer "B.Fab")
			(hide yes)
			(effects
				(font
					(size 1 1)
					(thickness 0.15)
				)
				(justify mirror)
			)
		)
		(sheetname "/Supply/")
		(sheetfile "supply.kicad_sch")
		(attr smd)
		(fp_rect
			(start -0.9659 0.481258)
			(end 0.9649 -0.458742)
			(stroke
				(width 0.05)
				(type solid)
			)
			(fill no)
			(layer "B.CrtYd")
		)
		(fp_line
			(start -0.499 -0.248)
			(end -0.499 0.25)
			(stroke
				(width 0.15)
				(type solid)
			)
			(layer "B.Fab")
		)
		(fp_line
			(start -0.499 0.25)
			(end 0.499 0.25)
			(stroke
				(width 0.15)
				(type solid)
			)
			(layer "B.Fab")
		)
		(fp_line
			(start 0.499 -0.248)
			(end -0.499 -0.248)
			(stroke
				(width 0.15)
				(type solid)
			)
			(layer "B.Fab")
		)
		(fp_line
			(start 0.499 0.25)
			(end 0.499 -0.248)
			(stroke
				(width 0.15)
				(type solid)
			)
			(layer "B.Fab")
		)
		(pad "1" smd roundrect
			(at -0.484 0)
			(size 0.59 0.64)
			(layers "B.Cu" "B.Mask" "B.Paste")
			(roundrect_rratio 0.25)
			(net 1 "GND")
			(pintype "passive")
		)
		(pad "2" smd roundrect
			(at 0.484 0)
			(size 0.59 0.64)
			(layers "B.Cu" "B.Mask" "B.Paste")
			(roundrect_rratio 0.25)
			(net 201 "+5V")
			(pintype "passive")
		)
	)
	(footprint "antmicro-footprints:C_0402_1005Metric"
		(layer "B.Cu")
		(at 117.150501 205.426 180)
		(descr "Capacitor SMD 0402")
		(tags "capacitor SMD 0402")
		(property "Reference" "C170"
			(at 0 0.699 0)
			(layer "B.SilkS")
			(hide yes)
			(effects
				(font
					(size 0.7 0.7)
					(thickness 0.15)
				)
				(justify left bottom mirror)
			)
		)
		(property "Value" "C_100n_0402"
			(at -1.022927 -2.155213 0)
			(layer "B.Fab")
			(effects
				(font
					(size 0.7 0.7)
					(thickness 0.15)
				)
				(justify left bottom mirror)
			)
		)
		(property "Datasheet" "https://www.murata.com/products/productdetail?partno=GRM155R61H104KE14%23"
			(at 0 0 180)
			(layer "F.Fab")
			(hide yes)
			(effects
				(font
					(size 1.27 1.27)
					(thickness 0.15)
				)
			)
		)
		(property "Author" "Antmicro"
			(at 234.301002 410.852 0)
			(layer "B.Fab")
			(hide yes)
			(effects
				(font
					(size 1 1)
					(thickness 0.15)
				)
				(justify mirror)
			)
		)
		(property "Dielectric" "X5R"
			(at 234.301002 410.852 0)
			(layer "B.Fab")
			(hide yes)
			(effects
				(font
					(size 1 1)
					(thickness 0.15)
				)
				(justify mirror)
			)
		)
		(property "License" "Apache-2.0"
			(at 234.301002 410.852 0)
			(layer "B.Fab")
			(hide yes)
			(effects
				(font
					(size 1 1)
					(thickness 0.15)
				)
				(justify mirror)
			)
		)
		(property "MPN" "GRM155R61H104KE14D"
			(at 234.301002 410.852 0)
			(layer "B.Fab")
			(hide yes)
			(effects
				(font
					(size 1 1)
					(thickness 0.15)
				)
				(justify mirror)
			)
		)
		(property "Manufacturer" "Murata"
			(at 234.301002 410.852 0)
			(layer "B.Fab")
			(hide yes)
			(effects
				(font
					(size 1 1)
					(thickness 0.15)
				)
				(justify mirror)
			)
		)
		(property "Val" "100n"
			(at 234.301002 410.852 0)
			(layer "B.Fab")
			(hide yes)
			(effects
				(font
					(size 1 1)
					(thickness 0.15)
				)
				(justify mirror)
			)
		)
		(property "Voltage" "50V"
			(at 234.301002 410.852 0)
			(layer "B.Fab")
			(hide yes)
			(effects
				(font
					(size 1 1)
					(thickness 0.15)
				)
				(justify mirror)
			)
		)
		(sheetname "/Supply/")
		(sheetfile "supply.kicad_sch")
		(attr smd)
		(fp_rect
			(start -0.9659 0.481258)
			(end 0.9649 -0.458742)
			(stroke
				(width 0.05)
				(type solid)
			)
			(fill no)
			(layer "B.CrtYd")
		)
		(fp_line
			(start 0.499 0.25)
			(end 0.499 -0.248)
			(stroke
				(width 0.15)
				(type solid)
			)
			(layer "B.Fab")
		)
		(fp_line
			(start 0.499 -0.248)
			(end -0.499 -0.248)
			(stroke
				(width 0.15)
				(type solid)
			)
			(layer "B.Fab")
		)
		(fp_line
			(start -0.499 0.25)
			(end 0.499 0.25)
			(stroke
				(width 0.15)
				(type solid)
			)
			(layer "B.Fab")
		)
		(fp_line
			(start -0.499 -0.248)
			(end -0.499 0.25)
			(stroke
				(width 0.15)
				(type solid)
			)
			(layer "B.Fab")
		)
		(pad "1" smd roundrect
			(at -0.484 0 180)
			(size 0.59 0.64)
			(layers "B.Cu" "B.Mask" "B.Paste")
			(roundrect_rratio 0.25)
			(net 1 "GND")
			(pintype "passive")
		)
		(pad "2" smd roundrect
			(at 0.484 0 180)
			(size 0.59 0.64)
			(layers "B.Cu" "B.Mask" "B.Paste")
			(roundrect_rratio 0.25)
			(net 11 "+12V")
			(pintype "passive")
		)
	)
	(footprint "antmicro-footprints:R_0402_1005Metric"
		(layer "B.Cu")
		(at 202.881001 170.222 90)
		(descr "Resistor SMD 0402")
		(tags "resistor SMD 0402")
		(property "Reference" "R169"
			(at -1.122484 0.368999 270)
			(layer "B.SilkS")
			(effects
				(font
					(size 0.7 0.7)
					(thickness 0.15)
				)
				(justify left bottom mirror)
			)
		)
		(property "Value" "R_0R_0402"
			(at -1.011843 -1.772047 270)
			(layer "B.Fab")
			(effects
				(font
					(size 0.7 0.7)
					(thickness 0.15)
				)
				(justify left bottom mirror)
			)
		)
		(property "Datasheet" "https://industrial.panasonic.com/cdbs/www-data/pdf/RDA0000/AOA0000C301.pdf"
			(at 0 0 90)
			(layer "F.Fab")
			(hide yes)
			(effects
				(font
					(size 1.27 1.27)
					(thickness 0.15)
				)
			)
		)
		(property "Author" "Antmicro"
			(at 373.103001 -32.659001 0)
			(layer "B.Fab")
			(hide yes)
			(effects
				(font
					(size 1 1)
					(thickness 0.15)
				)
				(justify mirror)
			)
		)
		(property "Current" "1A"
			(at 373.103001 -32.659001 0)
			(layer "B.Fab")
			(hide yes)
			(effects
				(font
					(size 1 1)
					(thickness 0.15)
				)
				(justify mirror)
			)
		)
		(property "License" "Apache-2.0"
			(at 373.103001 -32.659001 0)
			(layer "B.Fab")
			(hide yes)
			(effects
				(font
					(size 1 1)
					(thickness 0.15)
				)
				(justify mirror)
			)
		)
		(property "MPN" "ERJ2GE0R00X"
			(at 373.103001 -32.659001 0)
			(layer "B.Fab")
			(hide yes)
			(effects
				(font
					(size 1 1)
					(thickness 0.15)
				)
				(justify mirror)
			)
		)
		(property "Manufacturer" "Panasonic"
			(at 373.103001 -32.659001 0)
			(layer "B.Fab")
			(hide yes)
			(effects
				(font
					(size 1 1)
					(thickness 0.15)
				)
				(justify mirror)
			)
		)
		(property "Tolerance" ""
			(at 373.103001 -32.659001 0)
			(layer "B.Fab")
			(hide yes)
			(effects
				(font
					(size 1 1)
					(thickness 0.15)
				)
				(justify mirror)
			)
		)
		(property "Val" "0R"
			(at 373.103001 -32.659001 0)
			(layer "B.Fab")
			(hide yes)
			(effects
				(font
					(size 1 1)
					(thickness 0.15)
				)
				(justify mirror)
			)
		)
		(sheetname "/Supply/")
		(sheetfile "supply.kicad_sch")
		(attr exclude_from_pos_files exclude_from_bom dnp)
		(fp_rect
			(start -0.93 0.47)
			(end 0.93 -0.47)
			(stroke
				(width 0.05)
				(type solid)
			)
			(fill no)
			(layer "B.CrtYd")
		)
		(fp_rect
			(start -0.5 0.25)
			(end 0.5 -0.25)
			(stroke
				(width 0.15)
				(type solid)
			)
			(fill no)
			(layer "B.Fab")
		)
		(pad "1" smd roundrect
			(at -0.485 0 90)
			(size 0.59 0.64)
			(layers "B.Cu" "B.Mask" "B.Paste")
			(roundrect_rratio 0.25)
			(net 1 "GND")
			(pintype "passive")
		)
		(pad "2" smd roundrect
			(at 0.485 0 90)
			(size 0.59 0.64)
			(layers "B.Cu" "B.Mask" "B.Paste")
			(roundrect_rratio 0.25)
			(net 218 "/Supply/FB8")
			(pintype "passive")
		)
	)
	(footprint "antmicro-footprints:C_0402_1005Metric"
		(layer "B.Cu")
		(at 172.800501 196.376)
		(descr "Capacitor SMD 0402")
		(tags "capacitor SMD 0402")
		(property "Reference" "C204"
			(at 0 0.699 180)
			(layer "B.SilkS")
			(hide yes)
			(effects
				(font
					(size 0.7 0.7)
					(thickness 0.15)
				)
				(justify left bottom mirror)
			)
		)
		(property "Value" "C_100n_0402"
			(at -1.022927 -2.155213 180)
			(layer "B.Fab")
			(effects
				(font
					(size 0.7 0.7)
					(thickness 0.15)
				)
				(justify left bottom mirror)
			)
		)
		(property "Datasheet" "https://www.murata.com/products/productdetail?partno=GRM155R61H104KE14%23"
			(at 0 0 0)
			(layer "F.Fab")
			(hide yes)
			(effects
				(font
					(size 1.27 1.27)
					(thickness 0.15)
				)
			)
		)
		(property "Author" "Antmicro"
			(at 0 0 0)
			(layer "B.Fab")
			(hide yes)
			(effects
				(font
					(size 1 1)
					(thickness 0.15)
				)
				(justify mirror)
			)
		)
		(property "Dielectric" "X5R"
			(at 0 0 0)
			(layer "B.Fab")
			(hide yes)
			(effects
				(font
					(size 1 1)
					(thickness 0.15)
				)
				(justify mirror)
			)
		)
		(property "License" "Apache-2.0"
			(at 0 0 0)
			(layer "B.Fab")
			(hide yes)
			(effects
				(font
					(size 1 1)
					(thickness 0.15)
				)
				(justify mirror)
			)
		)
		(property "MPN" "GRM155R61H104KE14D"
			(at 0 0 0)
			(layer "B.Fab")
			(hide yes)
			(effects
				(font
					(size 1 1)
					(thickness 0.15)
				)
				(justify mirror)
			)
		)
		(property "Manufacturer" "Murata"
			(at 0 0 0)
			(layer "B.Fab")
			(hide yes)
			(effects
				(font
					(size 1 1)
					(thickness 0.15)
				)
				(justify mirror)
			)
		)
		(property "Val" "100n"
			(at 0 0 0)
			(layer "B.Fab")
			(hide yes)
			(effects
				(font
					(size 1 1)
					(thickness 0.15)
				)
				(justify mirror)
			)
		)
		(property "Voltage" "50V"
			(at 0 0 0)
			(layer "B.Fab")
			(hide yes)
			(effects
				(font
					(size 1 1)
					(thickness 0.15)
				)
				(justify mirror)
			)
		)
		(sheetname "/Supply/")
		(sheetfile "supply.kicad_sch")
		(attr smd)
		(fp_rect
			(start -0.9659 0.481258)
			(end 0.9649 -0.458742)
			(stroke
				(width 0.05)
				(type solid)
			)
			(fill no)
			(layer "B.CrtYd")
		)
		(fp_line
			(start -0.499 -0.248)
			(end -0.499 0.25)
			(stroke
				(width 0.15)
				(type solid)
			)
			(layer "B.Fab")
		)
		(fp_line
			(start -0.499 0.25)
			(end 0.499 0.25)
			(stroke
				(width 0.15)
				(type solid)
			)
			(layer "B.Fab")
		)
		(fp_line
			(start 0.499 -0.248)
			(end -0.499 -0.248)
			(stroke
				(width 0.15)
				(type solid)
			)
			(layer "B.Fab")
		)
		(fp_line
			(start 0.499 0.25)
			(end 0.499 -0.248)
			(stroke
				(width 0.15)
				(type solid)
			)
			(layer "B.Fab")
		)
		(pad "1" smd roundrect
			(at -0.484 0)
			(size 0.59 0.64)
			(layers "B.Cu" "B.Mask" "B.Paste")
			(roundrect_rratio 0.25)
			(net 1 "GND")
			(pintype "passive")
		)
		(pad "2" smd roundrect
			(at 0.484 0)
			(size 0.59 0.64)
			(layers "B.Cu" "B.Mask" "B.Paste")
			(roundrect_rratio 0.25)
			(net 38 "VDC")
			(pintype "passive")
		)
	)
	(footprint "antmicro-footprints:R_0402_1005Metric"
		(layer "B.Cu")
		(at 141.67 142.4 -90)
		(descr "Resistor SMD 0402")
		(tags "resistor SMD 0402")
		(property "Reference" "R30"
			(at -3.044968 -0.354606 90)
			(layer "B.SilkS")
			(effects
				(font
					(size 0.7 0.7)
					(thickness 0.15)
				)
				(justify left bottom mirror)
			)
		)
		(property "Value" "R_0R_0402"
			(at -1.011843 -1.772047 90)
			(layer "B.Fab")
			(effects
				(font
					(size 0.7 0.7)
					(thickness 0.15)
				)
				(justify left bottom mirror)
			)
		)
		(property "Datasheet" "https://industrial.panasonic.com/cdbs/www-data/pdf/RDA0000/AOA0000C301.pdf"
			(at 0 0 270)
			(layer "F.Fab")
			(hide yes)
			(effects
				(font
					(size 1.27 1.27)
					(thickness 0.15)
				)
			)
		)
		(property "Author" "Antmicro"
			(at -0.73 284.07 0)
			(layer "B.Fab")
			(hide yes)
			(effects
				(font
					(size 1 1)
					(thickness 0.15)
				)
				(justify mirror)
			)
		)
		(property "Current" "1A"
			(at -0.73 284.07 0)
			(layer "B.Fab")
			(hide yes)
			(effects
				(font
					(size 1 1)
					(thickness 0.15)
				)
				(justify mirror)
			)
		)
		(property "License" "Apache-2.0"
			(at -0.73 284.07 0)
			(layer "B.Fab")
			(hide yes)
			(effects
				(font
					(size 1 1)
					(thickness 0.15)
				)
				(justify mirror)
			)
		)
		(property "MPN" "ERJ2GE0R00X"
			(at -0.73 284.07 0)
			(layer "B.Fab")
			(hide yes)
			(effects
				(font
					(size 1 1)
					(thickness 0.15)
				)
				(justify mirror)
			)
		)
		(property "Manufacturer" "Panasonic"
			(at -0.73 284.07 0)
			(layer "B.Fab")
			(hide yes)
			(effects
				(font
					(size 1 1)
					(thickness 0.15)
				)
				(justify mirror)
			)
		)
		(property "Tolerance" ""
			(at -0.73 284.07 0)
			(layer "B.Fab")
			(hide yes)
			(effects
				(font
					(size 1 1)
					(thickness 0.15)
				)
				(justify mirror)
			)
		)
		(property "Val" "0R"
			(at -0.73 284.07 0)
			(layer "B.Fab")
			(hide yes)
			(effects
				(font
					(size 1 1)
					(thickness 0.15)
				)
				(justify mirror)
			)
		)
		(sheetname "/DDR5 SODIMM/")
		(sheetfile "ddr5-sodimm.kicad_sch")
		(attr exclude_from_pos_files exclude_from_bom dnp)
		(fp_rect
			(start -0.93 0.47)
			(end 0.93 -0.47)
			(stroke
				(width 0.05)
				(type solid)
			)
			(fill no)
			(layer "B.CrtYd")
		)
		(fp_rect
			(start -0.5 0.25)
			(end 0.5 -0.25)
			(stroke
				(width 0.15)
				(type solid)
			)
			(fill no)
			(layer "B.Fab")
		)
		(pad "1" smd roundrect
			(at -0.485 0 270)
			(size 0.59 0.64)
			(layers "B.Cu" "B.Mask" "B.Paste")
			(roundrect_rratio 0.25)
			(net 1 "GND")
			(pintype "passive")
		)
		(pad "2" smd roundrect
			(at 0.485 0 270)
			(size 0.59 0.64)
			(layers "B.Cu" "B.Mask" "B.Paste")
			(roundrect_rratio 0.25)
			(net 171 "/DDR5 SODIMM/RFU2")
			(pintype "passive")
		)
	)
	(footprint "antmicro-footprints:C_0402_1005Metric"
		(layer "B.Cu")
		(at 141.375501 177.801 90)
		(descr "Capacitor SMD 0402 (1005 Metric), square (rectangular) end terminal, IPC_7351 nominal, (Body size source: IPC-SM-782 page 76, https://www.pcb-3d.com/wordpress/wp-content/uploads/ipc-sm-782a_amendment_1_and_2.pdf)")
		(tags "capacitor 0402")
		(property "Reference" "C50"
			(at 0 1.17 270)
			(layer "B.SilkS")
			(hide yes)
			(effects
				(font
					(size 0.7 0.7)
					(thickness 0.15)
				)
				(justify left bottom mirror)
			)
		)
		(property "Value" "C_4u7_0402"
			(at 0 -1.169 270)
			(layer "B.Fab")
			(effects
				(font
					(size 0.7 0.7)
					(thickness 0.15)
				)
				(justify left bottom mirror)
			)
		)
		(property "Datasheet" "https://www.murata.com/products/productdetail?partno=GRM155R61A475MEAA%23"
			(at 0 0 90)
			(layer "F.Fab")
			(hide yes)
			(effects
				(font
					(size 1.27 1.27)
					(thickness 0.15)
				)
			)
		)
		(property "Author" "Antmicro"
			(at 319.176501 36.425499 0)
			(layer "B.Fab")
			(hide yes)
			(effects
				(font
					(size 1 1)
					(thickness 0.15)
				)
				(justify mirror)
			)
		)
		(property "Dielectric" ""
			(at 319.176501 36.425499 0)
			(layer "B.Fab")
			(hide yes)
			(effects
				(font
					(size 1 1)
					(thickness 0.15)
				)
				(justify mirror)
			)
		)
		(property "License" "Apache-2.0"
			(at 319.176501 36.425499 0)
			(layer "B.Fab")
			(hide yes)
			(effects
				(font
					(size 1 1)
					(thickness 0.15)
				)
				(justify mirror)
			)
		)
		(property "MPN" "GRM155R61A475MEAAD"
			(at 319.176501 36.425499 0)
			(layer "B.Fab")
			(hide yes)
			(effects
				(font
					(size 1 1)
					(thickness 0.15)
				)
				(justify mirror)
			)
		)
		(property "Manufacturer" "Murata"
			(at 319.176501 36.425499 0)
			(layer "B.Fab")
			(hide yes)
			(effects
				(font
					(size 1 1)
					(thickness 0.15)
				)
				(justify mirror)
			)
		)
		(property "Val" "4u7"
			(at 319.176501 36.425499 0)
			(layer "B.Fab")
			(hide yes)
			(effects
				(font
					(size 1 1)
					(thickness 0.15)
				)
				(justify mirror)
			)
		)
		(property "Voltage" ""
			(at 319.176501 36.425499 0)
			(layer "B.Fab")
			(hide yes)
			(effects
				(font
					(size 1 1)
					(thickness 0.15)
				)
				(justify mirror)
			)
		)
		(sheetname "/FPGA power/")
		(sheetfile "fpga-power.kicad_sch")
		(attr smd)
		(fp_rect
			(start -0.9656 0.4572)
			(end 0.9652 -0.4828)
			(stroke
				(width 0.05)
				(type solid)
			)
			(fill no)
			(layer "B.CrtYd")
		)
		(fp_line
			(start 0.498 -0.248)
			(end -0.5 -0.248)
			(stroke
				(width 0.15)
				(type solid)
			)
			(layer "B.Fab")
		)
		(fp_line
			(start -0.5 -0.248)
			(end -0.5 0.25)
			(stroke
				(width 0.15)
				(type solid)
			)
			(layer "B.Fab")
		)
		(fp_line
			(start 0.498 0.25)
			(end 0.498 -0.248)
			(stroke
				(width 0.15)
				(type solid)
			)
			(layer "B.Fab")
		)
		(fp_line
			(start -0.5 0.25)
			(end 0.498 0.25)
			(stroke
				(width 0.15)
				(type solid)
			)
			(layer "B.Fab")
		)
		(pad "1" smd roundrect
			(at -0.5 0)
			(size 0.6 0.6)
			(layers "B.Cu" "B.Mask" "B.Paste")
			(roundrect_rratio 0.25)
			(net 188 "+1V8")
			(pintype "passive")
		)
		(pad "2" smd roundrect
			(at 0.498 0 90)
			(size 0.6 0.6)
			(layers "B.Cu" "B.Mask" "B.Paste")
			(roundrect_rratio 0.25)
			(net 1 "GND")
			(pintype "passive")
		)
	)
	(footprint "antmicro-footprints:R_0402_1005Metric"
		(layer "B.Cu")
		(at 125.877001 173.3005)
		(descr "Resistor SMD 0402 (1005 Metric), square (rectangular) end terminal, IPC_7351 nominal, (Body size source: IPC-SM-782 page 76, https://www.pcb-3d.com/wordpress/wp-content/uploads/ipc-sm-782a_amendment_1_and_2.pdf)")
		(tags "resistor 0402")
		(property "Reference" "R96"
			(at 0 1.17 180)
			(layer "B.SilkS")
			(hide yes)
			(effects
				(font
					(size 0.7 0.7)
					(thickness 0.15)
				)
				(justify left bottom mirror)
			)
		)
		(property "Value" "R_0R_0402"
			(at 0 -1.169 180)
			(layer "B.Fab")
			(effects
				(font
					(size 0.7 0.7)
					(thickness 0.15)
				)
				(justify left bottom mirror)
			)
		)
		(property "Datasheet" "https://industrial.panasonic.com/cdbs/www-data/pdf/RDA0000/AOA0000C301.pdf"
			(at 0 0 0)
			(layer "F.Fab")
			(hide yes)
			(effects
				(font
					(size 1.27 1.27)
					(thickness 0.15)
				)
			)
		)
		(property "Author" "Antmicro"
			(at 0 0 0)
			(layer "B.Fab")
			(hide yes)
			(effects
				(font
					(size 1 1)
					(thickness 0.15)
				)
				(justify mirror)
			)
		)
		(property "Current" "1A"
			(at 0 0 0)
			(layer "B.Fab")
			(hide yes)
			(effects
				(font
					(size 1 1)
					(thickness 0.15)
				)
				(justify mirror)
			)
		)
		(property "License" "Apache-2.0"
			(at 0 0 0)
			(layer "B.Fab")
			(hide yes)
			(effects
				(font
					(size 1 1)
					(thickness 0.15)
				)
				(justify mirror)
			)
		)
		(property "MPN" "ERJ2GE0R00X"
			(at 0 0 0)
			(layer "B.Fab")
			(hide yes)
			(effects
				(font
					(size 1 1)
					(thickness 0.15)
				)
				(justify mirror)
			)
		)
		(property "Manufacturer" "Panasonic"
			(at 0 0 0)
			(layer "B.Fab")
			(hide yes)
			(effects
				(font
					(size 1 1)
					(thickness 0.15)
				)
				(justify mirror)
			)
		)
		(property "Tolerance" ""
			(at 0 0 0)
			(layer "B.Fab")
			(hide yes)
			(effects
				(font
					(size 1 1)
					(thickness 0.15)
				)
				(justify mirror)
			)
		)
		(property "Val" "0R"
			(at 0 0 0)
			(layer "B.Fab")
			(hide yes)
			(effects
				(font
					(size 1 1)
					(thickness 0.15)
				)
				(justify mirror)
			)
		)
		(sheetname "/FPGA banks unused/")
		(sheetfile "fpga-bank-13-15.kicad_sch")
		(attr smd)
		(fp_line
			(start -0.95 -0.45)
			(end -0.95 0.46)
			(stroke
				(width 0.05)
				(type solid)
			)
			(layer "B.CrtYd")
		)
		(fp_line
			(start -0.95 0.46)
			(end 0.9652 0.46)
			(stroke
				(width 0.05)
				(type solid)
			)
			(layer "B.CrtYd")
		)
		(fp_line
			(start 0.9652 -0.45)
			(end -0.95 -0.45)
			(stroke
				(width 0.05)
				(type solid)
			)
			(layer "B.CrtYd")
		)
		(fp_line
			(start 0.9652 0.46)
			(end 0.9652 -0.45)
			(stroke
				(width 0.05)
				(type solid)
			)
			(layer "B.CrtYd")
		)
		(fp_line
			(start -0.5 -0.249)
			(end -0.5 0.25)
			(stroke
				(width 0.15)
				(type solid)
			)
			(layer "B.Fab")
		)
		(fp_line
			(start -0.5 0.25)
			(end 0.499 0.25)
			(stroke
				(width 0.15)
				(type solid)
			)
			(layer "B.Fab")
		)
		(fp_line
			(start 0.499 -0.249)
			(end -0.5 -0.249)
			(stroke
				(width 0.15)
				(type solid)
			)
			(layer "B.Fab")
		)
		(fp_line
			(start 0.499 0.25)
			(end 0.499 -0.249)
			(stroke
				(width 0.15)
				(type solid)
			)
			(layer "B.Fab")
		)
		(pad "1" smd roundrect
			(at -0.5 0 270)
			(size 0.6 0.6)
			(layers "B.Cu" "B.Mask" "B.Paste")
			(roundrect_rratio 0.25)
			(net 200 "+3V3")
			(pintype "passive")
		)
		(pad "2" smd roundrect
			(at 0.499 0)
			(size 0.6 0.6)
			(layers "B.Cu" "B.Mask" "B.Paste")
			(roundrect_rratio 0.25)
			(net 376 "Net-(R96-Pad2)")
			(pintype "passive")
		)
	)
	(footprint "antmicro-footprints:C_0402_1005Metric"
		(layer "B.Cu")
		(at 147.875501 176.301 180)
		(descr "Capacitor SMD 0402 (1005 Metric), square (rectangular) end terminal, IPC_7351 nominal, (Body size source: IPC-SM-782 page 76, https://www.pcb-3d.com/wordpress/wp-content/uploads/ipc-sm-782a_amendment_1_and_2.pdf)")
		(tags "capacitor 0402")
		(property "Reference" "C96"
			(at 0 1.17 0)
			(layer "B.SilkS")
			(hide yes)
			(effects
				(font
					(size 0.7 0.7)
					(thickness 0.15)
				)
				(justify left bottom mirror)
			)
		)
		(property "Value" "C_100n_0402"
			(at 0 -1.169 0)
			(layer "B.Fab")
			(effects
				(font
					(size 0.7 0.7)
					(thickness 0.15)
				)
				(justify left bottom mirror)
			)
		)
		(property "Datasheet" "https://www.murata.com/products/productdetail?partno=GRM155R61H104KE14%23"
			(at 0 0 180)
			(layer "F.Fab")
			(hide yes)
			(effects
				(font
					(size 1.27 1.27)
					(thickness 0.15)
				)
			)
		)
		(property "Author" "Antmicro"
			(at 295.751002 352.602 0)
			(layer "B.Fab")
			(hide yes)
			(effects
				(font
					(size 1 1)
					(thickness 0.15)
				)
				(justify mirror)
			)
		)
		(property "Dielectric" "X5R"
			(at 295.751002 352.602 0)
			(layer "B.Fab")
			(hide yes)
			(effects
				(font
					(size 1 1)
					(thickness 0.15)
				)
				(justify mirror)
			)
		)
		(property "License" "Apache-2.0"
			(at 295.751002 352.602 0)
			(layer "B.Fab")
			(hide yes)
			(effects
				(font
					(size 1 1)
					(thickness 0.15)
				)
				(justify mirror)
			)
		)
		(property "MPN" "GRM155R61H104KE14D"
			(at 295.751002 352.602 0)
			(layer "B.Fab")
			(hide yes)
			(effects
				(font
					(size 1 1)
					(thickness 0.15)
				)
				(justify mirror)
			)
		)
		(property "Manufacturer" "Murata"
			(at 295.751002 352.602 0)
			(layer "B.Fab")
			(hide yes)
			(effects
				(font
					(size 1 1)
					(thickness 0.15)
				)
				(justify mirror)
			)
		)
		(property "Val" "100n"
			(at 295.751002 352.602 0)
			(layer "B.Fab")
			(hide yes)
			(effects
				(font
					(size 1 1)
					(thickness 0.15)
				)
				(justify mirror)
			)
		)
		(property "Voltage" "50V"
			(at 295.751002 352.602 0)
			(layer "B.Fab")
			(hide yes)
			(effects
				(font
					(size 1 1)
					(thickness 0.15)
				)
				(justify mirror)
			)
		)
		(sheetname "/FPGA power/")
		(sheetfile "fpga-power.kicad_sch")
		(attr smd)
		(fp_rect
			(start -0.9656 0.4572)
			(end 0.9652 -0.4828)
			(stroke
				(width 0.05)
				(type solid)
			)
			(fill no)
			(layer "B.CrtYd")
		)
		(fp_line
			(start 0.498 0.25)
			(end 0.498 -0.248)
			(stroke
				(width 0.15)
				(type solid)
			)
			(layer "B.Fab")
		)
		(fp_line
			(start 0.498 -0.248)
			(end -0.5 -0.248)
			(stroke
				(width 0.15)
				(type solid)
			)
			(layer "B.Fab")
		)
		(fp_line
			(start -0.5 0.25)
			(end 0.498 0.25)
			(stroke
				(width 0.15)
				(type solid)
			)
			(layer "B.Fab")
		)
		(fp_line
			(start -0.5 -0.248)
			(end -0.5 0.25)
			(stroke
				(width 0.15)
				(type solid)
			)
			(layer "B.Fab")
		)
		(pad "1" smd roundrect
			(at -0.5 0 90)
			(size 0.6 0.6)
			(layers "B.Cu" "B.Mask" "B.Paste")
			(roundrect_rratio 0.25)
			(net 1 "GND")
			(pintype "passive")
		)
		(pad "2" smd roundrect
			(at 0.498 0 180)
			(size 0.6 0.6)
			(layers "B.Cu" "B.Mask" "B.Paste")
			(roundrect_rratio 0.25)
			(net 188 "+1V8")
			(pintype "passive")
		)
	)
	(footprint "antmicro-footprints:R_0402_1005Metric"
		(layer "B.Cu")
		(at 147.877001 177.3025)
		(descr "Resistor SMD 0402 (1005 Metric), square (rectangular) end terminal, IPC_7351 nominal, (Body size source: IPC-SM-782 page 76, https://www.pcb-3d.com/wordpress/wp-content/uploads/ipc-sm-782a_amendment_1_and_2.pdf)")
		(tags "resistor 0402")
		(property "Reference" "R39"
			(at 0 1.17 180)
			(layer "B.SilkS")
			(hide yes)
			(effects
				(font
					(size 0.7 0.7)
					(thickness 0.15)
				)
				(justify left bottom mirror)
			)
		)
		(property "Value" "R_100R_0402"
			(at 0 -1.169 180)
			(layer "B.Fab")
			(effects
				(font
					(size 0.7 0.7)
					(thickness 0.15)
				)
				(justify left bottom mirror)
			)
		)
		(property "Datasheet" "https://www.bourns.com/docs/product-datasheets/cr.pdf"
			(at 0 0 0)
			(layer "F.Fab")
			(hide yes)
			(effects
				(font
					(size 1.27 1.27)
					(thickness 0.15)
				)
			)
		)
		(property "Author" "Antmicro"
			(at 0 0 0)
			(layer "B.Fab")
			(hide yes)
			(effects
				(font
					(size 1 1)
					(thickness 0.15)
				)
				(justify mirror)
			)
		)
		(property "License" "Apache-2.0"
			(at 0 0 0)
			(layer "B.Fab")
			(hide yes)
			(effects
				(font
					(size 1 1)
					(thickness 0.15)
				)
				(justify mirror)
			)
		)
		(property "MPN" "CR0402-FX-1000GLF"
			(at 0 0 0)
			(layer "B.Fab")
			(hide yes)
			(effects
				(font
					(size 1 1)
					(thickness 0.15)
				)
				(justify mirror)
			)
		)
		(property "Manufacturer" "Bourns"
			(at 0 0 0)
			(layer "B.Fab")
			(hide yes)
			(effects
				(font
					(size 1 1)
					(thickness 0.15)
				)
				(justify mirror)
			)
		)
		(property "Tolerance" "1%"
			(at 0 0 0)
			(layer "B.Fab")
			(hide yes)
			(effects
				(font
					(size 1 1)
					(thickness 0.15)
				)
				(justify mirror)
			)
		)
		(property "Val" "100R"
			(at 0 0 0)
			(layer "B.Fab")
			(hide yes)
			(effects
				(font
					(size 1 1)
					(thickness 0.15)
				)
				(justify mirror)
			)
		)
		(sheetname "/FPGA power/")
		(sheetfile "fpga-power.kicad_sch")
		(attr smd)
		(fp_line
			(start -0.95 -0.45)
			(end -0.95 0.46)
			(stroke
				(width 0.05)
				(type solid)
			)
			(layer "B.CrtYd")
		)
		(fp_line
			(start -0.95 0.46)
			(end 0.9652 0.46)
			(stroke
				(width 0.05)
				(type solid)
			)
			(layer "B.CrtYd")
		)
		(fp_line
			(start 0.9652 -0.45)
			(end -0.95 -0.45)
			(stroke
				(width 0.05)
				(type solid)
			)
			(layer "B.CrtYd")
		)
		(fp_line
			(start 0.9652 0.46)
			(end 0.9652 -0.45)
			(stroke
				(width 0.05)
				(type solid)
			)
			(layer "B.CrtYd")
		)
		(fp_line
			(start -0.5 -0.249)
			(end -0.5 0.25)
			(stroke
				(width 0.15)
				(type solid)
			)
			(layer "B.Fab")
		)
		(fp_line
			(start -0.5 0.25)
			(end 0.499 0.25)
			(stroke
				(width 0.15)
				(type solid)
			)
			(layer "B.Fab")
		)
		(fp_line
			(start 0.499 -0.249)
			(end -0.5 -0.249)
			(stroke
				(width 0.15)
				(type solid)
			)
			(layer "B.Fab")
		)
		(fp_line
			(start 0.499 0.25)
			(end 0.499 -0.249)
			(stroke
				(width 0.15)
				(type solid)
			)
			(layer "B.Fab")
		)
		(pad "1" smd roundrect
			(at -0.5 0 270)
			(size 0.6 0.6)
			(layers "B.Cu" "B.Mask" "B.Paste")
			(roundrect_rratio 0.25)
			(net 369 "Net-(U4J-MGTRREF_115)")
			(pintype "passive")
		)
		(pad "2" smd roundrect
			(at 0.499 0)
			(size 0.6 0.6)
			(layers "B.Cu" "B.Mask" "B.Paste")
			(roundrect_rratio 0.25)
			(net 226 "+1V2_MGTAVTT")
			(pintype "passive")
		)
	)
	(footprint "antmicro-footprints:TP_SMD_1mm"
		(layer "B.Cu")
		(at 124.2 186.2 180)
		(property "Reference" "TP23"
			(at 0 0.731898 0)
			(layer "B.SilkS")
			(hide yes)
			(effects
				(font
					(size 0.7 0.7)
					(thickness 0.15)
				)
				(justify left bottom mirror)
			)
		)
		(property "Value" "TP_1mm_SMD"
			(at 0 -1.4 0)
			(layer "B.Fab")
			(effects
				(font
					(size 0.7 0.7)
					(thickness 0.15)
				)
				(justify left bottom mirror)
			)
		)
		(property "Author" "Antmicro"
			(at 248.4 372.4 0)
			(layer "B.Fab")
			(hide yes)
			(effects
				(font
					(size 1 1)
					(thickness 0.15)
				)
				(justify mirror)
			)
		)
		(property "License" "Apache-2.0"
			(at 248.4 372.4 0)
			(layer "B.Fab")
			(hide yes)
			(effects
				(font
					(size 1 1)
					(thickness 0.15)
				)
				(justify mirror)
			)
		)
		(property "MPN" ""
			(at 248.4 372.4 0)
			(layer "B.Fab")
			(hide yes)
			(effects
				(font
					(size 1 1)
					(thickness 0.15)
				)
				(justify mirror)
			)
		)
		(property "Manufacturer" ""
			(at 248.4 372.4 0)
			(layer "B.Fab")
			(hide yes)
			(effects
				(font
					(size 1 1)
					(thickness 0.15)
				)
				(justify mirror)
			)
		)
		(sheetname "/FPGA bank 14/")
		(sheetfile "fpga-bank-14.kicad_sch")
		(attr exclude_from_pos_files)
		(pad "1" smd circle
			(at 0 0 180)
			(size 1 1)
			(layers "B.Cu" "B.Mask")
			(net 612 "/FPGA bank 14/PUDC_B")
			(pinfunction "1")
			(pintype "passive")
		)
	)
	(footprint "antmicro-footprints:TP_SMD_1mm"
		(layer "B.Cu")
		(at 110 181.63 180)
		(property "Reference" "TP52"
			(at -3.2 -0.37 0)
			(layer "B.SilkS")
			(effects
				(font
					(size 0.7 0.7)
					(thickness 0.15)
				)
				(justify left bottom mirror)
			)
		)
		(property "Value" "TP_1mm_SMD"
			(at 0 -1.4 0)
			(layer "B.Fab")
			(effects
				(font
					(size 0.7 0.7)
					(thickness 0.15)
				)
				(justify left bottom mirror)
			)
		)
		(property "MPN" ""
			(at 0 0 0)
			(unlocked yes)
			(layer "B.Fab")
			(hide yes)
			(effects
				(font
					(size 1 1)
					(thickness 0.15)
				)
				(justify mirror)
			)
		)
		(property "Manufacturer" ""
			(at 0 0 0)
			(unlocked yes)
			(layer "B.Fab")
			(hide yes)
			(effects
				(font
					(size 1 1)
					(thickness 0.15)
				)
				(justify mirror)
			)
		)
		(property "Author" "Antmicro"
			(at 0 0 0)
			(unlocked yes)
			(layer "B.Fab")
			(hide yes)
			(effects
				(font
					(size 1 1)
					(thickness 0.15)
				)
				(justify mirror)
			)
		)
		(property "License" "Apache-2.0"
			(at 0 0 0)
			(unlocked yes)
			(layer "B.Fab")
			(hide yes)
			(effects
				(font
					(size 1 1)
					(thickness 0.15)
				)
				(justify mirror)
			)
		)
		(sheetname "/Debug FTDI/")
		(sheetfile "debug-ftdi.kicad_sch")
		(attr exclude_from_pos_files)
		(fp_circle
			(center 0 0)
			(end 0.6 0)
			(stroke
				(width 0.05)
				(type default)
			)
			(fill no)
			(layer "B.CrtYd")
		)
		(fp_text user "License: Apache-2.0"
			(at -0.5 -5.2 0)
			(layer "B.Fab")
			(effects
				(font
					(size 0.7 0.7)
					(thickness 0.15)
				)
				(justify left bottom mirror)
			)
		)
		(fp_text user "Author: Antmicro"
			(at -0.5 -4 0)
			(layer "B.Fab")
			(effects
				(font
					(size 0.7 0.7)
					(thickness 0.15)
				)
				(justify left bottom mirror)
			)
		)
		(fp_text user "${REFERENCE}"
			(at -0.5 -2.8 0)
			(layer "B.Fab")
			(effects
				(font
					(size 0.7 0.7)
					(thickness 0.15)
				)
				(justify left bottom mirror)
			)
		)
		(pad "1" smd circle
			(at 0 0 180)
			(size 1 1)
			(layers "B.Cu" "B.Mask")
			(net 1 "GND")
			(pinfunction "1")
			(pintype "passive")
		)
	)
	(footprint "antmicro-footprints:C_0402_1005Metric"
		(layer "B.Cu")
		(at 144.875001 180.3025 180)
		(descr "Capacitor SMD 0402 (1005 Metric), square (rectangular) end terminal, IPC_7351 nominal, (Body size source: IPC-SM-782 page 76, https://www.pcb-3d.com/wordpress/wp-content/uploads/ipc-sm-782a_amendment_1_and_2.pdf)")
		(tags "capacitor 0402")
		(property "Reference" "C92"
			(at 0 1.17 0)
			(layer "B.SilkS")
			(hide yes)
			(effects
				(font
					(size 0.7 0.7)
					(thickness 0.15)
				)
				(justify left bottom mirror)
			)
		)
		(property "Value" "C_100n_0402"
			(at 0 -1.169 0)
			(layer "B.Fab")
			(effects
				(font
					(size 0.7 0.7)
					(thickness 0.15)
				)
				(justify left bottom mirror)
			)
		)
		(property "Datasheet" "https://www.murata.com/products/productdetail?partno=GRM155R61H104KE14%23"
			(at 0 0 180)
			(layer "F.Fab")
			(hide yes)
			(effects
				(font
					(size 1.27 1.27)
					(thickness 0.15)
				)
			)
		)
		(property "Author" "Antmicro"
			(at 289.750002 360.605 0)
			(layer "B.Fab")
			(hide yes)
			(effects
				(font
					(size 1 1)
					(thickness 0.15)
				)
				(justify mirror)
			)
		)
		(property "Dielectric" "X5R"
			(at 289.750002 360.605 0)
			(layer "B.Fab")
			(hide yes)
			(effects
				(font
					(size 1 1)
					(thickness 0.15)
				)
				(justify mirror)
			)
		)
		(property "License" "Apache-2.0"
			(at 289.750002 360.605 0)
			(layer "B.Fab")
			(hide yes)
			(effects
				(font
					(size 1 1)
					(thickness 0.15)
				)
				(justify mirror)
			)
		)
		(property "MPN" "GRM155R61H104KE14D"
			(at 289.750002 360.605 0)
			(layer "B.Fab")
			(hide yes)
			(effects
				(font
					(size 1 1)
					(thickness 0.15)
				)
				(justify mirror)
			)
		)
		(property "Manufacturer" "Murata"
			(at 289.750002 360.605 0)
			(layer "B.Fab")
			(hide yes)
			(effects
				(font
					(size 1 1)
					(thickness 0.15)
				)
				(justify mirror)
			)
		)
		(property "Val" "100n"
			(at 289.750002 360.605 0)
			(layer "B.Fab")
			(hide yes)
			(effects
				(font
					(size 1 1)
					(thickness 0.15)
				)
				(justify mirror)
			)
		)
		(property "Voltage" "50V"
			(at 289.750002 360.605 0)
			(layer "B.Fab")
			(hide yes)
			(effects
				(font
					(size 1 1)
					(thickness 0.15)
				)
				(justify mirror)
			)
		)
		(sheetname "/FPGA power/")
		(sheetfile "fpga-power.kicad_sch")
		(attr smd)
		(fp_rect
			(start -0.9656 0.4572)
			(end 0.9652 -0.4828)
			(stroke
				(width 0.05)
				(type solid)
			)
			(fill no)
			(layer "B.CrtYd")
		)
		(fp_line
			(start 0.498 0.25)
			(end 0.498 -0.248)
			(stroke
				(width 0.15)
				(type solid)
			)
			(layer "B.Fab")
		)
		(fp_line
			(start 0.498 -0.248)
			(end -0.5 -0.248)
			(stroke
				(width 0.15)
				(type solid)
			)
			(layer "B.Fab")
		)
		(fp_line
			(start -0.5 0.25)
			(end 0.498 0.25)
			(stroke
				(width 0.15)
				(type solid)
			)
			(layer "B.Fab")
		)
		(fp_line
			(start -0.5 -0.248)
			(end -0.5 0.25)
			(stroke
				(width 0.15)
				(type solid)
			)
			(layer "B.Fab")
		)
		(pad "1" smd roundrect
			(at -0.5 0 90)
			(size 0.6 0.6)
			(layers "B.Cu" "B.Mask" "B.Paste")
			(roundrect_rratio 0.25)
			(net 1 "GND")
			(pintype "passive")
		)
		(pad "2" smd roundrect
			(at 0.498 0 180)
			(size 0.6 0.6)
			(layers "B.Cu" "B.Mask" "B.Paste")
			(roundrect_rratio 0.25)
			(net 227 "+1V0")
			(pintype "passive")
		)
	)
	(footprint "antmicro-footprints:C_0402_1005Metric"
		(layer "B.Cu")
		(at 145.525501 204.800501 90)
		(descr "Capacitor SMD 0402")
		(tags "capacitor SMD 0402")
		(property "Reference" "C230"
			(at 0 0.699 270)
			(layer "B.SilkS")
			(hide yes)
			(effects
				(font
					(size 0.7 0.7)
					(thickness 0.15)
				)
				(justify left bottom mirror)
			)
		)
		(property "Value" "C_100n_0402"
			(at -1.022927 -2.155213 270)
			(layer "B.Fab")
			(effects
				(font
					(size 0.7 0.7)
					(thickness 0.15)
				)
				(justify left bottom mirror)
			)
		)
		(property "Datasheet" "https://www.murata.com/products/productdetail?partno=GRM155R61H104KE14%23"
			(at 0 0 90)
			(layer "F.Fab")
			(hide yes)
			(effects
				(font
					(size 1.27 1.27)
					(thickness 0.15)
				)
			)
		)
		(property "Author" "Antmicro"
			(at 350.326002 59.275 0)
			(layer "B.Fab")
			(hide yes)
			(effects
				(font
					(size 1 1)
					(thickness 0.15)
				)
				(justify mirror)
			)
		)
		(property "Dielectric" "X5R"
			(at 350.326002 59.275 0)
			(layer "B.Fab")
			(hide yes)
			(effects
				(font
					(size 1 1)
					(thickness 0.15)
				)
				(justify mirror)
			)
		)
		(property "License" "Apache-2.0"
			(at 350.326002 59.275 0)
			(layer "B.Fab")
			(hide yes)
			(effects
				(font
					(size 1 1)
					(thickness 0.15)
				)
				(justify mirror)
			)
		)
		(property "MPN" "GRM155R61H104KE14D"
			(at 350.326002 59.275 0)
			(layer "B.Fab")
			(hide yes)
			(effects
				(font
					(size 1 1)
					(thickness 0.15)
				)
				(justify mirror)
			)
		)
		(property "Manufacturer" "Murata"
			(at 350.326002 59.275 0)
			(layer "B.Fab")
			(hide yes)
			(effects
				(font
					(size 1 1)
					(thickness 0.15)
				)
				(justify mirror)
			)
		)
		(property "Val" "100n"
			(at 350.326002 59.275 0)
			(layer "B.Fab")
			(hide yes)
			(effects
				(font
					(size 1 1)
					(thickness 0.15)
				)
				(justify mirror)
			)
		)
		(property "Voltage" "50V"
			(at 350.326002 59.275 0)
			(layer "B.Fab")
			(hide yes)
			(effects
				(font
					(size 1 1)
					(thickness 0.15)
				)
				(justify mirror)
			)
		)
		(sheetname "/FPGA MGT Interface/")
		(sheetfile "fpga-mgt.kicad_sch")
		(attr smd)
		(fp_rect
			(start -0.9659 0.481258)
			(end 0.9649 -0.458742)
			(stroke
				(width 0.05)
				(type solid)
			)
			(fill no)
			(layer "B.CrtYd")
		)
		(fp_line
			(start 0.499 -0.248)
			(end -0.499 -0.248)
			(stroke
				(width 0.15)
				(type solid)
			)
			(layer "B.Fab")
		)
		(fp_line
			(start -0.499 -0.248)
			(end -0.499 0.25)
			(stroke
				(width 0.15)
				(type solid)
			)
			(layer "B.Fab")
		)
		(fp_line
			(start 0.499 0.25)
			(end 0.499 -0.248)
			(stroke
				(width 0.15)
				(type solid)
			)
			(layer "B.Fab")
		)
		(fp_line
			(start -0.499 0.25)
			(end 0.499 0.25)
			(stroke
				(width 0.15)
				(type solid)
			)
			(layer "B.Fab")
		)
		(pad "1" smd roundrect
			(at -0.484 0 90)
			(size 0.59 0.64)
			(layers "B.Cu" "B.Mask" "B.Paste")
			(roundrect_rratio 0.25)
			(net 24 "/FPGA MGT Interface/PCIE.TXD3_N")
			(pintype "passive")
		)
		(pad "2" smd roundrect
			(at 0.484 0 90)
			(size 0.59 0.64)
			(layers "B.Cu" "B.Mask" "B.Paste")
			(roundrect_rratio 0.25)
			(net 25 "/FPGA MGT Interface/GTX_TX0_N")
			(pintype "passive")
		)
	)
	(footprint "antmicro-footprints:TP_SMD_1mm"
		(layer "B.Cu")
		(at 90.1 186.1 180)
		(property "Reference" "TP47"
			(at -1.2 0.6 0)
			(layer "B.SilkS")
			(effects
				(font
					(size 0.7 0.7)
					(thickness 0.15)
				)
				(justify left bottom mirror)
			)
		)
		(property "Value" "TP_1mm_SMD"
			(at 0 -1.4 0)
			(layer "B.Fab")
			(effects
				(font
					(size 0.7 0.7)
					(thickness 0.15)
				)
				(justify left bottom mirror)
			)
		)
		(property "MPN" ""
			(at 0 0 0)
			(unlocked yes)
			(layer "B.Fab")
			(hide yes)
			(effects
				(font
					(size 1 1)
					(thickness 0.15)
				)
				(justify mirror)
			)
		)
		(property "Manufacturer" ""
			(at 0 0 0)
			(unlocked yes)
			(layer "B.Fab")
			(hide yes)
			(effects
				(font
					(size 1 1)
					(thickness 0.15)
				)
				(justify mirror)
			)
		)
		(property "Author" "Antmicro"
			(at 0 0 0)
			(unlocked yes)
			(layer "B.Fab")
			(hide yes)
			(effects
				(font
					(size 1 1)
					(thickness 0.15)
				)
				(justify mirror)
			)
		)
		(property "License" "Apache-2.0"
			(at 0 0 0)
			(unlocked yes)
			(layer "B.Fab")
			(hide yes)
			(effects
				(font
					(size 1 1)
					(thickness 0.15)
				)
				(justify mirror)
			)
		)
		(sheetname "/Debug FTDI/")
		(sheetfile "debug-ftdi.kicad_sch")
		(attr exclude_from_pos_files)
		(fp_circle
			(center 0 0)
			(end 0.6 0)
			(stroke
				(width 0.05)
				(type default)
			)
			(fill no)
			(layer "B.CrtYd")
		)
		(fp_text user "License: Apache-2.0"
			(at -0.5 -5.2 0)
			(layer "B.Fab")
			(effects
				(font
					(size 0.7 0.7)
					(thickness 0.15)
				)
				(justify left bottom mirror)
			)
		)
		(fp_text user "Author: Antmicro"
			(at -0.5 -4 0)
			(layer "B.Fab")
			(effects
				(font
					(size 0.7 0.7)
					(thickness 0.15)
				)
				(justify left bottom mirror)
			)
		)
		(fp_text user "${REFERENCE}"
			(at -0.5 -2.8 0)
			(layer "B.Fab")
			(effects
				(font
					(size 0.7 0.7)
					(thickness 0.15)
				)
				(justify left bottom mirror)
			)
		)
		(pad "1" smd circle
			(at 0 0 180)
			(size 1 1)
			(layers "B.Cu" "B.Mask")
			(net 1 "GND")
			(pinfunction "1")
			(pintype "passive")
		)
	)
	(footprint "antmicro-footprints:C_0402_1005Metric"
		(layer "B.Cu")
		(at 128.875501 168.301 180)
		(descr "Capacitor SMD 0402 (1005 Metric), square (rectangular) end terminal, IPC_7351 nominal, (Body size source: IPC-SM-782 page 76, https://www.pcb-3d.com/wordpress/wp-content/uploads/ipc-sm-782a_amendment_1_and_2.pdf)")
		(tags "capacitor 0402")
		(property "Reference" "C46"
			(at 0 1.17 0)
			(layer "B.SilkS")
			(hide yes)
			(effects
				(font
					(size 0.7 0.7)
					(thickness 0.15)
				)
				(justify left bottom mirror)
			)
		)
		(property "Value" "C_100n_0402"
			(at 0 -1.169 0)
			(layer "B.Fab")
			(effects
				(font
					(size 0.7 0.7)
					(thickness 0.15)
				)
				(justify left bottom mirror)
			)
		)
		(property "Datasheet" "https://www.murata.com/products/productdetail?partno=GRM155R61H104KE14%23"
			(at 0 0 180)
			(layer "F.Fab")
			(hide yes)
			(effects
				(font
					(size 1.27 1.27)
					(thickness 0.15)
				)
			)
		)
		(property "Author" "Antmicro"
			(at 257.751002 336.602 0)
			(layer "B.Fab")
			(hide yes)
			(effects
				(font
					(size 1 1)
					(thickness 0.15)
				)
				(justify mirror)
			)
		)
		(property "Dielectric" "X5R"
			(at 257.751002 336.602 0)
			(layer "B.Fab")
			(hide yes)
			(effects
				(font
					(size 1 1)
					(thickness 0.15)
				)
				(justify mirror)
			)
		)
		(property "License" "Apache-2.0"
			(at 257.751002 336.602 0)
			(layer "B.Fab")
			(hide yes)
			(effects
				(font
					(size 1 1)
					(thickness 0.15)
				)
				(justify mirror)
			)
		)
		(property "MPN" "GRM155R61H104KE14D"
			(at 257.751002 336.602 0)
			(layer "B.Fab")
			(hide yes)
			(effects
				(font
					(size 1 1)
					(thickness 0.15)
				)
				(justify mirror)
			)
		)
		(property "Manufacturer" "Murata"
			(at 257.751002 336.602 0)
			(layer "B.Fab")
			(hide yes)
			(effects
				(font
					(size 1 1)
					(thickness 0.15)
				)
				(justify mirror)
			)
		)
		(property "Val" "100n"
			(at 257.751002 336.602 0)
			(layer "B.Fab")
			(hide yes)
			(effects
				(font
					(size 1 1)
					(thickness 0.15)
				)
				(justify mirror)
			)
		)
		(property "Voltage" "50V"
			(at 257.751002 336.602 0)
			(layer "B.Fab")
			(hide yes)
			(effects
				(font
					(size 1 1)
					(thickness 0.15)
				)
				(justify mirror)
			)
		)
		(sheetname "/FPGA power/")
		(sheetfile "fpga-power.kicad_sch")
		(attr smd)
		(fp_rect
			(start -0.9656 0.4572)
			(end 0.9652 -0.4828)
			(stroke
				(width 0.05)
				(type solid)
			)
			(fill no)
			(layer "B.CrtYd")
		)
		(fp_line
			(start 0.498 0.25)
			(end 0.498 -0.248)
			(stroke
				(width 0.15)
				(type solid)
			)
			(layer "B.Fab")
		)
		(fp_line
			(start 0.498 -0.248)
			(end -0.5 -0.248)
			(stroke
				(width 0.15)
				(type solid)
			)
			(layer "B.Fab")
		)
		(fp_line
			(start -0.5 0.25)
			(end 0.498 0.25)
			(stroke
				(width 0.15)
				(type solid)
			)
			(layer "B.Fab")
		)
		(fp_line
			(start -0.5 -0.248)
			(end -0.5 0.25)
			(stroke
				(width 0.15)
				(type solid)
			)
			(layer "B.Fab")
		)
		(pad "1" smd roundrect
			(at -0.5 0 90)
			(size 0.6 0.6)
			(layers "B.Cu" "B.Mask" "B.Paste")
			(roundrect_rratio 0.25)
			(net 1 "GND")
			(pintype "passive")
		)
		(pad "2" smd roundrect
			(at 0.498 0 180)
			(size 0.6 0.6)
			(layers "B.Cu" "B.Mask" "B.Paste")
			(roundrect_rratio 0.25)
			(net 200 "+3V3")
			(pintype "passive")
		)
	)
	(footprint "antmicro-footprints:Fiducial_1mm_Mask2mm"
		(layer "B.Cu")
		(at 197.010501 197.696 180)
		(descr "Circular Fiducial, 1mm bare copper, 3mm soldermask opening")
		(tags "fiducial")
		(property "Reference" "FID1002"
			(at 0 1.4 0)
			(layer "B.SilkS")
			(hide yes)
			(effects
				(font
					(size 0.7 0.7)
					(thickness 0.15)
				)
				(justify left bottom mirror)
			)
		)
		(property "Value" "Fiducial_1mm_Mask2mm"
			(at 0 -2.2 0)
			(layer "B.Fab")
			(effects
				(font
					(size 0.7 0.7)
					(thickness 0.15)
				)
				(justify left bottom mirror)
			)
		)
		(property "Author" "Antmicro"
			(at 394.021002 395.392 0)
			(layer "B.Fab")
			(hide yes)
			(effects
				(font
					(size 1 1)
					(thickness 0.15)
				)
				(justify mirror)
			)
		)
		(property "License" "Apache-2.0"
			(at 394.021002 395.392 0)
			(layer "B.Fab")
			(hide yes)
			(effects
				(font
					(size 1 1)
					(thickness 0.15)
				)
				(justify mirror)
			)
		)
		(property "MPN" ""
			(at 394.021002 395.392 0)
			(layer "B.Fab")
			(hide yes)
			(effects
				(font
					(size 1 1)
					(thickness 0.15)
				)
				(justify mirror)
			)
		)
		(property "Manufacturer" ""
			(at 394.021002 395.392 0)
			(layer "B.Fab")
			(hide yes)
			(effects
				(font
					(size 1 1)
					(thickness 0.15)
				)
				(justify mirror)
			)
		)
		(sheetfile "sodimm-ddr5-tester.kicad_sch")
		(attr board_only exclude_from_pos_files exclude_from_bom)
		(fp_circle
			(center 0 0)
			(end 1.24 0)
			(stroke
				(width 0.05)
				(type solid)
			)
			(fill no)
			(layer "B.CrtYd")
		)
		(fp_circle
			(center 0 0)
			(end 0.999 0)
			(stroke
				(width 0.15)
				(type solid)
			)
			(fill no)
			(layer "B.Fab")
		)
		(pad "" smd circle
			(at 0 0 180)
			(size 1 1)
			(layers "B.Cu" "B.Mask")
			(solder_mask_margin 0.5)
			(clearance 0.5)
		)
	)
	(footprint "antmicro-footprints:C_0402_1005Metric"
		(layer "B.Cu")
		(at 93.8 164.4515 180)
		(descr "Capacitor SMD 0402")
		(tags "capacitor SMD 0402")
		(property "Reference" "C161"
			(at 0 0.699 0)
			(layer "B.SilkS")
			(hide yes)
			(effects
				(font
					(size 0.7 0.7)
					(thickness 0.15)
				)
				(justify left bottom mirror)
			)
		)
		(property "Value" "C_100n_0402"
			(at -1.022927 -2.155213 0)
			(layer "B.Fab")
			(effects
				(font
					(size 0.7 0.7)
					(thickness 0.15)
				)
				(justify left bottom mirror)
			)
		)
		(property "Datasheet" "https://www.murata.com/products/productdetail?partno=GRM155R61H104KE14%23"
			(at 0 0 180)
			(layer "F.Fab")
			(hide yes)
			(effects
				(font
					(size 1.27 1.27)
					(thickness 0.15)
				)
			)
		)
		(property "Author" "Antmicro"
			(at 187.6 328.903 0)
			(layer "B.Fab")
			(hide yes)
			(effects
				(font
					(size 1 1)
					(thickness 0.15)
				)
				(justify mirror)
			)
		)
		(property "Dielectric" "X5R"
			(at 187.6 328.903 0)
			(layer "B.Fab")
			(hide yes)
			(effects
				(font
					(size 1 1)
					(thickness 0.15)
				)
				(justify mirror)
			)
		)
		(property "License" "Apache-2.0"
			(at 187.6 328.903 0)
			(layer "B.Fab")
			(hide yes)
			(effects
				(font
					(size 1 1)
					(thickness 0.15)
				)
				(justify mirror)
			)
		)
		(property "MPN" "GRM155R61H104KE14D"
			(at 187.6 328.903 0)
			(layer "B.Fab")
			(hide yes)
			(effects
				(font
					(size 1 1)
					(thickness 0.15)
				)
				(justify mirror)
			)
		)
		(property "Manufacturer" "Murata"
			(at 187.6 328.903 0)
			(layer "B.Fab")
			(hide yes)
			(effects
				(font
					(size 1 1)
					(thickness 0.15)
				)
				(justify mirror)
			)
		)
		(property "Val" "100n"
			(at 187.6 328.903 0)
			(layer "B.Fab")
			(hide yes)
			(effects
				(font
					(size 1 1)
					(thickness 0.15)
				)
				(justify mirror)
			)
		)
		(property "Voltage" "50V"
			(at 187.6 328.903 0)
			(layer "B.Fab")
			(hide yes)
			(effects
				(font
					(size 1 1)
					(thickness 0.15)
				)
				(justify mirror)
			)
		)
		(sheetname "/Ethernet/")
		(sheetfile "ethernet.kicad_sch")
		(attr smd)
		(fp_rect
			(start -0.9659 0.481258)
			(end 0.9649 -0.458742)
			(stroke
				(width 0.05)
				(type solid)
			)
			(fill no)
			(layer "B.CrtYd")
		)
		(fp_line
			(start 0.499 0.25)
			(end 0.499 -0.248)
			(stroke
				(width 0.15)
				(type solid)
			)
			(layer "B.Fab")
		)
		(fp_line
			(start 0.499 -0.248)
			(end -0.499 -0.248)
			(stroke
				(width 0.15)
				(type solid)
			)
			(layer "B.Fab")
		)
		(fp_line
			(start -0.499 0.25)
			(end 0.499 0.25)
			(stroke
				(width 0.15)
				(type solid)
			)
			(layer "B.Fab")
		)
		(fp_line
			(start -0.499 -0.248)
			(end -0.499 0.25)
			(stroke
				(width 0.15)
				(type solid)
			)
			(layer "B.Fab")
		)
		(pad "1" smd roundrect
			(at -0.484 0 180)
			(size 0.59 0.64)
			(layers "B.Cu" "B.Mask" "B.Paste")
			(roundrect_rratio 0.25)
			(net 1 "GND")
			(pintype "passive")
		)
		(pad "2" smd roundrect
			(at 0.484 0 180)
			(size 0.59 0.64)
			(layers "B.Cu" "B.Mask" "B.Paste")
			(roundrect_rratio 0.25)
			(net 200 "+3V3")
			(pintype "passive")
		)
	)
	(footprint "antmicro-footprints:C_0603_1608Metric"
		(layer "B.Cu")
		(at 139.575501 174.801 180)
		(descr "Capacitor SMD 0603")
		(tags "capacitor 0603")
		(property "Reference" "C18"
			(at 0 0.9 0)
			(layer "B.SilkS")
			(hide yes)
			(effects
				(font
					(size 0.7 0.7)
					(thickness 0.15)
				)
				(justify left bottom mirror)
			)
		)
		(property "Value" "C_47u_0603"
			(at 0 -1.6 0)
			(layer "B.Fab")
			(effects
				(font
					(size 0.7 0.7)
					(thickness 0.15)
				)
				(justify left bottom mirror)
			)
		)
		(property "Datasheet" "https://www.murata.com/products/productdetail?partno=GRM188R60J476ME15%23"
			(at 0 0 180)
			(layer "F.Fab")
			(hide yes)
			(effects
				(font
					(size 1.27 1.27)
					(thickness 0.15)
				)
			)
		)
		(property "Author" "Antmicro"
			(at 279.151002 349.602 0)
			(layer "B.Fab")
			(hide yes)
			(effects
				(font
					(size 1 1)
					(thickness 0.15)
				)
				(justify mirror)
			)
		)
		(property "Dielectric" ""
			(at 279.151002 349.602 0)
			(layer "B.Fab")
			(hide yes)
			(effects
				(font
					(size 1 1)
					(thickness 0.15)
				)
				(justify mirror)
			)
		)
		(property "License" "Apache-2.0"
			(at 279.151002 349.602 0)
			(layer "B.Fab")
			(hide yes)
			(effects
				(font
					(size 1 1)
					(thickness 0.15)
				)
				(justify mirror)
			)
		)
		(property "MPN" "GRM188R60J476ME15D"
			(at 279.151002 349.602 0)
			(layer "B.Fab")
			(hide yes)
			(effects
				(font
					(size 1 1)
					(thickness 0.15)
				)
				(justify mirror)
			)
		)
		(property "Manufacturer" "Murata"
			(at 279.151002 349.602 0)
			(layer "B.Fab")
			(hide yes)
			(effects
				(font
					(size 1 1)
					(thickness 0.15)
				)
				(justify mirror)
			)
		)
		(property "Val" "47u"
			(at 279.151002 349.602 0)
			(layer "B.Fab")
			(hide yes)
			(effects
				(font
					(size 1 1)
					(thickness 0.15)
				)
				(justify mirror)
			)
		)
		(property "Voltage" ""
			(at 279.151002 349.602 0)
			(layer "B.Fab")
			(hide yes)
			(effects
				(font
					(size 1 1)
					(thickness 0.15)
				)
				(justify mirror)
			)
		)
		(sheetname "/FPGA power/")
		(sheetfile "fpga-power.kicad_sch")
		(attr smd)
		(fp_line
			(start -0.3 0.3)
			(end 0.3 0.3)
			(stroke
				(width 0.15)
				(type solid)
			)
			(layer "B.SilkS")
		)
		(fp_line
			(start -0.3 -0.3)
			(end 0.3 -0.3)
			(stroke
				(width 0.15)
				(type solid)
			)
			(layer "B.SilkS")
		)
		(fp_rect
			(start -1.24 0.7)
			(end 1.24 -0.7)
			(stroke
				(width 0.05)
				(type solid)
			)
			(fill no)
			(layer "B.CrtYd")
		)
		(fp_rect
			(start -0.8 0.4)
			(end 0.8 -0.4)
			(stroke
				(width 0.15)
				(type solid)
			)
			(fill no)
			(layer "B.Fab")
		)
		(pad "1" smd roundrect
			(at -0.7 0 180)
			(size 0.6 0.8)
			(layers "B.Cu" "B.Mask" "B.Paste")
			(roundrect_rratio 0.2)
			(net 188 "+1V8")
			(pintype "passive")
		)
		(pad "2" smd roundrect
			(at 0.7 0 180)
			(size 0.6 0.8)
			(layers "B.Cu" "B.Mask" "B.Paste")
			(roundrect_rratio 0.2)
			(net 1 "GND")
			(pintype "passive")
		)
	)
	(footprint "antmicro-footprints:C_0402_1005Metric"
		(layer "B.Cu")
		(at 141.875501 180.301)
		(descr "Capacitor SMD 0402 (1005 Metric), square (rectangular) end terminal, IPC_7351 nominal, (Body size source: IPC-SM-782 page 76, https://www.pcb-3d.com/wordpress/wp-content/uploads/ipc-sm-782a_amendment_1_and_2.pdf)")
		(tags "capacitor 0402")
		(property "Reference" "C28"
			(at 0 1.17 180)
			(layer "B.SilkS")
			(hide yes)
			(effects
				(font
					(size 0.7 0.7)
					(thickness 0.15)
				)
				(justify left bottom mirror)
			)
		)
		(property "Value" "C_100n_0402"
			(at 0 -1.169 180)
			(layer "B.Fab")
			(effects
				(font
					(size 0.7 0.7)
					(thickness 0.15)
				)
				(justify left bottom mirror)
			)
		)
		(property "Datasheet" "https://www.murata.com/products/productdetail?partno=GRM155R61H104KE14%23"
			(at 0 0 0)
			(layer "F.Fab")
			(hide yes)
			(effects
				(font
					(size 1.27 1.27)
					(thickness 0.15)
				)
			)
		)
		(property "Author" "Antmicro"
			(at 0 0 0)
			(layer "B.Fab")
			(hide yes)
			(effects
				(font
					(size 1 1)
					(thickness 0.15)
				)
				(justify mirror)
			)
		)
		(property "Dielectric" "X5R"
			(at 0 0 0)
			(layer "B.Fab")
			(hide yes)
			(effects
				(font
					(size 1 1)
					(thickness 0.15)
				)
				(justify mirror)
			)
		)
		(property "License" "Apache-2.0"
			(at 0 0 0)
			(layer "B.Fab")
			(hide yes)
			(effects
				(font
					(size 1 1)
					(thickness 0.15)
				)
				(justify mirror)
			)
		)
		(property "MPN" "GRM155R61H104KE14D"
			(at 0 0 0)
			(layer "B.Fab")
			(hide yes)
			(effects
				(font
					(size 1 1)
					(thickness 0.15)
				)
				(justify mirror)
			)
		)
		(property "Manufacturer" "Murata"
			(at 0 0 0)
			(layer "B.Fab")
			(hide yes)
			(effects
				(font
					(size 1 1)
					(thickness 0.15)
				)
				(justify mirror)
			)
		)
		(property "Val" "100n"
			(at 0 0 0)
			(layer "B.Fab")
			(hide yes)
			(effects
				(font
					(size 1 1)
					(thickness 0.15)
				)
				(justify mirror)
			)
		)
		(property "Voltage" "50V"
			(at 0 0 0)
			(layer "B.Fab")
			(hide yes)
			(effects
				(font
					(size 1 1)
					(thickness 0.15)
				)
				(justify mirror)
			)
		)
		(sheetname "/FPGA power/")
		(sheetfile "fpga-power.kicad_sch")
		(attr smd)
		(fp_rect
			(start -0.9656 0.4572)
			(end 0.9652 -0.4828)
			(stroke
				(width 0.05)
				(type solid)
			)
			(fill no)
			(layer "B.CrtYd")
		)
		(fp_line
			(start -0.5 -0.248)
			(end -0.5 0.25)
			(stroke
				(width 0.15)
				(type solid)
			)
			(layer "B.Fab")
		)
		(fp_line
			(start -0.5 0.25)
			(end 0.498 0.25)
			(stroke
				(width 0.15)
				(type solid)
			)
			(layer "B.Fab")
		)
		(fp_line
			(start 0.498 -0.248)
			(end -0.5 -0.248)
			(stroke
				(width 0.15)
				(type solid)
			)
			(layer "B.Fab")
		)
		(fp_line
			(start 0.498 0.25)
			(end 0.498 -0.248)
			(stroke
				(width 0.15)
				(type solid)
			)
			(layer "B.Fab")
		)
		(pad "1" smd roundrect
			(at -0.5 0 270)
			(size 0.6 0.6)
			(layers "B.Cu" "B.Mask" "B.Paste")
			(roundrect_rratio 0.25)
			(net 1 "GND")
			(pintype "passive")
		)
		(pad "2" smd roundrect
			(at 0.498 0)
			(size 0.6 0.6)
			(layers "B.Cu" "B.Mask" "B.Paste")
			(roundrect_rratio 0.25)
			(net 200 "+3V3")
			(pintype "passive")
		)
	)
	(footprint "antmicro-footprints:TP_SMD_1mm"
		(layer "B.Cu")
		(at 186.4 167.45 180)
		(property "Reference" "TP30"
			(at 0 0.731898 0)
			(layer "B.SilkS")
			(hide yes)
			(effects
				(font
					(size 0.7 0.7)
					(thickness 0.15)
				)
				(justify left bottom mirror)
			)
		)
		(property "Value" "TP_1mm_SMD"
			(at 0 -1.4 0)
			(layer "B.Fab")
			(effects
				(font
					(size 0.7 0.7)
					(thickness 0.15)
				)
				(justify left bottom mirror)
			)
		)
		(property "MPN" ""
			(at 0 0 0)
			(unlocked yes)
			(layer "B.Fab")
			(hide yes)
			(effects
				(font
					(size 1 1)
					(thickness 0.15)
				)
				(justify mirror)
			)
		)
		(property "Manufacturer" ""
			(at 0 0 0)
			(unlocked yes)
			(layer "B.Fab")
			(hide yes)
			(effects
				(font
					(size 1 1)
					(thickness 0.15)
				)
				(justify mirror)
			)
		)
		(property "Author" "Antmicro"
			(at 0 0 0)
			(unlocked yes)
			(layer "B.Fab")
			(hide yes)
			(effects
				(font
					(size 1 1)
					(thickness 0.15)
				)
				(justify mirror)
			)
		)
		(property "License" "Apache-2.0"
			(at 0 0 0)
			(unlocked yes)
			(layer "B.Fab")
			(hide yes)
			(effects
				(font
					(size 1 1)
					(thickness 0.15)
				)
				(justify mirror)
			)
		)
		(sheetname "/Supply/")
		(sheetfile "supply.kicad_sch")
		(attr exclude_from_pos_files)
		(fp_circle
			(center 0 0)
			(end 0.6 0)
			(stroke
				(width 0.05)
				(type default)
			)
			(fill no)
			(layer "B.CrtYd")
		)
		(fp_text user "Author: Antmicro"
			(at -0.5 -4 0)
			(layer "B.Fab")
			(effects
				(font
					(size 0.7 0.7)
					(thickness 0.15)
				)
				(justify left bottom mirror)
			)
		)
		(fp_text user "${REFERENCE}"
			(at -0.5 -2.8 0)
			(layer "B.Fab")
			(effects
				(font
					(size 0.7 0.7)
					(thickness 0.15)
				)
				(justify left bottom mirror)
			)
		)
		(fp_text user "License: Apache-2.0"
			(at -0.5 -5.2 0)
			(layer "B.Fab")
			(effects
				(font
					(size 0.7 0.7)
					(thickness 0.15)
				)
				(justify left bottom mirror)
			)
		)
		(pad "1" smd circle
			(at 0 0 180)
			(size 1 1)
			(layers "B.Cu" "B.Mask")
			(net 200 "+3V3")
			(pinfunction "1")
			(pintype "passive")
		)
	)
	(footprint "antmicro-footprints:R_0402_1005Metric_EIA"
		(layer "B.Cu")
		(at 143.375001 170.8025 90)
		(descr "Resistor SMD 0402 (1005 Metric), square (rectangular) end terminal, IPC_7351 nominal, (Body size source: IPC-SM-782 page 76, https://www.pcb-3d.com/wordpress/wp-content/uploads/ipc-sm-782a_amendment_1_and_2.pdf)")
		(tags "resistor 0402")
		(property "Reference" "R133"
			(at 0 1.17 270)
			(layer "B.SilkS")
			(hide yes)
			(effects
				(font
					(size 0.7 0.7)
					(thickness 0.15)
				)
				(justify left bottom mirror)
			)
		)
		(property "Value" "R_80R6_0402_EIA"
			(at 0 -1.169 270)
			(layer "B.Fab")
			(effects
				(font
					(size 0.7 0.7)
					(thickness 0.15)
				)
				(justify left bottom mirror)
			)
		)
		(property "Datasheet" "https://www.bourns.com/docs/product-datasheets/cr.pdf"
			(at 0 0 90)
			(layer "F.Fab")
			(hide yes)
			(effects
				(font
					(size 1.27 1.27)
					(thickness 0.15)
				)
			)
		)
		(property "Author" "Antmicro"
			(at 314.177501 27.427499 0)
			(layer "B.Fab")
			(hide yes)
			(effects
				(font
					(size 1 1)
					(thickness 0.15)
				)
				(justify mirror)
			)
		)
		(property "License" "Apache-2.0"
			(at 314.177501 27.427499 0)
			(layer "B.Fab")
			(hide yes)
			(effects
				(font
					(size 1 1)
					(thickness 0.15)
				)
				(justify mirror)
			)
		)
		(property "MPN" "MC00625W0402180R6"
			(at 314.177501 27.427499 0)
			(layer "B.Fab")
			(hide yes)
			(effects
				(font
					(size 1 1)
					(thickness 0.15)
				)
				(justify mirror)
			)
		)
		(property "Manufacturer" "Multicomp Pro"
			(at 314.177501 27.427499 0)
			(layer "B.Fab")
			(hide yes)
			(effects
				(font
					(size 1 1)
					(thickness 0.15)
				)
				(justify mirror)
			)
		)
		(property "Tolerance" "1%"
			(at 314.177501 27.427499 0)
			(layer "B.Fab")
			(hide yes)
			(effects
				(font
					(size 1 1)
					(thickness 0.15)
				)
				(justify mirror)
			)
		)
		(property "Val" "80R6"
			(at 314.177501 27.427499 0)
			(layer "B.Fab")
			(hide yes)
			(effects
				(font
					(size 1 1)
					(thickness 0.15)
				)
				(justify mirror)
			)
		)
		(sheetname "/FPGA banks HP/")
		(sheetfile "fpga-banks-32-34.kicad_sch")
		(attr smd)
		(fp_line
			(start 0.9652 -0.45)
			(end -0.95 -0.45)
			(stroke
				(width 0.05)
				(type solid)
			)
			(layer "B.CrtYd")
		)
		(fp_line
			(start -0.95 -0.45)
			(end -0.95 0.46)
			(stroke
				(width 0.05)
				(type solid)
			)
			(layer "B.CrtYd")
		)
		(fp_line
			(start 0.9652 0.46)
			(end 0.9652 -0.45)
			(stroke
				(width 0.05)
				(type solid)
			)
			(layer "B.CrtYd")
		)
		(fp_line
			(start -0.95 0.46)
			(end 0.9652 0.46)
			(stroke
				(width 0.05)
				(type solid)
			)
			(layer "B.CrtYd")
		)
		(fp_line
			(start 0.499 -0.249)
			(end -0.5 -0.249)
			(stroke
				(width 0.15)
				(type solid)
			)
			(layer "B.Fab")
		)
		(fp_line
			(start -0.5 -0.249)
			(end -0.5 0.25)
			(stroke
				(width 0.15)
				(type solid)
			)
			(layer "B.Fab")
		)
		(fp_line
			(start 0.499 0.25)
			(end 0.499 -0.249)
			(stroke
				(width 0.15)
				(type solid)
			)
			(layer "B.Fab")
		)
		(fp_line
			(start -0.5 0.25)
			(end 0.499 0.25)
			(stroke
				(width 0.15)
				(type solid)
			)
			(layer "B.Fab")
		)
		(pad "1" smd roundrect
			(at -0.5 0)
			(size 0.6 0.6)
			(layers "B.Cu" "B.Mask" "B.Paste")
			(roundrect_rratio 0.25)
			(net 684 "/FPGA banks HP/VRN")
			(pintype "passive")
		)
		(pad "2" smd roundrect
			(at 0.499 0 90)
			(size 0.6 0.6)
			(layers "B.Cu" "B.Mask" "B.Paste")
			(roundrect_rratio 0.25)
			(net 206 "+1V1")
			(pintype "passive")
		)
	)
	(footprint "antmicro-footprints:C_0402_1005Metric"
		(layer "B.Cu")
		(at 136.875501 162.301 180)
		(descr "Capacitor SMD 0402 (1005 Metric), square (rectangular) end terminal, IPC_7351 nominal, (Body size source: IPC-SM-782 page 76, https://www.pcb-3d.com/wordpress/wp-content/uploads/ipc-sm-782a_amendment_1_and_2.pdf)")
		(tags "capacitor 0402")
		(property "Reference" "C24"
			(at 0 1.17 0)
			(layer "B.SilkS")
			(hide yes)
			(effects
				(font
					(size 0.7 0.7)
					(thickness 0.15)
				)
				(justify left bottom mirror)
			)
		)
		(property "Value" "C_100n_0402"
			(at 0 -1.169 0)
			(layer "B.Fab")
			(effects
				(font
					(size 0.7 0.7)
					(thickness 0.15)
				)
				(justify left bottom mirror)
			)
		)
		(property "Datasheet" "https://www.murata.com/products/productdetail?partno=GRM155R61H104KE14%23"
			(at 0 0 180)
			(layer "F.Fab")
			(hide yes)
			(effects
				(font
					(size 1.27 1.27)
					(thickness 0.15)
				)
			)
		)
		(property "Author" "Antmicro"
			(at 273.751002 324.602 0)
			(layer "B.Fab")
			(hide yes)
			(effects
				(font
					(size 1 1)
					(thickness 0.15)
				)
				(justify mirror)
			)
		)
		(property "Dielectric" "X5R"
			(at 273.751002 324.602 0)
			(layer "B.Fab")
			(hide yes)
			(effects
				(font
					(size 1 1)
					(thickness 0.15)
				)
				(justify mirror)
			)
		)
		(property "License" "Apache-2.0"
			(at 273.751002 324.602 0)
			(layer "B.Fab")
			(hide yes)
			(effects
				(font
					(size 1 1)
					(thickness 0.15)
				)
				(justify mirror)
			)
		)
		(property "MPN" "GRM155R61H104KE14D"
			(at 273.751002 324.602 0)
			(layer "B.Fab")
			(hide yes)
			(effects
				(font
					(size 1 1)
					(thickness 0.15)
				)
				(justify mirror)
			)
		)
		(property "Manufacturer" "Murata"
			(at 273.751002 324.602 0)
			(layer "B.Fab")
			(hide yes)
			(effects
				(font
					(size 1 1)
					(thickness 0.15)
				)
				(justify mirror)
			)
		)
		(property "Val" "100n"
			(at 273.751002 324.602 0)
			(layer "B.Fab")
			(hide yes)
			(effects
				(font
					(size 1 1)
					(thickness 0.15)
				)
				(justify mirror)
			)
		)
		(property "Voltage" "50V"
			(at 273.751002 324.602 0)
			(layer "B.Fab")
			(hide yes)
			(effects
				(font
					(size 1 1)
					(thickness 0.15)
				)
				(justify mirror)
			)
		)
		(sheetname "/FPGA power/")
		(sheetfile "fpga-power.kicad_sch")
		(attr smd)
		(fp_rect
			(start -0.9656 0.4572)
			(end 0.9652 -0.4828)
			(stroke
				(width 0.05)
				(type solid)
			)
			(fill no)
			(layer "B.CrtYd")
		)
		(fp_line
			(start 0.498 0.25)
			(end 0.498 -0.248)
			(stroke
				(width 0.15)
				(type solid)
			)
			(layer "B.Fab")
		)
		(fp_line
			(start 0.498 -0.248)
			(end -0.5 -0.248)
			(stroke
				(width 0.15)
				(type solid)
			)
			(layer "B.Fab")
		)
		(fp_line
			(start -0.5 0.25)
			(end 0.498 0.25)
			(stroke
				(width 0.15)
				(type solid)
			)
			(layer "B.Fab")
		)
		(fp_line
			(start -0.5 -0.248)
			(end -0.5 0.25)
			(stroke
				(width 0.15)
				(type solid)
			)
			(layer "B.Fab")
		)
		(pad "1" smd roundrect
			(at -0.5 0 90)
			(size 0.6 0.6)
			(layers "B.Cu" "B.Mask" "B.Paste")
			(roundrect_rratio 0.25)
			(net 1 "GND")
			(pintype "passive")
		)
		(pad "2" smd roundrect
			(at 0.498 0 180)
			(size 0.6 0.6)
			(layers "B.Cu" "B.Mask" "B.Paste")
			(roundrect_rratio 0.25)
			(net 206 "+1V1")
			(pintype "passive")
		)
	)
	(footprint "antmicro-footprints:C_0402_1005Metric"
		(layer "B.Cu")
		(at 196.55 141.25 180)
		(descr "Capacitor SMD 0402")
		(tags "capacitor SMD 0402")
		(property "Reference" "C203"
			(at 0 0.699 0)
			(layer "B.SilkS")
			(hide yes)
			(effects
				(font
					(size 0.7 0.7)
					(thickness 0.15)
				)
				(justify left bottom mirror)
			)
		)
		(property "Value" "C_100n_0402"
			(at -1.022927 -2.155213 0)
			(layer "B.Fab")
			(effects
				(font
					(size 0.7 0.7)
					(thickness 0.15)
				)
				(justify left bottom mirror)
			)
		)
		(property "Datasheet" "https://www.murata.com/products/productdetail?partno=GRM155R61H104KE14%23"
			(at 0 0 180)
			(layer "F.Fab")
			(hide yes)
			(effects
				(font
					(size 1.27 1.27)
					(thickness 0.15)
				)
			)
		)
		(property "Author" "Antmicro"
			(at 393.1 282.5 0)
			(layer "B.Fab")
			(hide yes)
			(effects
				(font
					(size 1 1)
					(thickness 0.15)
				)
				(justify mirror)
			)
		)
		(property "Dielectric" "X5R"
			(at 393.1 282.5 0)
			(layer "B.Fab")
			(hide yes)
			(effects
				(font
					(size 1 1)
					(thickness 0.15)
				)
				(justify mirror)
			)
		)
		(property "License" "Apache-2.0"
			(at 393.1 282.5 0)
			(layer "B.Fab")
			(hide yes)
			(effects
				(font
					(size 1 1)
					(thickness 0.15)
				)
				(justify mirror)
			)
		)
		(property "MPN" "GRM155R61H104KE14D"
			(at 393.1 282.5 0)
			(layer "B.Fab")
			(hide yes)
			(effects
				(font
					(size 1 1)
					(thickness 0.15)
				)
				(justify mirror)
			)
		)
		(property "Manufacturer" "Murata"
			(at 393.1 282.5 0)
			(layer "B.Fab")
			(hide yes)
			(effects
				(font
					(size 1 1)
					(thickness 0.15)
				)
				(justify mirror)
			)
		)
		(property "Val" "100n"
			(at 393.1 282.5 0)
			(layer "B.Fab")
			(hide yes)
			(effects
				(font
					(size 1 1)
					(thickness 0.15)
				)
				(justify mirror)
			)
		)
		(property "Voltage" "50V"
			(at 393.1 282.5 0)
			(layer "B.Fab")
			(hide yes)
			(effects
				(font
					(size 1 1)
					(thickness 0.15)
				)
				(justify mirror)
			)
		)
		(sheetname "/Supply/")
		(sheetfile "supply.kicad_sch")
		(attr smd)
		(fp_rect
			(start -0.9659 0.481258)
			(end 0.9649 -0.458742)
			(stroke
				(width 0.05)
				(type solid)
			)
			(fill no)
			(layer "B.CrtYd")
		)
		(fp_line
			(start 0.499 0.25)
			(end 0.499 -0.248)
			(stroke
				(width 0.15)
				(type solid)
			)
			(layer "B.Fab")
		)
		(fp_line
			(start 0.499 -0.248)
			(end -0.499 -0.248)
			(stroke
				(width 0.15)
				(type solid)
			)
			(layer "B.Fab")
		)
		(fp_line
			(start -0.499 0.25)
			(end 0.499 0.25)
			(stroke
				(width 0.15)
				(type solid)
			)
			(layer "B.Fab")
		)
		(fp_line
			(start -0.499 -0.248)
			(end -0.499 0.25)
			(stroke
				(width 0.15)
				(type solid)
			)
			(layer "B.Fab")
		)
		(pad "1" smd roundrect
			(at -0.484 0 180)
			(size 0.59 0.64)
			(layers "B.Cu" "B.Mask" "B.Paste")
			(roundrect_rratio 0.25)
			(net 41 "+3V3_AON")
			(pintype "passive")
		)
		(pad "2" smd roundrect
			(at 0.484 0 180)
			(size 0.59 0.64)
			(layers "B.Cu" "B.Mask" "B.Paste")
			(roundrect_rratio 0.25)
			(net 1 "GND")
			(pintype "passive")
		)
	)
	(footprint "antmicro-footprints:R_0402_1005Metric"
		(layer "B.Cu")
		(at 137 142.4 -90)
		(descr "Resistor SMD 0402")
		(tags "resistor SMD 0402")
		(property "Reference" "R23"
			(at -3.044968 -0.354606 90)
			(layer "B.SilkS")
			(effects
				(font
					(size 0.7 0.7)
					(thickness 0.15)
				)
				(justify left bottom mirror)
			)
		)
		(property "Value" "R_47k_0402"
			(at -1.011843 -1.772047 90)
			(layer "B.Fab")
			(effects
				(font
					(size 0.7 0.7)
					(thickness 0.15)
				)
				(justify left bottom mirror)
			)
		)
		(property "Datasheet" "https://www.bourns.com/docs/product-datasheets/cr.pdf"
			(at 0 0 270)
			(layer "F.Fab")
			(hide yes)
			(effects
				(font
					(size 1.27 1.27)
					(thickness 0.15)
				)
			)
		)
		(property "Author" "Antmicro"
			(at -5.4 279.4 0)
			(layer "B.Fab")
			(hide yes)
			(effects
				(font
					(size 1 1)
					(thickness 0.15)
				)
				(justify mirror)
			)
		)
		(property "License" "Apache-2.0"
			(at -5.4 279.4 0)
			(layer "B.Fab")
			(hide yes)
			(effects
				(font
					(size 1 1)
					(thickness 0.15)
				)
				(justify mirror)
			)
		)
		(property "MPN" "CR0402-FX-4702GLF"
			(at -5.4 279.4 0)
			(layer "B.Fab")
			(hide yes)
			(effects
				(font
					(size 1 1)
					(thickness 0.15)
				)
				(justify mirror)
			)
		)
		(property "Manufacturer" "Bourns"
			(at -5.4 279.4 0)
			(layer "B.Fab")
			(hide yes)
			(effects
				(font
					(size 1 1)
					(thickness 0.15)
				)
				(justify mirror)
			)
		)
		(property "Tolerance" "1%"
			(at -5.4 279.4 0)
			(layer "B.Fab")
			(hide yes)
			(effects
				(font
					(size 1 1)
					(thickness 0.15)
				)
				(justify mirror)
			)
		)
		(property "Val" "47k"
			(at -5.4 279.4 0)
			(layer "B.Fab")
			(hide yes)
			(effects
				(font
					(size 1 1)
					(thickness 0.15)
				)
				(justify mirror)
			)
		)
		(sheetname "/DDR5 SODIMM/")
		(sheetfile "ddr5-sodimm.kicad_sch")
		(attr smd)
		(fp_rect
			(start -0.93 0.47)
			(end 0.93 -0.47)
			(stroke
				(width 0.05)
				(type solid)
			)
			(fill no)
			(layer "B.CrtYd")
		)
		(fp_rect
			(start -0.5 0.25)
			(end 0.5 -0.25)
			(stroke
				(width 0.15)
				(type solid)
			)
			(fill no)
			(layer "B.Fab")
		)
		(pad "1" smd roundrect
			(at -0.485 0 270)
			(size 0.59 0.64)
			(layers "B.Cu" "B.Mask" "B.Paste")
			(roundrect_rratio 0.25)
			(net 172 "/DDR5 SODIMM/VSS_DET2")
			(pintype "passive")
		)
		(pad "2" smd roundrect
			(at 0.485 0 270)
			(size 0.59 0.64)
			(layers "B.Cu" "B.Mask" "B.Paste")
			(roundrect_rratio 0.25)
			(net 200 "+3V3")
			(pintype "passive")
		)
	)
	(footprint "antmicro-footprints:C_0402_1005Metric"
		(layer "B.Cu")
		(at 126.375501 181.801 -90)
		(descr "Capacitor SMD 0402 (1005 Metric), square (rectangular) end terminal, IPC_7351 nominal, (Body size source: IPC-SM-782 page 76, https://www.pcb-3d.com/wordpress/wp-content/uploads/ipc-sm-782a_amendment_1_and_2.pdf)")
		(tags "capacitor 0402")
		(property "Reference" "C36"
			(at 0 1.17 90)
			(layer "B.SilkS")
			(hide yes)
			(effects
				(font
					(size 0.7 0.7)
					(thickness 0.15)
				)
				(justify left bottom mirror)
			)
		)
		(property "Value" "C_100n_0402"
			(at 0 -1.169 90)
			(layer "B.Fab")
			(effects
				(font
					(size 0.7 0.7)
					(thickness 0.15)
				)
				(justify left bottom mirror)
			)
		)
		(property "Datasheet" "https://www.murata.com/products/productdetail?partno=GRM155R61H104KE14%23"
			(at 0 0 270)
			(layer "F.Fab")
			(hide yes)
			(effects
				(font
					(size 1.27 1.27)
					(thickness 0.15)
				)
			)
		)
		(property "Author" "Antmicro"
			(at -55.425499 308.176501 0)
			(layer "B.Fab")
			(hide yes)
			(effects
				(font
					(size 1 1)
					(thickness 0.15)
				)
				(justify mirror)
			)
		)
		(property "Dielectric" "X5R"
			(at -55.425499 308.176501 0)
			(layer "B.Fab")
			(hide yes)
			(effects
				(font
					(size 1 1)
					(thickness 0.15)
				)
				(justify mirror)
			)
		)
		(property "License" "Apache-2.0"
			(at -55.425499 308.176501 0)
			(layer "B.Fab")
			(hide yes)
			(effects
				(font
					(size 1 1)
					(thickness 0.15)
				)
				(justify mirror)
			)
		)
		(property "MPN" "GRM155R61H104KE14D"
			(at -55.425499 308.176501 0)
			(layer "B.Fab")
			(hide yes)
			(effects
				(font
					(size 1 1)
					(thickness 0.15)
				)
				(justify mirror)
			)
		)
		(property "Manufacturer" "Murata"
			(at -55.425499 308.176501 0)
			(layer "B.Fab")
			(hide yes)
			(effects
				(font
					(size 1 1)
					(thickness 0.15)
				)
				(justify mirror)
			)
		)
		(property "Val" "100n"
			(at -55.425499 308.176501 0)
			(layer "B.Fab")
			(hide yes)
			(effects
				(font
					(size 1 1)
					(thickness 0.15)
				)
				(justify mirror)
			)
		)
		(property "Voltage" "50V"
			(at -55.425499 308.176501 0)
			(layer "B.Fab")
			(hide yes)
			(effects
				(font
					(size 1 1)
					(thickness 0.15)
				)
				(justify mirror)
			)
		)
		(sheetname "/FPGA power/")
		(sheetfile "fpga-power.kicad_sch")
		(attr smd)
		(fp_rect
			(start -0.9656 0.4572)
			(end 0.9652 -0.4828)
			(stroke
				(width 0.05)
				(type solid)
			)
			(fill no)
			(layer "B.CrtYd")
		)
		(fp_line
			(start -0.5 0.25)
			(end 0.498 0.25)
			(stroke
				(width 0.15)
				(type solid)
			)
			(layer "B.Fab")
		)
		(fp_line
			(start 0.498 0.25)
			(end 0.498 -0.248)
			(stroke
				(width 0.15)
				(type solid)
			)
			(layer "B.Fab")
		)
		(fp_line
			(start -0.5 -0.248)
			(end -0.5 0.25)
			(stroke
				(width 0.15)
				(type solid)
			)
			(layer "B.Fab")
		)
		(fp_line
			(start 0.498 -0.248)
			(end -0.5 -0.248)
			(stroke
				(width 0.15)
				(type solid)
			)
			(layer "B.Fab")
		)
		(pad "1" smd roundrect
			(at -0.5 0 180)
			(size 0.6 0.6)
			(layers "B.Cu" "B.Mask" "B.Paste")
			(roundrect_rratio 0.25)
			(net 1 "GND")
			(pintype "passive")
		)
		(pad "2" smd roundrect
			(at 0.498 0 270)
			(size 0.6 0.6)
			(layers "B.Cu" "B.Mask" "B.Paste")
			(roundrect_rratio 0.25)
			(net 200 "+3V3")
			(pintype "passive")
		)
	)
	(footprint "antmicro-footprints:TP_SMD_1mm"
		(layer "B.Cu")
		(at 181.066 147.52 180)
		(property "Reference" "TP66"
			(at -1.244 0.73 0)
			(layer "B.SilkS")
			(effects
				(font
					(size 0.7 0.7)
					(thickness 0.15)
				)
				(justify left bottom mirror)
			)
		)
		(property "Value" "TP_1mm_SMD"
			(at 0 -1.4 0)
			(layer "B.Fab")
			(effects
				(font
					(size 0.7 0.7)
					(thickness 0.15)
				)
				(justify left bottom mirror)
			)
		)
		(property "MPN" ""
			(at 0 0 0)
			(unlocked yes)
			(layer "B.Fab")
			(hide yes)
			(effects
				(font
					(size 1 1)
					(thickness 0.15)
				)
				(justify mirror)
			)
		)
		(property "Manufacturer" ""
			(at 0 0 0)
			(unlocked yes)
			(layer "B.Fab")
			(hide yes)
			(effects
				(font
					(size 1 1)
					(thickness 0.15)
				)
				(justify mirror)
			)
		)
		(property "Author" "Antmicro"
			(at 0 0 0)
			(unlocked yes)
			(layer "B.Fab")
			(hide yes)
			(effects
				(font
					(size 1 1)
					(thickness 0.15)
				)
				(justify mirror)
			)
		)
		(property "License" "Apache-2.0"
			(at 0 0 0)
			(unlocked yes)
			(layer "B.Fab")
			(hide yes)
			(effects
				(font
					(size 1 1)
					(thickness 0.15)
				)
				(justify mirror)
			)
		)
		(sheetname "/Supply/")
		(sheetfile "supply.kicad_sch")
		(attr exclude_from_pos_files)
		(fp_circle
			(center 0 0)
			(end 0.6 0)
			(stroke
				(width 0.05)
				(type default)
			)
			(fill no)
			(layer "B.CrtYd")
		)
		(fp_text user "${REFERENCE}"
			(at -0.5 -2.8 0)
			(layer "B.Fab")
			(effects
				(font
					(size 0.7 0.7)
					(thickness 0.15)
				)
				(justify left bottom mirror)
			)
		)
		(fp_text user "Author: Antmicro"
			(at -0.5 -4 0)
			(layer "B.Fab")
			(effects
				(font
					(size 0.7 0.7)
					(thickness 0.15)
				)
				(justify left bottom mirror)
			)
		)
		(fp_text user "License: Apache-2.0"
			(at -0.5 -5.2 0)
			(layer "B.Fab")
			(effects
				(font
					(size 0.7 0.7)
					(thickness 0.15)
				)
				(justify left bottom mirror)
			)
		)
		(pad "1" smd circle
			(at 0 0 180)
			(size 1 1)
			(layers "B.Cu" "B.Mask")
			(net 36 "DAC_VREF")
			(pinfunction "1")
			(pintype "passive")
		)
	)
	(footprint "antmicro-footprints:C_0402_1005Metric"
		(layer "B.Cu")
		(at 130.375501 162.801 -90)
		(descr "Capacitor SMD 0402 (1005 Metric), square (rectangular) end terminal, IPC_7351 nominal, (Body size source: IPC-SM-782 page 76, https://www.pcb-3d.com/wordpress/wp-content/uploads/ipc-sm-782a_amendment_1_and_2.pdf)")
		(tags "capacitor 0402")
		(property "Reference" "C29"
			(at 0 1.17 90)
			(layer "B.SilkS")
			(hide yes)
			(effects
				(font
					(size 0.7 0.7)
					(thickness 0.15)
				)
				(justify left bottom mirror)
			)
		)
		(property "Value" "C_100n_0402"
			(at 0 -1.169 90)
			(layer "B.Fab")
			(effects
				(font
					(size 0.7 0.7)
					(thickness 0.15)
				)
				(justify left bottom mirror)
			)
		)
		(property "Datasheet" "https://www.murata.com/products/productdetail?partno=GRM155R61H104KE14%23"
			(at 0 0 270)
			(layer "F.Fab")
			(hide yes)
			(effects
				(font
					(size 1.27 1.27)
					(thickness 0.15)
				)
			)
		)
		(property "Author" "Antmicro"
			(at -32.425499 293.176501 0)
			(layer "B.Fab")
			(hide yes)
			(effects
				(font
					(size 1 1)
					(thickness 0.15)
				)
				(justify mirror)
			)
		)
		(property "Dielectric" "X5R"
			(at -32.425499 293.176501 0)
			(layer "B.Fab")
			(hide yes)
			(effects
				(font
					(size 1 1)
					(thickness 0.15)
				)
				(justify mirror)
			)
		)
		(property "License" "Apache-2.0"
			(at -32.425499 293.176501 0)
			(layer "B.Fab")
			(hide yes)
			(effects
				(font
					(size 1 1)
					(thickness 0.15)
				)
				(justify mirror)
			)
		)
		(property "MPN" "GRM155R61H104KE14D"
			(at -32.425499 293.176501 0)
			(layer "B.Fab")
			(hide yes)
			(effects
				(font
					(size 1 1)
					(thickness 0.15)
				)
				(justify mirror)
			)
		)
		(property "Manufacturer" "Murata"
			(at -32.425499 293.176501 0)
			(layer "B.Fab")
			(hide yes)
			(effects
				(font
					(size 1 1)
					(thickness 0.15)
				)
				(justify mirror)
			)
		)
		(property "Val" "100n"
			(at -32.425499 293.176501 0)
			(layer "B.Fab")
			(hide yes)
			(effects
				(font
					(size 1 1)
					(thickness 0.15)
				)
				(justify mirror)
			)
		)
		(property "Voltage" "50V"
			(at -32.425499 293.176501 0)
			(layer "B.Fab")
			(hide yes)
			(effects
				(font
					(size 1 1)
					(thickness 0.15)
				)
				(justify mirror)
			)
		)
		(sheetname "/FPGA power/")
		(sheetfile "fpga-power.kicad_sch")
		(attr smd)
		(fp_rect
			(start -0.9656 0.4572)
			(end 0.9652 -0.4828)
			(stroke
				(width 0.05)
				(type solid)
			)
			(fill no)
			(layer "B.CrtYd")
		)
		(fp_line
			(start -0.5 0.25)
			(end 0.498 0.25)
			(stroke
				(width 0.15)
				(type solid)
			)
			(layer "B.Fab")
		)
		(fp_line
			(start 0.498 0.25)
			(end 0.498 -0.248)
			(stroke
				(width 0.15)
				(type solid)
			)
			(layer "B.Fab")
		)
		(fp_line
			(start -0.5 -0.248)
			(end -0.5 0.25)
			(stroke
				(width 0.15)
				(type solid)
			)
			(layer "B.Fab")
		)
		(fp_line
			(start 0.498 -0.248)
			(end -0.5 -0.248)
			(stroke
				(width 0.15)
				(type solid)
			)
			(layer "B.Fab")
		)
		(pad "1" smd roundrect
			(at -0.5 0 180)
			(size 0.6 0.6)
			(layers "B.Cu" "B.Mask" "B.Paste")
			(roundrect_rratio 0.25)
			(net 1 "GND")
			(pintype "passive")
		)
		(pad "2" smd roundrect
			(at 0.498 0 270)
			(size 0.6 0.6)
			(layers "B.Cu" "B.Mask" "B.Paste")
			(roundrect_rratio 0.25)
			(net 200 "+3V3")
			(pintype "passive")
		)
	)
	(footprint "antmicro-footprints:R_0402_1005Metric"
		(layer "B.Cu")
		(at 84.273 130.7 180)
		(descr "Resistor SMD 0402")
		(tags "resistor SMD 0402")
		(property "Reference" "R193"
			(at -1.122484 0.772697 0)
			(layer "B.SilkS")
			(hide yes)
			(effects
				(font
					(size 0.7 0.7)
					(thickness 0.15)
				)
				(justify left bottom mirror)
			)
		)
		(property "Value" "R_330R_0402"
			(at -1.011843 -1.772047 0)
			(layer "B.Fab")
			(effects
				(font
					(size 0.7 0.7)
					(thickness 0.15)
				)
				(justify left bottom mirror)
			)
		)
		(property "Datasheet" "https://www.bourns.com/docs/product-datasheets/cr.pdf"
			(at 0 0 180)
			(layer "F.Fab")
			(hide yes)
			(effects
				(font
					(size 1.27 1.27)
					(thickness 0.15)
				)
			)
		)
		(property "Author" "Antmicro"
			(at 168.546 261.4 0)
			(layer "B.Fab")
			(hide yes)
			(effects
				(font
					(size 1 1)
					(thickness 0.15)
				)
				(justify mirror)
			)
		)
		(property "License" "Apache-2.0"
			(at 168.546 261.4 0)
			(layer "B.Fab")
			(hide yes)
			(effects
				(font
					(size 1 1)
					(thickness 0.15)
				)
				(justify mirror)
			)
		)
		(property "MPN" "CR0402-FX-3300GLF"
			(at 168.546 261.4 0)
			(layer "B.Fab")
			(hide yes)
			(effects
				(font
					(size 1 1)
					(thickness 0.15)
				)
				(justify mirror)
			)
		)
		(property "Manufacturer" "Bourns"
			(at 168.546 261.4 0)
			(layer "B.Fab")
			(hide yes)
			(effects
				(font
					(size 1 1)
					(thickness 0.15)
				)
				(justify mirror)
			)
		)
		(property "Tolerance" "1%"
			(at 168.546 261.4 0)
			(layer "B.Fab")
			(hide yes)
			(effects
				(font
					(size 1 1)
					(thickness 0.15)
				)
				(justify mirror)
			)
		)
		(property "Val" "330R"
			(at 168.546 261.4 0)
			(layer "B.Fab")
			(hide yes)
			(effects
				(font
					(size 1 1)
					(thickness 0.15)
				)
				(justify mirror)
			)
		)
		(sheetname "/Ethernet/")
		(sheetfile "ethernet.kicad_sch")
		(attr smd)
		(fp_rect
			(start -0.93 0.47)
			(end 0.93 -0.47)
			(stroke
				(width 0.05)
				(type solid)
			)
			(fill no)
			(layer "B.CrtYd")
		)
		(fp_rect
			(start -0.5 0.25)
			(end 0.5 -0.25)
			(stroke
				(width 0.15)
				(type solid)
			)
			(fill no)
			(layer "B.Fab")
		)
		(pad "1" smd roundrect
			(at -0.485 0 180)
			(size 0.59 0.64)
			(layers "B.Cu" "B.Mask" "B.Paste")
			(roundrect_rratio 0.25)
			(net 1 "GND")
			(pintype "passive")
		)
		(pad "2" smd roundrect
			(at 0.485 0 180)
			(size 0.59 0.64)
			(layers "B.Cu" "B.Mask" "B.Paste")
			(roundrect_rratio 0.25)
			(net 32 "Net-(C234-Pad1)")
			(pintype "passive")
		)
	)
	(footprint "antmicro-footprints:C_0402_1005Metric"
		(layer "B.Cu")
		(at 151 142.4 -90)
		(descr "Capacitor SMD 0402")
		(tags "capacitor SMD 0402")
		(property "Reference" "C8"
			(at 0 0.699 90)
			(layer "B.SilkS")
			(hide yes)
			(effects
				(font
					(size 0.7 0.7)
					(thickness 0.15)
				)
				(justify left bottom mirror)
			)
		)
		(property "Value" "C_100n_0402"
			(at -1.022927 -2.155213 90)
			(layer "B.Fab")
			(effects
				(font
					(size 0.7 0.7)
					(thickness 0.15)
				)
				(justify left bottom mirror)
			)
		)
		(property "Datasheet" "https://www.murata.com/products/productdetail?partno=GRM155R61H104KE14%23"
			(at 0 0 270)
			(layer "F.Fab")
			(hide yes)
			(effects
				(font
					(size 1.27 1.27)
					(thickness 0.15)
				)
			)
		)
		(property "Author" "Antmicro"
			(at 8.6 293.4 0)
			(layer "B.Fab")
			(hide yes)
			(effects
				(font
					(size 1 1)
					(thickness 0.15)
				)
				(justify mirror)
			)
		)
		(property "Dielectric" "X5R"
			(at 8.6 293.4 0)
			(layer "B.Fab")
			(hide yes)
			(effects
				(font
					(size 1 1)
					(thickness 0.15)
				)
				(justify mirror)
			)
		)
		(property "License" "Apache-2.0"
			(at 8.6 293.4 0)
			(layer "B.Fab")
			(hide yes)
			(effects
				(font
					(size 1 1)
					(thickness 0.15)
				)
				(justify mirror)
			)
		)
		(property "MPN" "GRM155R61H104KE14D"
			(at 8.6 293.4 0)
			(layer "B.Fab")
			(hide yes)
			(effects
				(font
					(size 1 1)
					(thickness 0.15)
				)
				(justify mirror)
			)
		)
		(property "Manufacturer" "Murata"
			(at 8.6 293.4 0)
			(layer "B.Fab")
			(hide yes)
			(effects
				(font
					(size 1 1)
					(thickness 0.15)
				)
				(justify mirror)
			)
		)
		(property "Val" "100n"
			(at 8.6 293.4 0)
			(layer "B.Fab")
			(hide yes)
			(effects
				(font
					(size 1 1)
					(thickness 0.15)
				)
				(justify mirror)
			)
		)
		(property "Voltage" "50V"
			(at 8.6 293.4 0)
			(layer "B.Fab")
			(hide yes)
			(effects
				(font
					(size 1 1)
					(thickness 0.15)
				)
				(justify mirror)
			)
		)
		(sheetname "/DDR5 SODIMM/")
		(sheetfile "ddr5-sodimm.kicad_sch")
		(attr smd)
		(fp_rect
			(start -0.9659 0.481258)
			(end 0.9649 -0.458742)
			(stroke
				(width 0.05)
				(type solid)
			)
			(fill no)
			(layer "B.CrtYd")
		)
		(fp_line
			(start -0.499 0.25)
			(end 0.499 0.25)
			(stroke
				(width 0.15)
				(type solid)
			)
			(layer "B.Fab")
		)
		(fp_line
			(start 0.499 0.25)
			(end 0.499 -0.248)
			(stroke
				(width 0.15)
				(type solid)
			)
			(layer "B.Fab")
		)
		(fp_line
			(start -0.499 -0.248)
			(end -0.499 0.25)
			(stroke
				(width 0.15)
				(type solid)
			)
			(layer "B.Fab")
		)
		(fp_line
			(start 0.499 -0.248)
			(end -0.499 -0.248)
			(stroke
				(width 0.15)
				(type solid)
			)
			(layer "B.Fab")
		)
		(pad "1" smd roundrect
			(at -0.484 0 270)
			(size 0.59 0.64)
			(layers "B.Cu" "B.Mask" "B.Paste")
			(roundrect_rratio 0.25)
			(net 1 "GND")
			(pintype "passive")
		)
		(pad "2" smd roundrect
			(at 0.484 0 270)
			(size 0.59 0.64)
			(layers "B.Cu" "B.Mask" "B.Paste")
			(roundrect_rratio 0.25)
			(net 206 "+1V1")
			(pintype "passive")
		)
	)
	(footprint "antmicro-footprints:R_0402_1005Metric"
		(layer "B.Cu")
		(at 195.415 145.851)
		(descr "Resistor SMD 0402")
		(tags "resistor SMD 0402")
		(property "Reference" "R190"
			(at -1.122484 0.772697 180)
			(layer "B.SilkS")
			(hide yes)
			(effects
				(font
					(size 0.7 0.7)
					(thickness 0.15)
				)
				(justify left bottom mirror)
			)
		)
		(property "Value" "R_47k_0402"
			(at -1.011843 -1.772047 180)
			(layer "B.Fab")
			(effects
				(font
					(size 0.7 0.7)
					(thickness 0.15)
				)
				(justify left bottom mirror)
			)
		)
		(property "Datasheet" "https://www.bourns.com/docs/product-datasheets/cr.pdf"
			(at 0 0 0)
			(layer "F.Fab")
			(hide yes)
			(effects
				(font
					(size 1.27 1.27)
					(thickness 0.15)
				)
			)
		)
		(property "Author" "Antmicro"
			(at 0 0 0)
			(layer "B.Fab")
			(hide yes)
			(effects
				(font
					(size 1 1)
					(thickness 0.15)
				)
				(justify mirror)
			)
		)
		(property "License" "Apache-2.0"
			(at 0 0 0)
			(layer "B.Fab")
			(hide yes)
			(effects
				(font
					(size 1 1)
					(thickness 0.15)
				)
				(justify mirror)
			)
		)
		(property "MPN" "CR0402-FX-4702GLF"
			(at 0 0 0)
			(layer "B.Fab")
			(hide yes)
			(effects
				(font
					(size 1 1)
					(thickness 0.15)
				)
				(justify mirror)
			)
		)
		(property "Manufacturer" "Bourns"
			(at 0 0 0)
			(layer "B.Fab")
			(hide yes)
			(effects
				(font
					(size 1 1)
					(thickness 0.15)
				)
				(justify mirror)
			)
		)
		(property "Tolerance" "1%"
			(at 0 0 0)
			(layer "B.Fab")
			(hide yes)
			(effects
				(font
					(size 1 1)
					(thickness 0.15)
				)
				(justify mirror)
			)
		)
		(property "Val" "47k"
			(at 0 0 0)
			(layer "B.Fab")
			(hide yes)
			(effects
				(font
					(size 1 1)
					(thickness 0.15)
				)
				(justify mirror)
			)
		)
		(sheetname "/Supply/")
		(sheetfile "supply.kicad_sch")
		(attr smd)
		(fp_rect
			(start -0.93 0.47)
			(end 0.93 -0.47)
			(stroke
				(width 0.05)
				(type solid)
			)
			(fill no)
			(layer "B.CrtYd")
		)
		(fp_rect
			(start -0.5 0.25)
			(end 0.5 -0.25)
			(stroke
				(width 0.15)
				(type solid)
			)
			(fill no)
			(layer "B.Fab")
		)
		(pad "1" smd roundrect
			(at -0.485 0)
			(size 0.59 0.64)
			(layers "B.Cu" "B.Mask" "B.Paste")
			(roundrect_rratio 0.25)
			(net 223 "/Supply/EN3")
			(pintype "passive")
		)
		(pad "2" smd roundrect
			(at 0.485 0)
			(size 0.59 0.64)
			(layers "B.Cu" "B.Mask" "B.Paste")
			(roundrect_rratio 0.25)
			(net 41 "+3V3_AON")
			(pintype "passive")
		)
	)
	(footprint "antmicro-footprints:C_0402_1005Metric"
		(layer "B.Cu")
		(at 140.375501 164.801 90)
		(descr "Capacitor SMD 0402 (1005 Metric), square (rectangular) end terminal, IPC_7351 nominal, (Body size source: IPC-SM-782 page 76, https://www.pcb-3d.com/wordpress/wp-content/uploads/ipc-sm-782a_amendment_1_and_2.pdf)")
		(tags "capacitor 0402")
		(property "Reference" "C66"
			(at 0 1.17 270)
			(layer "B.SilkS")
			(hide yes)
			(effects
				(font
					(size 0.7 0.7)
					(thickness 0.15)
				)
				(justify left bottom mirror)
			)
		)
		(property "Value" "C_100n_0402"
			(at 0 -1.169 270)
			(layer "B.Fab")
			(effects
				(font
					(size 0.7 0.7)
					(thickness 0.15)
				)
				(justify left bottom mirror)
			)
		)
		(property "Datasheet" "https://www.murata.com/products/productdetail?partno=GRM155R61H104KE14%23"
			(at 0 0 90)
			(layer "F.Fab")
			(hide yes)
			(effects
				(font
					(size 1.27 1.27)
					(thickness 0.15)
				)
			)
		)
		(property "Author" "Antmicro"
			(at 305.176501 24.425499 0)
			(layer "B.Fab")
			(hide yes)
			(effects
				(font
					(size 1 1)
					(thickness 0.15)
				)
				(justify mirror)
			)
		)
		(property "Dielectric" "X5R"
			(at 305.176501 24.425499 0)
			(layer "B.Fab")
			(hide yes)
			(effects
				(font
					(size 1 1)
					(thickness 0.15)
				)
				(justify mirror)
			)
		)
		(property "License" "Apache-2.0"
			(at 305.176501 24.425499 0)
			(layer "B.Fab")
			(hide yes)
			(effects
				(font
					(size 1 1)
					(thickness 0.15)
				)
				(justify mirror)
			)
		)
		(property "MPN" "GRM155R61H104KE14D"
			(at 305.176501 24.425499 0)
			(layer "B.Fab")
			(hide yes)
			(effects
				(font
					(size 1 1)
					(thickness 0.15)
				)
				(justify mirror)
			)
		)
		(property "Manufacturer" "Murata"
			(at 305.176501 24.425499 0)
			(layer "B.Fab")
			(hide yes)
			(effects
				(font
					(size 1 1)
					(thickness 0.15)
				)
				(justify mirror)
			)
		)
		(property "Val" "100n"
			(at 305.176501 24.425499 0)
			(layer "B.Fab")
			(hide yes)
			(effects
				(font
					(size 1 1)
					(thickness 0.15)
				)
				(justify mirror)
			)
		)
		(property "Voltage" "50V"
			(at 305.176501 24.425499 0)
			(layer "B.Fab")
			(hide yes)
			(effects
				(font
					(size 1 1)
					(thickness 0.15)
				)
				(justify mirror)
			)
		)
		(sheetname "/FPGA power/")
		(sheetfile "fpga-power.kicad_sch")
		(attr smd)
		(fp_rect
			(start -0.9656 0.4572)
			(end 0.9652 -0.4828)
			(stroke
				(width 0.05)
				(type solid)
			)
			(fill no)
			(layer "B.CrtYd")
		)
		(fp_line
			(start 0.498 -0.248)
			(end -0.5 -0.248)
			(stroke
				(width 0.15)
				(type solid)
			)
			(layer "B.Fab")
		)
		(fp_line
			(start -0.5 -0.248)
			(end -0.5 0.25)
			(stroke
				(width 0.15)
				(type solid)
			)
			(layer "B.Fab")
		)
		(fp_line
			(start 0.498 0.25)
			(end 0.498 -0.248)
			(stroke
				(width 0.15)
				(type solid)
			)
			(layer "B.Fab")
		)
		(fp_line
			(start -0.5 0.25)
			(end 0.498 0.25)
			(stroke
				(width 0.15)
				(type solid)
			)
			(layer "B.Fab")
		)
		(pad "1" smd roundrect
			(at -0.5 0)
			(size 0.6 0.6)
			(layers "B.Cu" "B.Mask" "B.Paste")
			(roundrect_rratio 0.25)
			(net 1 "GND")
			(pintype "passive")
		)
		(pad "2" smd roundrect
			(at 0.498 0 90)
			(size 0.6 0.6)
			(layers "B.Cu" "B.Mask" "B.Paste")
			(roundrect_rratio 0.25)
			(net 206 "+1V1")
			(pintype "passive")
		)
	)
	(footprint "antmicro-footprints:C_0402_1005Metric"
		(layer "B.Cu")
		(at 150.375501 169.8025 -90)
		(descr "Capacitor SMD 0402 (1005 Metric), square (rectangular) end terminal, IPC_7351 nominal, (Body size source: IPC-SM-782 page 76, https://www.pcb-3d.com/wordpress/wp-content/uploads/ipc-sm-782a_amendment_1_and_2.pdf)")
		(tags "capacitor 0402")
		(property "Reference" "C95"
			(at 0 1.17 90)
			(layer "B.SilkS")
			(hide yes)
			(effects
				(font
					(size 0.7 0.7)
					(thickness 0.15)
				)
				(justify left bottom mirror)
			)
		)
		(property "Value" "C_100n_0402"
			(at 0 -1.169 90)
			(layer "B.Fab")
			(effects
				(font
					(size 0.7 0.7)
					(thickness 0.15)
				)
				(justify left bottom mirror)
			)
		)
		(property "Datasheet" "https://www.murata.com/products/productdetail?partno=GRM155R61H104KE14%23"
			(at 0 0 270)
			(layer "F.Fab")
			(hide yes)
			(effects
				(font
					(size 1.27 1.27)
					(thickness 0.15)
				)
			)
		)
		(property "Author" "Antmicro"
			(at -19.426999 320.178001 0)
			(layer "B.Fab")
			(hide yes)
			(effects
				(font
					(size 1 1)
					(thickness 0.15)
				)
				(justify mirror)
			)
		)
		(property "Dielectric" "X5R"
			(at -19.426999 320.178001 0)
			(layer "B.Fab")
			(hide yes)
			(effects
				(font
					(size 1 1)
					(thickness 0.15)
				)
				(justify mirror)
			)
		)
		(property "License" "Apache-2.0"
			(at -19.426999 320.178001 0)
			(layer "B.Fab")
			(hide yes)
			(effects
				(font
					(size 1 1)
					(thickness 0.15)
				)
				(justify mirror)
			)
		)
		(property "MPN" "GRM155R61H104KE14D"
			(at -19.426999 320.178001 0)
			(layer "B.Fab")
			(hide yes)
			(effects
				(font
					(size 1 1)
					(thickness 0.15)
				)
				(justify mirror)
			)
		)
		(property "Manufacturer" "Murata"
			(at -19.426999 320.178001 0)
			(layer "B.Fab")
			(hide yes)
			(effects
				(font
					(size 1 1)
					(thickness 0.15)
				)
				(justify mirror)
			)
		)
		(property "Val" "100n"
			(at -19.426999 320.178001 0)
			(layer "B.Fab")
			(hide yes)
			(effects
				(font
					(size 1 1)
					(thickness 0.15)
				)
				(justify mirror)
			)
		)
		(property "Voltage" "50V"
			(at -19.426999 320.178001 0)
			(layer "B.Fab")
			(hide yes)
			(effects
				(font
					(size 1 1)
					(thickness 0.15)
				)
				(justify mirror)
			)
		)
		(sheetname "/FPGA power/")
		(sheetfile "fpga-power.kicad_sch")
		(attr smd)
		(fp_rect
			(start -0.9656 0.4572)
			(end 0.9652 -0.4828)
			(stroke
				(width 0.05)
				(type solid)
			)
			(fill no)
			(layer "B.CrtYd")
		)
		(fp_line
			(start -0.5 0.25)
			(end 0.498 0.25)
			(stroke
				(width 0.15)
				(type solid)
			)
			(layer "B.Fab")
		)
		(fp_line
			(start 0.498 0.25)
			(end 0.498 -0.248)
			(stroke
				(width 0.15)
				(type solid)
			)
			(layer "B.Fab")
		)
		(fp_line
			(start -0.5 -0.248)
			(end -0.5 0.25)
			(stroke
				(width 0.15)
				(type solid)
			)
			(layer "B.Fab")
		)
		(fp_line
			(start 0.498 -0.248)
			(end -0.5 -0.248)
			(stroke
				(width 0.15)
				(type solid)
			)
			(layer "B.Fab")
		)
		(pad "1" smd roundrect
			(at -0.5 0 180)
			(size 0.6 0.6)
			(layers "B.Cu" "B.Mask" "B.Paste")
			(roundrect_rratio 0.25)
			(net 1 "GND")
			(pintype "passive")
		)
		(pad "2" smd roundrect
			(at 0.498 0 270)
			(size 0.6 0.6)
			(layers "B.Cu" "B.Mask" "B.Paste")
			(roundrect_rratio 0.25)
			(net 206 "+1V1")
			(pintype "passive")
		)
	)
	(footprint "antmicro-footprints:C_0402_1005Metric"
		(layer "B.Cu")
		(at 144.877001 186.3005 180)
		(descr "Capacitor SMD 0402 (1005 Metric), square (rectangular) end terminal, IPC_7351 nominal, (Body size source: IPC-SM-782 page 76, https://www.pcb-3d.com/wordpress/wp-content/uploads/ipc-sm-782a_amendment_1_and_2.pdf)")
		(tags "capacitor 0402")
		(property "Reference" "C51"
			(at 0 1.17 0)
			(layer "B.SilkS")
			(hide yes)
			(effects
				(font
					(size 0.7 0.7)
					(thickness 0.15)
				)
				(justify left bottom mirror)
			)
		)
		(property "Value" "C_100n_0402"
			(at 0 -1.169 0)
			(layer "B.Fab")
			(effects
				(font
					(size 0.7 0.7)
					(thickness 0.15)
				)
				(justify left bottom mirror)
			)
		)
		(property "Datasheet" "https://www.murata.com/products/productdetail?partno=GRM155R61H104KE14%23"
			(at 0 0 180)
			(layer "F.Fab")
			(hide yes)
			(effects
				(font
					(size 1.27 1.27)
					(thickness 0.15)
				)
			)
		)
		(property "Author" "Antmicro"
			(at 289.754002 372.601 0)
			(layer "B.Fab")
			(hide yes)
			(effects
				(font
					(size 1 1)
					(thickness 0.15)
				)
				(justify mirror)
			)
		)
		(property "Dielectric" "X5R"
			(at 289.754002 372.601 0)
			(layer "B.Fab")
			(hide yes)
			(effects
				(font
					(size 1 1)
					(thickness 0.15)
				)
				(justify mirror)
			)
		)
		(property "License" "Apache-2.0"
			(at 289.754002 372.601 0)
			(layer "B.Fab")
			(hide yes)
			(effects
				(font
					(size 1 1)
					(thickness 0.15)
				)
				(justify mirror)
			)
		)
		(property "MPN" "GRM155R61H104KE14D"
			(at 289.754002 372.601 0)
			(layer "B.Fab")
			(hide yes)
			(effects
				(font
					(size 1 1)
					(thickness 0.15)
				)
				(justify mirror)
			)
		)
		(property "Manufacturer" "Murata"
			(at 289.754002 372.601 0)
			(layer "B.Fab")
			(hide yes)
			(effects
				(font
					(size 1 1)
					(thickness 0.15)
				)
				(justify mirror)
			)
		)
		(property "Val" "100n"
			(at 289.754002 372.601 0)
			(layer "B.Fab")
			(hide yes)
			(effects
				(font
					(size 1 1)
					(thickness 0.15)
				)
				(justify mirror)
			)
		)
		(property "Voltage" "50V"
			(at 289.754002 372.601 0)
			(layer "B.Fab")
			(hide yes)
			(effects
				(font
					(size 1 1)
					(thickness 0.15)
				)
				(justify mirror)
			)
		)
		(sheetname "/FPGA power/")
		(sheetfile "fpga-power.kicad_sch")
		(attr smd)
		(fp_rect
			(start -0.9656 0.4572)
			(end 0.9652 -0.4828)
			(stroke
				(width 0.05)
				(type solid)
			)
			(fill no)
			(layer "B.CrtYd")
		)
		(fp_line
			(start 0.498 0.25)
			(end 0.498 -0.248)
			(stroke
				(width 0.15)
				(type solid)
			)
			(layer "B.Fab")
		)
		(fp_line
			(start 0.498 -0.248)
			(end -0.5 -0.248)
			(stroke
				(width 0.15)
				(type solid)
			)
			(layer "B.Fab")
		)
		(fp_line
			(start -0.5 0.25)
			(end 0.498 0.25)
			(stroke
				(width 0.15)
				(type solid)
			)
			(layer "B.Fab")
		)
		(fp_line
			(start -0.5 -0.248)
			(end -0.5 0.25)
			(stroke
				(width 0.15)
				(type solid)
			)
			(layer "B.Fab")
		)
		(pad "1" smd roundrect
			(at -0.5 0 90)
			(size 0.6 0.6)
			(layers "B.Cu" "B.Mask" "B.Paste")
			(roundrect_rratio 0.25)
			(net 1 "GND")
			(pintype "passive")
		)
		(pad "2" smd roundrect
			(at 0.498 0 180)
			(size 0.6 0.6)
			(layers "B.Cu" "B.Mask" "B.Paste")
			(roundrect_rratio 0.25)
			(net 200 "+3V3")
			(pintype "passive")
		)
	)
	(footprint "antmicro-footprints:C_0402_1005Metric"
		(layer "B.Cu")
		(at 137.375501 184.801 -90)
		(descr "Capacitor SMD 0402 (1005 Metric), square (rectangular) end terminal, IPC_7351 nominal, (Body size source: IPC-SM-782 page 76, https://www.pcb-3d.com/wordpress/wp-content/uploads/ipc-sm-782a_amendment_1_and_2.pdf)")
		(tags "capacitor 0402")
		(property "Reference" "C59"
			(at 0 1.17 90)
			(layer "B.SilkS")
			(hide yes)
			(effects
				(font
					(size 0.7 0.7)
					(thickness 0.15)
				)
				(justify left bottom mirror)
			)
		)
		(property "Value" "C_100n_0402"
			(at 0 -1.169 90)
			(layer "B.Fab")
			(effects
				(font
					(size 0.7 0.7)
					(thickness 0.15)
				)
				(justify left bottom mirror)
			)
		)
		(property "Datasheet" "https://www.murata.com/products/productdetail?partno=GRM155R61H104KE14%23"
			(at 0 0 270)
			(layer "F.Fab")
			(hide yes)
			(effects
				(font
					(size 1.27 1.27)
					(thickness 0.15)
				)
			)
		)
		(property "Author" "Antmicro"
			(at -47.425499 322.176501 0)
			(layer "B.Fab")
			(hide yes)
			(effects
				(font
					(size 1 1)
					(thickness 0.15)
				)
				(justify mirror)
			)
		)
		(property "Dielectric" "X5R"
			(at -47.425499 322.176501 0)
			(layer "B.Fab")
			(hide yes)
			(effects
				(font
					(size 1 1)
					(thickness 0.15)
				)
				(justify mirror)
			)
		)
		(property "License" "Apache-2.0"
			(at -47.425499 322.176501 0)
			(layer "B.Fab")
			(hide yes)
			(effects
				(font
					(size 1 1)
					(thickness 0.15)
				)
				(justify mirror)
			)
		)
		(property "MPN" "GRM155R61H104KE14D"
			(at -47.425499 322.176501 0)
			(layer "B.Fab")
			(hide yes)
			(effects
				(font
					(size 1 1)
					(thickness 0.15)
				)
				(justify mirror)
			)
		)
		(property "Manufacturer" "Murata"
			(at -47.425499 322.176501 0)
			(layer "B.Fab")
			(hide yes)
			(effects
				(font
					(size 1 1)
					(thickness 0.15)
				)
				(justify mirror)
			)
		)
		(property "Val" "100n"
			(at -47.425499 322.176501 0)
			(layer "B.Fab")
			(hide yes)
			(effects
				(font
					(size 1 1)
					(thickness 0.15)
				)
				(justify mirror)
			)
		)
		(property "Voltage" "50V"
			(at -47.425499 322.176501 0)
			(layer "B.Fab")
			(hide yes)
			(effects
				(font
					(size 1 1)
					(thickness 0.15)
				)
				(justify mirror)
			)
		)
		(sheetname "/FPGA power/")
		(sheetfile "fpga-power.kicad_sch")
		(attr smd)
		(fp_rect
			(start -0.9656 0.4572)
			(end 0.9652 -0.4828)
			(stroke
				(width 0.05)
				(type solid)
			)
			(fill no)
			(layer "B.CrtYd")
		)
		(fp_line
			(start -0.5 0.25)
			(end 0.498 0.25)
			(stroke
				(width 0.15)
				(type solid)
			)
			(layer "B.Fab")
		)
		(fp_line
			(start 0.498 0.25)
			(end 0.498 -0.248)
			(stroke
				(width 0.15)
				(type solid)
			)
			(layer "B.Fab")
		)
		(fp_line
			(start -0.5 -0.248)
			(end -0.5 0.25)
			(stroke
				(width 0.15)
				(type solid)
			)
			(layer "B.Fab")
		)
		(fp_line
			(start 0.498 -0.248)
			(end -0.5 -0.248)
			(stroke
				(width 0.15)
				(type solid)
			)
			(layer "B.Fab")
		)
		(pad "1" smd roundrect
			(at -0.5 0 180)
			(size 0.6 0.6)
			(layers "B.Cu" "B.Mask" "B.Paste")
			(roundrect_rratio 0.25)
			(net 1 "GND")
			(pintype "passive")
		)
		(pad "2" smd roundrect
			(at 0.498 0 270)
			(size 0.6 0.6)
			(layers "B.Cu" "B.Mask" "B.Paste")
			(roundrect_rratio 0.25)
			(net 200 "+3V3")
			(pintype "passive")
		)
	)
	(footprint "antmicro-footprints:C_0402_1005Metric"
		(layer "B.Cu")
		(at 197.665 145.801)
		(descr "Capacitor SMD 0402")
		(tags "capacitor SMD 0402")
		(property "Reference" "C209"
			(at 0 0.699 180)
			(layer "B.SilkS")
			(hide yes)
			(effects
				(font
					(size 0.7 0.7)
					(thickness 0.15)
				)
				(justify left bottom mirror)
			)
		)
		(property "Value" "C_100n_0402"
			(at -1.022927 -2.155213 180)
			(layer "B.Fab")
			(effects
				(font
					(size 0.7 0.7)
					(thickness 0.15)
				)
				(justify left bottom mirror)
			)
		)
		(property "Datasheet" "https://www.murata.com/products/productdetail?partno=GRM155R61H104KE14%23"
			(at 0 0 0)
			(layer "F.Fab")
			(hide yes)
			(effects
				(font
					(size 1.27 1.27)
					(thickness 0.15)
				)
			)
		)
		(property "Author" "Antmicro"
			(at 0 0 0)
			(layer "B.Fab")
			(hide yes)
			(effects
				(font
					(size 1 1)
					(thickness 0.15)
				)
				(justify mirror)
			)
		)
		(property "Dielectric" "X5R"
			(at 0 0 0)
			(layer "B.Fab")
			(hide yes)
			(effects
				(font
					(size 1 1)
					(thickness 0.15)
				)
				(justify mirror)
			)
		)
		(property "License" "Apache-2.0"
			(at 0 0 0)
			(layer "B.Fab")
			(hide yes)
			(effects
				(font
					(size 1 1)
					(thickness 0.15)
				)
				(justify mirror)
			)
		)
		(property "MPN" "GRM155R61H104KE14D"
			(at 0 0 0)
			(layer "B.Fab")
			(hide yes)
			(effects
				(font
					(size 1 1)
					(thickness 0.15)
				)
				(justify mirror)
			)
		)
		(property "Manufacturer" "Murata"
			(at 0 0 0)
			(layer "B.Fab")
			(hide yes)
			(effects
				(font
					(size 1 1)
					(thickness 0.15)
				)
				(justify mirror)
			)
		)
		(property "Val" "100n"
			(at 0 0 0)
			(layer "B.Fab")
			(hide yes)
			(effects
				(font
					(size 1 1)
					(thickness 0.15)
				)
				(justify mirror)
			)
		)
		(property "Voltage" "50V"
			(at 0 0 0)
			(layer "B.Fab")
			(hide yes)
			(effects
				(font
					(size 1 1)
					(thickness 0.15)
				)
				(justify mirror)
			)
		)
		(sheetname "/Supply/")
		(sheetfile "supply.kicad_sch")
		(attr smd)
		(fp_rect
			(start -0.9659 0.481258)
			(end 0.9649 -0.458742)
			(stroke
				(width 0.05)
				(type solid)
			)
			(fill no)
			(layer "B.CrtYd")
		)
		(fp_line
			(start -0.499 -0.248)
			(end -0.499 0.25)
			(stroke
				(width 0.15)
				(type solid)
			)
			(layer "B.Fab")
		)
		(fp_line
			(start -0.499 0.25)
			(end 0.499 0.25)
			(stroke
				(width 0.15)
				(type solid)
			)
			(layer "B.Fab")
		)
		(fp_line
			(start 0.499 -0.248)
			(end -0.499 -0.248)
			(stroke
				(width 0.15)
				(type solid)
			)
			(layer "B.Fab")
		)
		(fp_line
			(start 0.499 0.25)
			(end 0.499 -0.248)
			(stroke
				(width 0.15)
				(type solid)
			)
			(layer "B.Fab")
		)
		(pad "1" smd roundrect
			(at -0.484 0)
			(size 0.59 0.64)
			(layers "B.Cu" "B.Mask" "B.Paste")
			(roundrect_rratio 0.25)
			(net 1 "GND")
			(pintype "passive")
		)
		(pad "2" smd roundrect
			(at 0.484 0)
			(size 0.59 0.64)
			(layers "B.Cu" "B.Mask" "B.Paste")
			(roundrect_rratio 0.25)
			(net 62 "/Supply/SEQ_EN")
			(pintype "passive")
		)
	)
	(footprint "antmicro-footprints:C_0402_1005Metric"
		(layer "B.Cu")
		(at 130.375501 183.8005 -90)
		(descr "Capacitor SMD 0402 (1005 Metric), square (rectangular) end terminal, IPC_7351 nominal, (Body size source: IPC-SM-782 page 76, https://www.pcb-3d.com/wordpress/wp-content/uploads/ipc-sm-782a_amendment_1_and_2.pdf)")
		(tags "capacitor 0402")
		(property "Reference" "C41"
			(at 0 1.17 90)
			(layer "B.SilkS")
			(hide yes)
			(effects
				(font
					(size 0.7 0.7)
					(thickness 0.15)
				)
				(justify left bottom mirror)
			)
		)
		(property "Value" "C_100n_0402"
			(at 0 -1.169 90)
			(layer "B.Fab")
			(effects
				(font
					(size 0.7 0.7)
					(thickness 0.15)
				)
				(justify left bottom mirror)
			)
		)
		(property "Datasheet" "https://www.murata.com/products/productdetail?partno=GRM155R61H104KE14%23"
			(at 0 0 270)
			(layer "F.Fab")
			(hide yes)
			(effects
				(font
					(size 1.27 1.27)
					(thickness 0.15)
				)
			)
		)
		(property "Author" "Antmicro"
			(at -53.424999 314.176001 0)
			(layer "B.Fab")
			(hide yes)
			(effects
				(font
					(size 1 1)
					(thickness 0.15)
				)
				(justify mirror)
			)
		)
		(property "Dielectric" "X5R"
			(at -53.424999 314.176001 0)
			(layer "B.Fab")
			(hide yes)
			(effects
				(font
					(size 1 1)
					(thickness 0.15)
				)
				(justify mirror)
			)
		)
		(property "License" "Apache-2.0"
			(at -53.424999 314.176001 0)
			(layer "B.Fab")
			(hide yes)
			(effects
				(font
					(size 1 1)
					(thickness 0.15)
				)
				(justify mirror)
			)
		)
		(property "MPN" "GRM155R61H104KE14D"
			(at -53.424999 314.176001 0)
			(layer "B.Fab")
			(hide yes)
			(effects
				(font
					(size 1 1)
					(thickness 0.15)
				)
				(justify mirror)
			)
		)
		(property "Manufacturer" "Murata"
			(at -53.424999 314.176001 0)
			(layer "B.Fab")
			(hide yes)
			(effects
				(font
					(size 1 1)
					(thickness 0.15)
				)
				(justify mirror)
			)
		)
		(property "Val" "100n"
			(at -53.424999 314.176001 0)
			(layer "B.Fab")
			(hide yes)
			(effects
				(font
					(size 1 1)
					(thickness 0.15)
				)
				(justify mirror)
			)
		)
		(property "Voltage" "50V"
			(at -53.424999 314.176001 0)
			(layer "B.Fab")
			(hide yes)
			(effects
				(font
					(size 1 1)
					(thickness 0.15)
				)
				(justify mirror)
			)
		)
		(sheetname "/FPGA power/")
		(sheetfile "fpga-power.kicad_sch")
		(attr smd)
		(fp_rect
			(start -0.9656 0.4572)
			(end 0.9652 -0.4828)
			(stroke
				(width 0.05)
				(type solid)
			)
			(fill no)
			(layer "B.CrtYd")
		)
		(fp_line
			(start -0.5 0.25)
			(end 0.498 0.25)
			(stroke
				(width 0.15)
				(type solid)
			)
			(layer "B.Fab")
		)
		(fp_line
			(start 0.498 0.25)
			(end 0.498 -0.248)
			(stroke
				(width 0.15)
				(type solid)
			)
			(layer "B.Fab")
		)
		(fp_line
			(start -0.5 -0.248)
			(end -0.5 0.25)
			(stroke
				(width 0.15)
				(type solid)
			)
			(layer "B.Fab")
		)
		(fp_line
			(start 0.498 -0.248)
			(end -0.5 -0.248)
			(stroke
				(width 0.15)
				(type solid)
			)
			(layer "B.Fab")
		)
		(pad "1" smd roundrect
			(at -0.5 0 180)
			(size 0.6 0.6)
			(layers "B.Cu" "B.Mask" "B.Paste")
			(roundrect_rratio 0.25)
			(net 1 "GND")
			(pintype "passive")
		)
		(pad "2" smd roundrect
			(at 0.498 0 270)
			(size 0.6 0.6)
			(layers "B.Cu" "B.Mask" "B.Paste")
			(roundrect_rratio 0.25)
			(net 200 "+3V3")
			(pintype "passive")
		)
	)
	(footprint "antmicro-footprints:TP_SMD_1mm"
		(layer "B.Cu")
		(at 124.2 184.8 180)
		(property "Reference" "TP24"
			(at 0 0.731898 0)
			(layer "B.SilkS")
			(hide yes)
			(effects
				(font
					(size 0.7 0.7)
					(thickness 0.15)
				)
				(justify left bottom mirror)
			)
		)
		(property "Value" "TP_1mm_SMD"
			(at 0 -1.4 0)
			(layer "B.Fab")
			(effects
				(font
					(size 0.7 0.7)
					(thickness 0.15)
				)
				(justify left bottom mirror)
			)
		)
		(property "Author" "Antmicro"
			(at 248.4 369.6 0)
			(layer "B.Fab")
			(hide yes)
			(effects
				(font
					(size 1 1)
					(thickness 0.15)
				)
				(justify mirror)
			)
		)
		(property "License" "Apache-2.0"
			(at 248.4 369.6 0)
			(layer "B.Fab")
			(hide yes)
			(effects
				(font
					(size 1 1)
					(thickness 0.15)
				)
				(justify mirror)
			)
		)
		(property "MPN" ""
			(at 248.4 369.6 0)
			(layer "B.Fab")
			(hide yes)
			(effects
				(font
					(size 1 1)
					(thickness 0.15)
				)
				(justify mirror)
			)
		)
		(property "Manufacturer" ""
			(at 248.4 369.6 0)
			(layer "B.Fab")
			(hide yes)
			(effects
				(font
					(size 1 1)
					(thickness 0.15)
				)
				(justify mirror)
			)
		)
		(sheetname "/FPGA bank 14/")
		(sheetfile "fpga-bank-14.kicad_sch")
		(attr exclude_from_pos_files)
		(pad "1" smd circle
			(at 0 0 180)
			(size 1 1)
			(layers "B.Cu" "B.Mask")
			(net 44 "/FPGA bank 14/EMCCLK")
			(pinfunction "1")
			(pintype "passive")
		)
	)
	(footprint "antmicro-footprints:C_0402_1005Metric"
		(layer "B.Cu")
		(at 140.375501 177.801 90)
		(descr "Capacitor SMD 0402 (1005 Metric), square (rectangular) end terminal, IPC_7351 nominal, (Body size source: IPC-SM-782 page 76, https://www.pcb-3d.com/wordpress/wp-content/uploads/ipc-sm-782a_amendment_1_and_2.pdf)")
		(tags "capacitor 0402")
		(property "Reference" "C71"
			(at 0 1.17 270)
			(layer "B.SilkS")
			(hide yes)
			(effects
				(font
					(size 0.7 0.7)
					(thickness 0.15)
				)
				(justify left bottom mirror)
			)
		)
		(property "Value" "C_4u7_0402"
			(at 0 -1.169 270)
			(layer "B.Fab")
			(effects
				(font
					(size 0.7 0.7)
					(thickness 0.15)
				)
				(justify left bottom mirror)
			)
		)
		(property "Datasheet" "https://www.murata.com/products/productdetail?partno=GRM155R61A475MEAA%23"
			(at 0 0 90)
			(layer "F.Fab")
			(hide yes)
			(effects
				(font
					(size 1.27 1.27)
					(thickness 0.15)
				)
			)
		)
		(property "Author" "Antmicro"
			(at 318.176501 37.425499 0)
			(layer "B.Fab")
			(hide yes)
			(effects
				(font
					(size 1 1)
					(thickness 0.15)
				)
				(justify mirror)
			)
		)
		(property "Dielectric" ""
			(at 318.176501 37.425499 0)
			(layer "B.Fab")
			(hide yes)
			(effects
				(font
					(size 1 1)
					(thickness 0.15)
				)
				(justify mirror)
			)
		)
		(property "License" "Apache-2.0"
			(at 318.176501 37.425499 0)
			(layer "B.Fab")
			(hide yes)
			(effects
				(font
					(size 1 1)
					(thickness 0.15)
				)
				(justify mirror)
			)
		)
		(property "MPN" "GRM155R61A475MEAAD"
			(at 318.176501 37.425499 0)
			(layer "B.Fab")
			(hide yes)
			(effects
				(font
					(size 1 1)
					(thickness 0.15)
				)
				(justify mirror)
			)
		)
		(property "Manufacturer" "Murata"
			(at 318.176501 37.425499 0)
			(layer "B.Fab")
			(hide yes)
			(effects
				(font
					(size 1 1)
					(thickness 0.15)
				)
				(justify mirror)
			)
		)
		(property "Val" "4u7"
			(at 318.176501 37.425499 0)
			(layer "B.Fab")
			(hide yes)
			(effects
				(font
					(size 1 1)
					(thickness 0.15)
				)
				(justify mirror)
			)
		)
		(property "Voltage" ""
			(at 318.176501 37.425499 0)
			(layer "B.Fab")
			(hide yes)
			(effects
				(font
					(size 1 1)
					(thickness 0.15)
				)
				(justify mirror)
			)
		)
		(sheetname "/FPGA power/")
		(sheetfile "fpga-power.kicad_sch")
		(attr smd)
		(fp_rect
			(start -0.9656 0.4572)
			(end 0.9652 -0.4828)
			(stroke
				(width 0.05)
				(type solid)
			)
			(fill no)
			(layer "B.CrtYd")
		)
		(fp_line
			(start 0.498 -0.248)
			(end -0.5 -0.248)
			(stroke
				(width 0.15)
				(type solid)
			)
			(layer "B.Fab")
		)
		(fp_line
			(start -0.5 -0.248)
			(end -0.5 0.25)
			(stroke
				(width 0.15)
				(type solid)
			)
			(layer "B.Fab")
		)
		(fp_line
			(start 0.498 0.25)
			(end 0.498 -0.248)
			(stroke
				(width 0.15)
				(type solid)
			)
			(layer "B.Fab")
		)
		(fp_line
			(start -0.5 0.25)
			(end 0.498 0.25)
			(stroke
				(width 0.15)
				(type solid)
			)
			(layer "B.Fab")
		)
		(pad "1" smd roundrect
			(at -0.5 0)
			(size 0.6 0.6)
			(layers "B.Cu" "B.Mask" "B.Paste")
			(roundrect_rratio 0.25)
			(net 227 "+1V0")
			(pintype "passive")
		)
		(pad "2" smd roundrect
			(at 0.498 0 90)
			(size 0.6 0.6)
			(layers "B.Cu" "B.Mask" "B.Paste")
			(roundrect_rratio 0.25)
			(net 1 "GND")
			(pintype "passive")
		)
	)
	(footprint "antmicro-footprints:R_0402_1005Metric"
		(layer "B.Cu")
		(at 138 142.4 90)
		(descr "Resistor SMD 0402")
		(tags "resistor SMD 0402")
		(property "Reference" "R24"
			(at 3.05 0.35 270)
			(layer "B.SilkS")
			(effects
				(font
					(size 0.7 0.7)
					(thickness 0.15)
				)
				(justify left bottom mirror)
			)
		)
		(property "Value" "R_0R_0402"
			(at -1.011843 -1.772047 270)
			(layer "B.Fab")
			(effects
				(font
					(size 0.7 0.7)
					(thickness 0.15)
				)
				(justify left bottom mirror)
			)
		)
		(property "Datasheet" "https://industrial.panasonic.com/cdbs/www-data/pdf/RDA0000/AOA0000C301.pdf"
			(at 0 0 90)
			(layer "F.Fab")
			(hide yes)
			(effects
				(font
					(size 1.27 1.27)
					(thickness 0.15)
				)
			)
		)
		(property "Author" "Antmicro"
			(at 280.4 4.4 0)
			(layer "B.Fab")
			(hide yes)
			(effects
				(font
					(size 1 1)
					(thickness 0.15)
				)
				(justify mirror)
			)
		)
		(property "Current" "1A"
			(at 280.4 4.4 0)
			(layer "B.Fab")
			(hide yes)
			(effects
				(font
					(size 1 1)
					(thickness 0.15)
				)
				(justify mirror)
			)
		)
		(property "License" "Apache-2.0"
			(at 280.4 4.4 0)
			(layer "B.Fab")
			(hide yes)
			(effects
				(font
					(size 1 1)
					(thickness 0.15)
				)
				(justify mirror)
			)
		)
		(property "MPN" "ERJ2GE0R00X"
			(at 280.4 4.4 0)
			(layer "B.Fab")
			(hide yes)
			(effects
				(font
					(size 1 1)
					(thickness 0.15)
				)
				(justify mirror)
			)
		)
		(property "Manufacturer" "Panasonic"
			(at 280.4 4.4 0)
			(layer "B.Fab")
			(hide yes)
			(effects
				(font
					(size 1 1)
					(thickness 0.15)
				)
				(justify mirror)
			)
		)
		(property "Tolerance" ""
			(at 280.4 4.4 0)
			(layer "B.Fab")
			(hide yes)
			(effects
				(font
					(size 1 1)
					(thickness 0.15)
				)
				(justify mirror)
			)
		)
		(property "Val" "0R"
			(at 280.4 4.4 0)
			(layer "B.Fab")
			(hide yes)
			(effects
				(font
					(size 1 1)
					(thickness 0.15)
				)
				(justify mirror)
			)
		)
		(sheetname "/DDR5 SODIMM/")
		(sheetfile "ddr5-sodimm.kicad_sch")
		(attr exclude_from_pos_files exclude_from_bom dnp)
		(fp_rect
			(start -0.93 0.47)
			(end 0.93 -0.47)
			(stroke
				(width 0.05)
				(type solid)
			)
			(fill no)
			(layer "B.CrtYd")
		)
		(fp_rect
			(start -0.5 0.25)
			(end 0.5 -0.25)
			(stroke
				(width 0.15)
				(type solid)
			)
			(fill no)
			(layer "B.Fab")
		)
		(pad "1" smd roundrect
			(at -0.485 0 90)
			(size 0.59 0.64)
			(layers "B.Cu" "B.Mask" "B.Paste")
			(roundrect_rratio 0.25)
			(net 1 "GND")
			(pintype "passive")
		)
		(pad "2" smd roundrect
			(at 0.485 0 90)
			(size 0.59 0.64)
			(layers "B.Cu" "B.Mask" "B.Paste")
			(roundrect_rratio 0.25)
			(net 172 "/DDR5 SODIMM/VSS_DET2")
			(pintype "passive")
		)
	)
	(footprint "antmicro-footprints:C_0402_1005Metric"
		(layer "B.Cu")
		(at 144.877001 184.3005)
		(descr "Capacitor SMD 0402 (1005 Metric), square (rectangular) end terminal, IPC_7351 nominal, (Body size source: IPC-SM-782 page 76, https://www.pcb-3d.com/wordpress/wp-content/uploads/ipc-sm-782a_amendment_1_and_2.pdf)")
		(tags "capacitor 0402")
		(property "Reference" "C57"
			(at 0 1.17 180)
			(layer "B.SilkS")
			(hide yes)
			(effects
				(font
					(size 0.7 0.7)
					(thickness 0.15)
				)
				(justify left bottom mirror)
			)
		)
		(property "Value" "C_4u7_0402"
			(at 0 -1.169 180)
			(layer "B.Fab")
			(effects
				(font
					(size 0.7 0.7)
					(thickness 0.15)
				)
				(justify left bottom mirror)
			)
		)
		(property "Datasheet" "https://www.murata.com/products/productdetail?partno=GRM155R61A475MEAA%23"
			(at 0 0 0)
			(layer "F.Fab")
			(hide yes)
			(effects
				(font
					(size 1.27 1.27)
					(thickness 0.15)
				)
			)
		)
		(property "Author" "Antmicro"
			(at 0 0 0)
			(layer "B.Fab")
			(hide yes)
			(effects
				(font
					(size 1 1)
					(thickness 0.15)
				)
				(justify mirror)
			)
		)
		(property "Dielectric" ""
			(at 0 0 0)
			(layer "B.Fab")
			(hide yes)
			(effects
				(font
					(size 1 1)
					(thickness 0.15)
				)
				(justify mirror)
			)
		)
		(property "License" "Apache-2.0"
			(at 0 0 0)
			(layer "B.Fab")
			(hide yes)
			(effects
				(font
					(size 1 1)
					(thickness 0.15)
				)
				(justify mirror)
			)
		)
		(property "MPN" "GRM155R61A475MEAAD"
			(at 0 0 0)
			(layer "B.Fab")
			(hide yes)
			(effects
				(font
					(size 1 1)
					(thickness 0.15)
				)
				(justify mirror)
			)
		)
		(property "Manufacturer" "Murata"
			(at 0 0 0)
			(layer "B.Fab")
			(hide yes)
			(effects
				(font
					(size 1 1)
					(thickness 0.15)
				)
				(justify mirror)
			)
		)
		(property "Val" "4u7"
			(at 0 0 0)
			(layer "B.Fab")
			(hide yes)
			(effects
				(font
					(size 1 1)
					(thickness 0.15)
				)
				(justify mirror)
			)
		)
		(property "Voltage" ""
			(at 0 0 0)
			(layer "B.Fab")
			(hide yes)
			(effects
				(font
					(size 1 1)
					(thickness 0.15)
				)
				(justify mirror)
			)
		)
		(sheetname "/FPGA power/")
		(sheetfile "fpga-power.kicad_sch")
		(attr smd)
		(fp_rect
			(start -0.9656 0.4572)
			(end 0.9652 -0.4828)
			(stroke
				(width 0.05)
				(type solid)
			)
			(fill no)
			(layer "B.CrtYd")
		)
		(fp_line
			(start -0.5 -0.248)
			(end -0.5 0.25)
			(stroke
				(width 0.15)
				(type solid)
			)
			(layer "B.Fab")
		)
		(fp_line
			(start -0.5 0.25)
			(end 0.498 0.25)
			(stroke
				(width 0.15)
				(type solid)
			)
			(layer "B.Fab")
		)
		(fp_line
			(start 0.498 -0.248)
			(end -0.5 -0.248)
			(stroke
				(width 0.15)
				(type solid)
			)
			(layer "B.Fab")
		)
		(fp_line
			(start 0.498 0.25)
			(end 0.498 -0.248)
			(stroke
				(width 0.15)
				(type solid)
			)
			(layer "B.Fab")
		)
		(pad "1" smd roundrect
			(at -0.5 0 270)
			(size 0.6 0.6)
			(layers "B.Cu" "B.Mask" "B.Paste")
			(roundrect_rratio 0.25)
			(net 188 "+1V8")
			(pintype "passive")
		)
		(pad "2" smd roundrect
			(at 0.498 0)
			(size 0.6 0.6)
			(layers "B.Cu" "B.Mask" "B.Paste")
			(roundrect_rratio 0.25)
			(net 1 "GND")
			(pintype "passive")
		)
	)
	(footprint "antmicro-footprints:R_0402_1005Metric"
		(layer "B.Cu")
		(at 195.415 146.851)
		(descr "Resistor SMD 0402")
		(tags "resistor SMD 0402")
		(property "Reference" "R187"
			(at -1.122484 0.772697 180)
			(layer "B.SilkS")
			(hide yes)
			(effects
				(font
					(size 0.7 0.7)
					(thickness 0.15)
				)
				(justify left bottom mirror)
			)
		)
		(property "Value" "R_47k_0402"
			(at -1.011843 -1.772047 180)
			(layer "B.Fab")
			(effects
				(font
					(size 0.7 0.7)
					(thickness 0.15)
				)
				(justify left bottom mirror)
			)
		)
		(property "Datasheet" "https://www.bourns.com/docs/product-datasheets/cr.pdf"
			(at 0 0 0)
			(layer "F.Fab")
			(hide yes)
			(effects
				(font
					(size 1.27 1.27)
					(thickness 0.15)
				)
			)
		)
		(property "Author" "Antmicro"
			(at 0 0 0)
			(layer "B.Fab")
			(hide yes)
			(effects
				(font
					(size 1 1)
					(thickness 0.15)
				)
				(justify mirror)
			)
		)
		(property "License" "Apache-2.0"
			(at 0 0 0)
			(layer "B.Fab")
			(hide yes)
			(effects
				(font
					(size 1 1)
					(thickness 0.15)
				)
				(justify mirror)
			)
		)
		(property "MPN" "CR0402-FX-4702GLF"
			(at 0 0 0)
			(layer "B.Fab")
			(hide yes)
			(effects
				(font
					(size 1 1)
					(thickness 0.15)
				)
				(justify mirror)
			)
		)
		(property "Manufacturer" "Bourns"
			(at 0 0 0)
			(layer "B.Fab")
			(hide yes)
			(effects
				(font
					(size 1 1)
					(thickness 0.15)
				)
				(justify mirror)
			)
		)
		(property "Tolerance" "1%"
			(at 0 0 0)
			(layer "B.Fab")
			(hide yes)
			(effects
				(font
					(size 1 1)
					(thickness 0.15)
				)
				(justify mirror)
			)
		)
		(property "Val" "47k"
			(at 0 0 0)
			(layer "B.Fab")
			(hide yes)
			(effects
				(font
					(size 1 1)
					(thickness 0.15)
				)
				(justify mirror)
			)
		)
		(sheetname "/Supply/")
		(sheetfile "supply.kicad_sch")
		(attr smd)
		(fp_rect
			(start -0.93 0.47)
			(end 0.93 -0.47)
			(stroke
				(width 0.05)
				(type solid)
			)
			(fill no)
			(layer "B.CrtYd")
		)
		(fp_rect
			(start -0.5 0.25)
			(end 0.5 -0.25)
			(stroke
				(width 0.15)
				(type solid)
			)
			(fill no)
			(layer "B.Fab")
		)
		(pad "1" smd roundrect
			(at -0.485 0)
			(size 0.59 0.64)
			(layers "B.Cu" "B.Mask" "B.Paste")
			(roundrect_rratio 0.25)
			(net 222 "/Supply/EN2")
			(pintype "passive")
		)
		(pad "2" smd roundrect
			(at 0.485 0)
			(size 0.59 0.64)
			(layers "B.Cu" "B.Mask" "B.Paste")
			(roundrect_rratio 0.25)
			(net 41 "+3V3_AON")
			(pintype "passive")
		)
	)
	(footprint "antmicro-footprints:TP_SMD_1mm"
		(layer "B.Cu")
		(at 203.1 151.8 90)
		(property "Reference" "TP41"
			(at 0.5 -0.4 270)
			(layer "B.SilkS")
			(effects
				(font
					(size 0.7 0.7)
					(thickness 0.15)
				)
				(justify right top mirror)
			)
		)
		(property "Value" "TP_1mm_SMD"
			(at 0 -1.4 90)
			(layer "B.Fab")
			(effects
				(font
					(size 0.7 0.7)
					(thickness 0.15)
				)
				(justify right top mirror)
			)
		)
		(property "MPN" ""
			(at 0 0 270)
			(unlocked yes)
			(layer "B.Fab")
			(hide yes)
			(effects
				(font
					(size 1 1)
					(thickness 0.15)
				)
				(justify mirror)
			)
		)
		(property "Manufacturer" ""
			(at 0 0 270)
			(unlocked yes)
			(layer "B.Fab")
			(hide yes)
			(effects
				(font
					(size 1 1)
					(thickness 0.15)
				)
				(justify mirror)
			)
		)
		(property "Author" "Antmicro"
			(at 0 0 270)
			(unlocked yes)
			(layer "B.Fab")
			(hide yes)
			(effects
				(font
					(size 1 1)
					(thickness 0.15)
				)
				(justify mirror)
			)
		)
		(property "License" "Apache-2.0"
			(at 0 0 270)
			(unlocked yes)
			(layer "B.Fab")
			(hide yes)
			(effects
				(font
					(size 1 1)
					(thickness 0.15)
				)
				(justify mirror)
			)
		)
		(sheetname "/I^{2}C/")
		(sheetfile "i2c.kicad_sch")
		(attr exclude_from_pos_files)
		(fp_circle
			(center 0 0)
			(end 0.6 0)
			(stroke
				(width 0.05)
				(type default)
			)
			(fill no)
			(layer "B.CrtYd")
		)
		(fp_text user "${REFERENCE}"
			(at -0.5 -2.8 90)
			(layer "B.Fab")
			(effects
				(font
					(size 0.7 0.7)
					(thickness 0.15)
				)
				(justify right top mirror)
			)
		)
		(fp_text user "Author: Antmicro"
			(at -0.5 -4 90)
			(layer "B.Fab")
			(effects
				(font
					(size 0.7 0.7)
					(thickness 0.15)
				)
				(justify right top mirror)
			)
		)
		(fp_text user "License: Apache-2.0"
			(at -0.5 -5.2 90)
			(layer "B.Fab")
			(effects
				(font
					(size 0.7 0.7)
					(thickness 0.15)
				)
				(justify right top mirror)
			)
		)
		(pad "1" smd circle
			(at 0 0 90)
			(size 1 1)
			(layers "B.Cu" "B.Mask")
			(net 687 "IN2")
			(pinfunction "1")
			(pintype "passive")
		)
	)
	(footprint "antmicro-footprints:C_0402_1005Metric"
		(layer "B.Cu")
		(at 140.375001 172.8025 90)
		(descr "Capacitor SMD 0402 (1005 Metric), square (rectangular) end terminal, IPC_7351 nominal, (Body size source: IPC-SM-782 page 76, https://www.pcb-3d.com/wordpress/wp-content/uploads/ipc-sm-782a_amendment_1_and_2.pdf)")
		(tags "capacitor 0402")
		(property "Reference" "C33"
			(at 0 1.17 270)
			(layer "B.SilkS")
			(hide yes)
			(effects
				(font
					(size 0.7 0.7)
					(thickness 0.15)
				)
				(justify left bottom mirror)
			)
		)
		(property "Value" "C_100n_0402"
			(at 0 -1.169 270)
			(layer "B.Fab")
			(effects
				(font
					(size 0.7 0.7)
					(thickness 0.15)
				)
				(justify left bottom mirror)
			)
		)
		(property "Datasheet" "https://www.murata.com/products/productdetail?partno=GRM155R61H104KE14%23"
			(at 0 0 90)
			(layer "F.Fab")
			(hide yes)
			(effects
				(font
					(size 1.27 1.27)
					(thickness 0.15)
				)
			)
		)
		(property "Author" "Antmicro"
			(at 313.177501 32.427499 0)
			(layer "B.Fab")
			(hide yes)
			(effects
				(font
					(size 1 1)
					(thickness 0.15)
				)
				(justify mirror)
			)
		)
		(property "Dielectric" "X5R"
			(at 313.177501 32.427499 0)
			(layer "B.Fab")
			(hide yes)
			(effects
				(font
					(size 1 1)
					(thickness 0.15)
				)
				(justify mirror)
			)
		)
		(property "License" "Apache-2.0"
			(at 313.177501 32.427499 0)
			(layer "B.Fab")
			(hide yes)
			(effects
				(font
					(size 1 1)
					(thickness 0.15)
				)
				(justify mirror)
			)
		)
		(property "MPN" "GRM155R61H104KE14D"
			(at 313.177501 32.427499 0)
			(layer "B.Fab")
			(hide yes)
			(effects
				(font
					(size 1 1)
					(thickness 0.15)
				)
				(justify mirror)
			)
		)
		(property "Manufacturer" "Murata"
			(at 313.177501 32.427499 0)
			(layer "B.Fab")
			(hide yes)
			(effects
				(font
					(size 1 1)
					(thickness 0.15)
				)
				(justify mirror)
			)
		)
		(property "Val" "100n"
			(at 313.177501 32.427499 0)
			(layer "B.Fab")
			(hide yes)
			(effects
				(font
					(size 1 1)
					(thickness 0.15)
				)
				(justify mirror)
			)
		)
		(property "Voltage" "50V"
			(at 313.177501 32.427499 0)
			(layer "B.Fab")
			(hide yes)
			(effects
				(font
					(size 1 1)
					(thickness 0.15)
				)
				(justify mirror)
			)
		)
		(sheetname "/FPGA power/")
		(sheetfile "fpga-power.kicad_sch")
		(attr smd)
		(fp_rect
			(start -0.9656 0.4572)
			(end 0.9652 -0.4828)
			(stroke
				(width 0.05)
				(type solid)
			)
			(fill no)
			(layer "B.CrtYd")
		)
		(fp_line
			(start 0.498 -0.248)
			(end -0.5 -0.248)
			(stroke
				(width 0.15)
				(type solid)
			)
			(layer "B.Fab")
		)
		(fp_line
			(start -0.5 -0.248)
			(end -0.5 0.25)
			(stroke
				(width 0.15)
				(type solid)
			)
			(layer "B.Fab")
		)
		(fp_line
			(start 0.498 0.25)
			(end 0.498 -0.248)
			(stroke
				(width 0.15)
				(type solid)
			)
			(layer "B.Fab")
		)
		(fp_line
			(start -0.5 0.25)
			(end 0.498 0.25)
			(stroke
				(width 0.15)
				(type solid)
			)
			(layer "B.Fab")
		)
		(pad "1" smd roundrect
			(at -0.5 0)
			(size 0.6 0.6)
			(layers "B.Cu" "B.Mask" "B.Paste")
			(roundrect_rratio 0.25)
			(net 1 "GND")
			(pintype "passive")
		)
		(pad "2" smd roundrect
			(at 0.498 0 90)
			(size 0.6 0.6)
			(layers "B.Cu" "B.Mask" "B.Paste")
			(roundrect_rratio 0.25)
			(net 227 "+1V0")
			(pintype "passive")
		)
	)
	(footprint "antmicro-footprints:TP_SMD_1mm"
		(layer "B.Cu")
		(at 199.2 141.2 180)
		(property "Reference" "TP26"
			(at 0 0.731898 0)
			(layer "B.SilkS")
			(hide yes)
			(effects
				(font
					(size 0.7 0.7)
					(thickness 0.15)
				)
				(justify left bottom mirror)
			)
		)
		(property "Value" "TP_1mm_SMD"
			(at 0 -1.4 0)
			(layer "B.Fab")
			(effects
				(font
					(size 0.7 0.7)
					(thickness 0.15)
				)
				(justify left bottom mirror)
			)
		)
		(property "MPN" ""
			(at 0 0 0)
			(unlocked yes)
			(layer "B.Fab")
			(hide yes)
			(effects
				(font
					(size 1 1)
					(thickness 0.15)
				)
				(justify mirror)
			)
		)
		(property "Manufacturer" ""
			(at 0 0 0)
			(unlocked yes)
			(layer "B.Fab")
			(hide yes)
			(effects
				(font
					(size 1 1)
					(thickness 0.15)
				)
				(justify mirror)
			)
		)
		(property "Author" "Antmicro"
			(at 0 0 0)
			(unlocked yes)
			(layer "B.Fab")
			(hide yes)
			(effects
				(font
					(size 1 1)
					(thickness 0.15)
				)
				(justify mirror)
			)
		)
		(property "License" "Apache-2.0"
			(at 0 0 0)
			(unlocked yes)
			(layer "B.Fab")
			(hide yes)
			(effects
				(font
					(size 1 1)
					(thickness 0.15)
				)
				(justify mirror)
			)
		)
		(sheetname "/Supply/")
		(sheetfile "supply.kicad_sch")
		(attr exclude_from_pos_files)
		(fp_circle
			(center 0 0)
			(end 0.6 0)
			(stroke
				(width 0.05)
				(type default)
			)
			(fill no)
			(layer "B.CrtYd")
		)
		(fp_text user "Author: Antmicro"
			(at -0.5 -4 0)
			(layer "B.Fab")
			(effects
				(font
					(size 0.7 0.7)
					(thickness 0.15)
				)
				(justify left bottom mirror)
			)
		)
		(fp_text user "License: Apache-2.0"
			(at -0.5 -5.2 0)
			(layer "B.Fab")
			(effects
				(font
					(size 0.7 0.7)
					(thickness 0.15)
				)
				(justify left bottom mirror)
			)
		)
		(fp_text user "${REFERENCE}"
			(at -0.5 -2.8 0)
			(layer "B.Fab")
			(effects
				(font
					(size 0.7 0.7)
					(thickness 0.15)
				)
				(justify left bottom mirror)
			)
		)
		(pad "1" smd circle
			(at 0 0 180)
			(size 1 1)
			(layers "B.Cu" "B.Mask")
			(net 41 "+3V3_AON")
			(pinfunction "1")
			(pintype "passive")
		)
	)
	(footprint "antmicro-footprints:C_0402_1005Metric"
		(layer "B.Cu")
		(at 104.95 171.988 90)
		(descr "Capacitor SMD 0402")
		(tags "capacitor SMD 0402")
		(property "Reference" "C237"
			(at 0 0.699 90)
			(layer "B.SilkS")
			(hide yes)
			(effects
				(font
					(size 0.7 0.7)
					(thickness 0.15)
				)
				(justify right bottom mirror)
			)
		)
		(property "Value" "C_100n_0402"
			(at -1.022927 -2.155213 90)
			(layer "B.Fab")
			(effects
				(font
					(size 0.7 0.7)
					(thickness 0.15)
				)
				(justify right bottom mirror)
			)
		)
		(property "Datasheet" "https://www.murata.com/products/productdetail?partno=GRM155R61H104KE14%23"
			(at 0 0 90)
			(layer "F.Fab")
			(hide yes)
			(effects
				(font
					(size 1.27 1.27)
					(thickness 0.15)
				)
			)
		)
		(property "Author" "Antmicro"
			(at 276.938 67.038 0)
			(layer "B.Fab")
			(hide yes)
			(effects
				(font
					(size 1 1)
					(thickness 0.15)
				)
				(justify mirror)
			)
		)
		(property "Dielectric" "X5R"
			(at 276.938 67.038 0)
			(layer "B.Fab")
			(hide yes)
			(effects
				(font
					(size 1 1)
					(thickness 0.15)
				)
				(justify mirror)
			)
		)
		(property "License" "Apache-2.0"
			(at 276.938 67.038 0)
			(layer "B.Fab")
			(hide yes)
			(effects
				(font
					(size 1 1)
					(thickness 0.15)
				)
				(justify mirror)
			)
		)
		(property "MPN" "GRM155R61H104KE14D"
			(at 276.938 67.038 0)
			(layer "B.Fab")
			(hide yes)
			(effects
				(font
					(size 1 1)
					(thickness 0.15)
				)
				(justify mirror)
			)
		)
		(property "Manufacturer" "Murata"
			(at 276.938 67.038 0)
			(layer "B.Fab")
			(hide yes)
			(effects
				(font
					(size 1 1)
					(thickness 0.15)
				)
				(justify mirror)
			)
		)
		(property "Val" "100n"
			(at 276.938 67.038 0)
			(layer "B.Fab")
			(hide yes)
			(effects
				(font
					(size 1 1)
					(thickness 0.15)
				)
				(justify mirror)
			)
		)
		(property "Voltage" "50V"
			(at 276.938 67.038 0)
			(layer "B.Fab")
			(hide yes)
			(effects
				(font
					(size 1 1)
					(thickness 0.15)
				)
				(justify mirror)
			)
		)
		(sheetname "/Debug FTDI/")
		(sheetfile "debug-ftdi.kicad_sch")
		(attr smd)
		(fp_rect
			(start -0.925 0.47)
			(end 0.925 -0.47)
			(stroke
				(width 0.05)
				(type default)
			)
			(fill no)
			(layer "B.CrtYd")
		)
		(fp_line
			(start 0.504 -0.248)
			(end -0.494 -0.248)
			(stroke
				(width 0.15)
				(type solid)
			)
			(layer "B.Fab")
		)
		(fp_line
			(start -0.494 -0.248)
			(end -0.494 0.25)
			(stroke
				(width 0.15)
				(type solid)
			)
			(layer "B.Fab")
		)
		(fp_line
			(start 0.504 0.25)
			(end 0.504 -0.248)
			(stroke
				(width 0.15)
				(type solid)
			)
			(layer "B.Fab")
		)
		(fp_line
			(start -0.494 0.25)
			(end 0.504 0.25)
			(stroke
				(width 0.15)
				(type solid)
			)
			(layer "B.Fab")
		)
		(pad "1" smd roundrect
			(at -0.48 0 90)
			(size 0.59 0.64)
			(layers "B.Cu" "B.Mask" "B.Paste")
			(roundrect_rratio 0.25)
			(net 1 "GND")
			(pintype "passive")
		)
		(pad "2" smd roundrect
			(at 0.48 0 90)
			(size 0.59 0.64)
			(layers "B.Cu" "B.Mask" "B.Paste")
			(roundrect_rratio 0.25)
			(net 6 "/Debug FTDI/FTDI_3V3")
			(pintype "passive")
		)
	)
	(footprint "antmicro-footprints:C_0402_1005Metric"
		(layer "B.Cu")
		(at 136.877002 171.3025 180)
		(descr "Capacitor SMD 0402 (1005 Metric), square (rectangular) end terminal, IPC_7351 nominal, (Body size source: IPC-SM-782 page 76, https://www.pcb-3d.com/wordpress/wp-content/uploads/ipc-sm-782a_amendment_1_and_2.pdf)")
		(tags "capacitor 0402")
		(property "Reference" "C26"
			(at 0 1.17 0)
			(layer "B.SilkS")
			(hide yes)
			(effects
				(font
					(size 0.7 0.7)
					(thickness 0.15)
				)
				(justify left bottom mirror)
			)
		)
		(property "Value" "C_100n_0402"
			(at 0 -1.169 0)
			(layer "B.Fab")
			(effects
				(font
					(size 0.7 0.7)
					(thickness 0.15)
				)
				(justify left bottom mirror)
			)
		)
		(property "Datasheet" "https://www.murata.com/products/productdetail?partno=GRM155R61H104KE14%23"
			(at 0 0 180)
			(layer "F.Fab")
			(hide yes)
			(effects
				(font
					(size 1.27 1.27)
					(thickness 0.15)
				)
			)
		)
		(property "Author" "Antmicro"
			(at 273.754004 342.605 0)
			(layer "B.Fab")
			(hide yes)
			(effects
				(font
					(size 1 1)
					(thickness 0.15)
				)
				(justify mirror)
			)
		)
		(property "Dielectric" "X5R"
			(at 273.754004 342.605 0)
			(layer "B.Fab")
			(hide yes)
			(effects
				(font
					(size 1 1)
					(thickness 0.15)
				)
				(justify mirror)
			)
		)
		(property "License" "Apache-2.0"
			(at 273.754004 342.605 0)
			(layer "B.Fab")
			(hide yes)
			(effects
				(font
					(size 1 1)
					(thickness 0.15)
				)
				(justify mirror)
			)
		)
		(property "MPN" "GRM155R61H104KE14D"
			(at 273.754004 342.605 0)
			(layer "B.Fab")
			(hide yes)
			(effects
				(font
					(size 1 1)
					(thickness 0.15)
				)
				(justify mirror)
			)
		)
		(property "Manufacturer" "Murata"
			(at 273.754004 342.605 0)
			(layer "B.Fab")
			(hide yes)
			(effects
				(font
					(size 1 1)
					(thickness 0.15)
				)
				(justify mirror)
			)
		)
		(property "Val" "100n"
			(at 273.754004 342.605 0)
			(layer "B.Fab")
			(hide yes)
			(effects
				(font
					(size 1 1)
					(thickness 0.15)
				)
				(justify mirror)
			)
		)
		(property "Voltage" "50V"
			(at 273.754004 342.605 0)
			(layer "B.Fab")
			(hide yes)
			(effects
				(font
					(size 1 1)
					(thickness 0.15)
				)
				(justify mirror)
			)
		)
		(sheetname "/FPGA power/")
		(sheetfile "fpga-power.kicad_sch")
		(attr smd)
		(fp_rect
			(start -0.9656 0.4572)
			(end 0.9652 -0.4828)
			(stroke
				(width 0.05)
				(type solid)
			)
			(fill no)
			(layer "B.CrtYd")
		)
		(fp_line
			(start 0.498 0.25)
			(end 0.498 -0.248)
			(stroke
				(width 0.15)
				(type solid)
			)
			(layer "B.Fab")
		)
		(fp_line
			(start 0.498 -0.248)
			(end -0.5 -0.248)
			(stroke
				(width 0.15)
				(type solid)
			)
			(layer "B.Fab")
		)
		(fp_line
			(start -0.5 0.25)
			(end 0.498 0.25)
			(stroke
				(width 0.15)
				(type solid)
			)
			(layer "B.Fab")
		)
		(fp_line
			(start -0.5 -0.248)
			(end -0.5 0.25)
			(stroke
				(width 0.15)
				(type solid)
			)
			(layer "B.Fab")
		)
		(pad "1" smd roundrect
			(at -0.5 0 90)
			(size 0.6 0.6)
			(layers "B.Cu" "B.Mask" "B.Paste")
			(roundrect_rratio 0.25)
			(net 1 "GND")
			(pintype "passive")
		)
		(pad "2" smd roundrect
			(at 0.498 0 180)
			(size 0.6 0.6)
			(layers "B.Cu" "B.Mask" "B.Paste")
			(roundrect_rratio 0.25)
			(net 227 "+1V0")
			(pintype "passive")
		)
	)
	(footprint "antmicro-footprints:R_0402_1005Metric"
		(layer "B.Cu")
		(at 122.350501 175.426 180)
		(descr "Resistor SMD 0402")
		(tags "resistor SMD 0402")
		(property "Reference" "R2"
			(at -1.122484 0.772697 0)
			(layer "B.SilkS")
			(hide yes)
			(effects
				(font
					(size 0.7 0.7)
					(thickness 0.15)
				)
				(justify left bottom mirror)
			)
		)
		(property "Value" "R_10k_0402"
			(at -1.011843 -1.772047 0)
			(layer "B.Fab")
			(effects
				(font
					(size 0.7 0.7)
					(thickness 0.15)
				)
				(justify left bottom mirror)
			)
		)
		(property "Datasheet" "https://www.bourns.com/docs/product-datasheets/cr.pdf"
			(at 0 0 180)
			(layer "F.Fab")
			(hide yes)
			(effects
				(font
					(size 1.27 1.27)
					(thickness 0.15)
				)
			)
		)
		(property "Author" "Antmicro"
			(at 244.701002 350.852 0)
			(layer "B.Fab")
			(hide yes)
			(effects
				(font
					(size 1 1)
					(thickness 0.15)
				)
				(justify mirror)
			)
		)
		(property "License" "Apache-2.0"
			(at 244.701002 350.852 0)
			(layer "B.Fab")
			(hide yes)
			(effects
				(font
					(size 1 1)
					(thickness 0.15)
				)
				(justify mirror)
			)
		)
		(property "MPN" "CR0402-FX-1002GLF"
			(at 244.701002 350.852 0)
			(layer "B.Fab")
			(hide yes)
			(effects
				(font
					(size 1 1)
					(thickness 0.15)
				)
				(justify mirror)
			)
		)
		(property "Manufacturer" "Bourns"
			(at 244.701002 350.852 0)
			(layer "B.Fab")
			(hide yes)
			(effects
				(font
					(size 1 1)
					(thickness 0.15)
				)
				(justify mirror)
			)
		)
		(property "Tolerance" "1%"
			(at 244.701002 350.852 0)
			(layer "B.Fab")
			(hide yes)
			(effects
				(font
					(size 1 1)
					(thickness 0.15)
				)
				(justify mirror)
			)
		)
		(property "Val" "10k"
			(at 244.701002 350.852 0)
			(layer "B.Fab")
			(hide yes)
			(effects
				(font
					(size 1 1)
					(thickness 0.15)
				)
				(justify mirror)
			)
		)
		(sheetname "/HyperRAM + QSPI Flash/")
		(sheetfile "hyperram-flash.kicad_sch")
		(attr smd)
		(fp_rect
			(start -0.93 0.47)
			(end 0.93 -0.47)
			(stroke
				(width 0.05)
				(type solid)
			)
			(fill no)
			(layer "B.CrtYd")
		)
		(fp_rect
			(start -0.5 0.25)
			(end 0.5 -0.25)
			(stroke
				(width 0.15)
				(type solid)
			)
			(fill no)
			(layer "B.Fab")
		)
		(pad "1" smd roundrect
			(at -0.485 0 180)
			(size 0.59 0.64)
			(layers "B.Cu" "B.Mask" "B.Paste")
			(roundrect_rratio 0.25)
			(net 200 "+3V3")
			(pintype "passive")
		)
		(pad "2" smd roundrect
			(at 0.485 0 180)
			(size 0.59 0.64)
			(layers "B.Cu" "B.Mask" "B.Paste")
			(roundrect_rratio 0.25)
			(net 624 "/FPGA bank 12/HyperRAM.~{CS}")
			(pintype "passive")
		)
	)
	(footprint "antmicro-footprints:C_0402_1005Metric"
		(layer "B.Cu")
		(at 147.875001 179.3005 180)
		(descr "Capacitor SMD 0402 (1005 Metric), square (rectangular) end terminal, IPC_7351 nominal, (Body size source: IPC-SM-782 page 76, https://www.pcb-3d.com/wordpress/wp-content/uploads/ipc-sm-782a_amendment_1_and_2.pdf)")
		(tags "capacitor 0402")
		(property "Reference" "C99"
			(at 0 1.17 0)
			(layer "B.SilkS")
			(hide yes)
			(effects
				(font
					(size 0.7 0.7)
					(thickness 0.15)
				)
				(justify left bottom mirror)
			)
		)
		(property "Value" "C_100n_0402"
			(at 0 -1.169 0)
			(layer "B.Fab")
			(effects
				(font
					(size 0.7 0.7)
					(thickness 0.15)
				)
				(justify left bottom mirror)
			)
		)
		(property "Datasheet" "https://www.murata.com/products/productdetail?partno=GRM155R61H104KE14%23"
			(at 0 0 180)
			(layer "F.Fab")
			(hide yes)
			(effects
				(font
					(size 1.27 1.27)
					(thickness 0.15)
				)
			)
		)
		(property "Author" "Antmicro"
			(at 295.750002 358.601 0)
			(layer "B.Fab")
			(hide yes)
			(effects
				(font
					(size 1 1)
					(thickness 0.15)
				)
				(justify mirror)
			)
		)
		(property "Dielectric" "X5R"
			(at 295.750002 358.601 0)
			(layer "B.Fab")
			(hide yes)
			(effects
				(font
					(size 1 1)
					(thickness 0.15)
				)
				(justify mirror)
			)
		)
		(property "License" "Apache-2.0"
			(at 295.750002 358.601 0)
			(layer "B.Fab")
			(hide yes)
			(effects
				(font
					(size 1 1)
					(thickness 0.15)
				)
				(justify mirror)
			)
		)
		(property "MPN" "GRM155R61H104KE14D"
			(at 295.750002 358.601 0)
			(layer "B.Fab")
			(hide yes)
			(effects
				(font
					(size 1 1)
					(thickness 0.15)
				)
				(justify mirror)
			)
		)
		(property "Manufacturer" "Murata"
			(at 295.750002 358.601 0)
			(layer "B.Fab")
			(hide yes)
			(effects
				(font
					(size 1 1)
					(thickness 0.15)
				)
				(justify mirror)
			)
		)
		(property "Val" "100n"
			(at 295.750002 358.601 0)
			(layer "B.Fab")
			(hide yes)
			(effects
				(font
					(size 1 1)
					(thickness 0.15)
				)
				(justify mirror)
			)
		)
		(property "Voltage" "50V"
			(at 295.750002 358.601 0)
			(layer "B.Fab")
			(hide yes)
			(effects
				(font
					(size 1 1)
					(thickness 0.15)
				)
				(justify mirror)
			)
		)
		(sheetname "/FPGA power/")
		(sheetfile "fpga-power.kicad_sch")
		(attr smd)
		(fp_rect
			(start -0.9656 0.4572)
			(end 0.9652 -0.4828)
			(stroke
				(width 0.05)
				(type solid)
			)
			(fill no)
			(layer "B.CrtYd")
		)
		(fp_line
			(start 0.498 0.25)
			(end 0.498 -0.248)
			(stroke
				(width 0.15)
				(type solid)
			)
			(layer "B.Fab")
		)
		(fp_line
			(start 0.498 -0.248)
			(end -0.5 -0.248)
			(stroke
				(width 0.15)
				(type solid)
			)
			(layer "B.Fab")
		)
		(fp_line
			(start -0.5 0.25)
			(end 0.498 0.25)
			(stroke
				(width 0.15)
				(type solid)
			)
			(layer "B.Fab")
		)
		(fp_line
			(start -0.5 -0.248)
			(end -0.5 0.25)
			(stroke
				(width 0.15)
				(type solid)
			)
			(layer "B.Fab")
		)
		(pad "1" smd roundrect
			(at -0.5 0 90)
			(size 0.6 0.6)
			(layers "B.Cu" "B.Mask" "B.Paste")
			(roundrect_rratio 0.25)
			(net 1 "GND")
			(pintype "passive")
		)
		(pad "2" smd roundrect
			(at 0.498 0 180)
			(size 0.6 0.6)
			(layers "B.Cu" "B.Mask" "B.Paste")
			(roundrect_rratio 0.25)
			(net 187 "+1V0_MGTAVCC")
			(pintype "passive")
		)
	)
	(footprint "antmicro-footprints:C_0402_1005Metric"
		(layer "B.Cu")
		(at 127.875501 165.301 180)
		(descr "Capacitor SMD 0402 (1005 Metric), square (rectangular) end terminal, IPC_7351 nominal, (Body size source: IPC-SM-782 page 76, https://www.pcb-3d.com/wordpress/wp-content/uploads/ipc-sm-782a_amendment_1_and_2.pdf)")
		(tags "capacitor 0402")
		(property "Reference" "C35"
			(at 0 1.17 0)
			(layer "B.SilkS")
			(hide yes)
			(effects
				(font
					(size 0.7 0.7)
					(thickness 0.15)
				)
				(justify left bottom mirror)
			)
		)
		(property "Value" "C_100n_0402"
			(at 0 -1.169 0)
			(layer "B.Fab")
			(effects
				(font
					(size 0.7 0.7)
					(thickness 0.15)
				)
				(justify left bottom mirror)
			)
		)
		(property "Datasheet" "https://www.murata.com/products/productdetail?partno=GRM155R61H104KE14%23"
			(at 0 0 180)
			(layer "F.Fab")
			(hide yes)
			(effects
				(font
					(size 1.27 1.27)
					(thickness 0.15)
				)
			)
		)
		(property "Author" "Antmicro"
			(at 255.751002 330.602 0)
			(layer "B.Fab")
			(hide yes)
			(effects
				(font
					(size 1 1)
					(thickness 0.15)
				)
				(justify mirror)
			)
		)
		(property "Dielectric" "X5R"
			(at 255.751002 330.602 0)
			(layer "B.Fab")
			(hide yes)
			(effects
				(font
					(size 1 1)
					(thickness 0.15)
				)
				(justify mirror)
			)
		)
		(property "License" "Apache-2.0"
			(at 255.751002 330.602 0)
			(layer "B.Fab")
			(hide yes)
			(effects
				(font
					(size 1 1)
					(thickness 0.15)
				)
				(justify mirror)
			)
		)
		(property "MPN" "GRM155R61H104KE14D"
			(at 255.751002 330.602 0)
			(layer "B.Fab")
			(hide yes)
			(effects
				(font
					(size 1 1)
					(thickness 0.15)
				)
				(justify mirror)
			)
		)
		(property "Manufacturer" "Murata"
			(at 255.751002 330.602 0)
			(layer "B.Fab")
			(hide yes)
			(effects
				(font
					(size 1 1)
					(thickness 0.15)
				)
				(justify mirror)
			)
		)
		(property "Val" "100n"
			(at 255.751002 330.602 0)
			(layer "B.Fab")
			(hide yes)
			(effects
				(font
					(size 1 1)
					(thickness 0.15)
				)
				(justify mirror)
			)
		)
		(property "Voltage" "50V"
			(at 255.751002 330.602 0)
			(layer "B.Fab")
			(hide yes)
			(effects
				(font
					(size 1 1)
					(thickness 0.15)
				)
				(justify mirror)
			)
		)
		(sheetname "/FPGA power/")
		(sheetfile "fpga-power.kicad_sch")
		(attr smd)
		(fp_rect
			(start -0.9656 0.4572)
			(end 0.9652 -0.4828)
			(stroke
				(width 0.05)
				(type solid)
			)
			(fill no)
			(layer "B.CrtYd")
		)
		(fp_line
			(start 0.498 0.25)
			(end 0.498 -0.248)
			(stroke
				(width 0.15)
				(type solid)
			)
			(layer "B.Fab")
		)
		(fp_line
			(start 0.498 -0.248)
			(end -0.5 -0.248)
			(stroke
				(width 0.15)
				(type solid)
			)
			(layer "B.Fab")
		)
		(fp_line
			(start -0.5 0.25)
			(end 0.498 0.25)
			(stroke
				(width 0.15)
				(type solid)
			)
			(layer "B.Fab")
		)
		(fp_line
			(start -0.5 -0.248)
			(end -0.5 0.25)
			(stroke
				(width 0.15)
				(type solid)
			)
			(layer "B.Fab")
		)
		(pad "1" smd roundrect
			(at -0.5 0 90)
			(size 0.6 0.6)
			(layers "B.Cu" "B.Mask" "B.Paste")
			(roundrect_rratio 0.25)
			(net 1 "GND")
			(pintype "passive")
		)
		(pad "2" smd roundrect
			(at 0.498 0 180)
			(size 0.6 0.6)
			(layers "B.Cu" "B.Mask" "B.Paste")
			(roundrect_rratio 0.25)
			(net 200 "+3V3")
			(pintype "passive")
		)
	)
	(footprint "antmicro-footprints:TP_SMD_1mm"
		(layer "B.Cu")
		(at 200.6 154.3 90)
		(property "Reference" "TP38"
			(at -3.4 -0.2 90)
			(layer "B.SilkS")
			(effects
				(font
					(size 0.7 0.7)
					(thickness 0.15)
				)
				(justify right top mirror)
			)
		)
		(property "Value" "TP_1mm_SMD"
			(at 0 -1.4 90)
			(layer "B.Fab")
			(effects
				(font
					(size 0.7 0.7)
					(thickness 0.15)
				)
				(justify right top mirror)
			)
		)
		(property "MPN" ""
			(at 0 0 270)
			(unlocked yes)
			(layer "B.Fab")
			(hide yes)
			(effects
				(font
					(size 1 1)
					(thickness 0.15)
				)
				(justify mirror)
			)
		)
		(property "Manufacturer" ""
			(at 0 0 270)
			(unlocked yes)
			(layer "B.Fab")
			(hide yes)
			(effects
				(font
					(size 1 1)
					(thickness 0.15)
				)
				(justify mirror)
			)
		)
		(property "Author" "Antmicro"
			(at 0 0 270)
			(unlocked yes)
			(layer "B.Fab")
			(hide yes)
			(effects
				(font
					(size 1 1)
					(thickness 0.15)
				)
				(justify mirror)
			)
		)
		(property "License" "Apache-2.0"
			(at 0 0 270)
			(unlocked yes)
			(layer "B.Fab")
			(hide yes)
			(effects
				(font
					(size 1 1)
					(thickness 0.15)
				)
				(justify mirror)
			)
		)
		(sheetname "/I^{2}C/")
		(sheetfile "i2c.kicad_sch")
		(attr exclude_from_pos_files)
		(fp_circle
			(center 0 0)
			(end 0.6 0)
			(stroke
				(width 0.05)
				(type default)
			)
			(fill no)
			(layer "B.CrtYd")
		)
		(fp_text user "Author: Antmicro"
			(at -0.5 -4 90)
			(layer "B.Fab")
			(effects
				(font
					(size 0.7 0.7)
					(thickness 0.15)
				)
				(justify right top mirror)
			)
		)
		(fp_text user "License: Apache-2.0"
			(at -0.5 -5.2 90)
			(layer "B.Fab")
			(effects
				(font
					(size 0.7 0.7)
					(thickness 0.15)
				)
				(justify right top mirror)
			)
		)
		(fp_text user "${REFERENCE}"
			(at -0.5 -2.8 90)
			(layer "B.Fab")
			(effects
				(font
					(size 0.7 0.7)
					(thickness 0.15)
				)
				(justify right top mirror)
			)
		)
		(pad "1" smd circle
			(at 0 0 90)
			(size 1 1)
			(layers "B.Cu" "B.Mask")
			(net 690 "/I^{2}C/PWR.SDA")
			(pinfunction "1")
			(pintype "passive")
		)
	)
	(footprint "antmicro-footprints:TP_SMD_1mm"
		(layer "B.Cu")
		(at 110 174.13 180)
		(property "Reference" "TP51"
			(at -3.2 -0.47 0)
			(layer "B.SilkS")
			(effects
				(font
					(size 0.7 0.7)
					(thickness 0.15)
				)
				(justify left bottom mirror)
			)
		)
		(property "Value" "TP_1mm_SMD"
			(at 0 -1.4 0)
			(layer "B.Fab")
			(effects
				(font
					(size 0.7 0.7)
					(thickness 0.15)
				)
				(justify left bottom mirror)
			)
		)
		(property "MPN" ""
			(at 0 0 0)
			(unlocked yes)
			(layer "B.Fab")
			(hide yes)
			(effects
				(font
					(size 1 1)
					(thickness 0.15)
				)
				(justify mirror)
			)
		)
		(property "Manufacturer" ""
			(at 0 0 0)
			(unlocked yes)
			(layer "B.Fab")
			(hide yes)
			(effects
				(font
					(size 1 1)
					(thickness 0.15)
				)
				(justify mirror)
			)
		)
		(property "Author" "Antmicro"
			(at 0 0 0)
			(unlocked yes)
			(layer "B.Fab")
			(hide yes)
			(effects
				(font
					(size 1 1)
					(thickness 0.15)
				)
				(justify mirror)
			)
		)
		(property "License" "Apache-2.0"
			(at 0 0 0)
			(unlocked yes)
			(layer "B.Fab")
			(hide yes)
			(effects
				(font
					(size 1 1)
					(thickness 0.15)
				)
				(justify mirror)
			)
		)
		(sheetname "/Debug FTDI/")
		(sheetfile "debug-ftdi.kicad_sch")
		(attr exclude_from_pos_files)
		(fp_circle
			(center 0 0)
			(end 0.6 0)
			(stroke
				(width 0.05)
				(type default)
			)
			(fill no)
			(layer "B.CrtYd")
		)
		(fp_text user "Author: Antmicro"
			(at -0.5 -4 0)
			(layer "B.Fab")
			(effects
				(font
					(size 0.7 0.7)
					(thickness 0.15)
				)
				(justify left bottom mirror)
			)
		)
		(fp_text user "License: Apache-2.0"
			(at -0.5 -5.2 0)
			(layer "B.Fab")
			(effects
				(font
					(size 0.7 0.7)
					(thickness 0.15)
				)
				(justify left bottom mirror)
			)
		)
		(fp_text user "${REFERENCE}"
			(at -0.5 -2.8 0)
			(layer "B.Fab")
			(effects
				(font
					(size 0.7 0.7)
					(thickness 0.15)
				)
				(justify left bottom mirror)
			)
		)
		(pad "1" smd circle
			(at 0 0 180)
			(size 1 1)
			(layers "B.Cu" "B.Mask")
			(net 643 "/Debug FTDI/UART1.RX")
			(pinfunction "1")
			(pintype "passive")
		)
	)
	(footprint "antmicro-footprints:C_0402_1005Metric"
		(layer "B.Cu")
		(at 147.375001 170.8005 -90)
		(descr "Capacitor SMD 0402 (1005 Metric), square (rectangular) end terminal, IPC_7351 nominal, (Body size source: IPC-SM-782 page 76, https://www.pcb-3d.com/wordpress/wp-content/uploads/ipc-sm-782a_amendment_1_and_2.pdf)")
		(tags "capacitor 0402")
		(property "Reference" "C80"
			(at 0 1.17 90)
			(layer "B.SilkS")
			(hide yes)
			(effects
				(font
					(size 0.7 0.7)
					(thickness 0.15)
				)
				(justify left bottom mirror)
			)
		)
		(property "Value" "C_100n_0402"
			(at 0 -1.169 90)
			(layer "B.Fab")
			(effects
				(font
					(size 0.7 0.7)
					(thickness 0.15)
				)
				(justify left bottom mirror)
			)
		)
		(property "Datasheet" "https://www.murata.com/products/productdetail?partno=GRM155R61H104KE14%23"
			(at 0 0 270)
			(layer "F.Fab")
			(hide yes)
			(effects
				(font
					(size 1.27 1.27)
					(thickness 0.15)
				)
			)
		)
		(property "Author" "Antmicro"
			(at -23.425499 318.175501 0)
			(layer "B.Fab")
			(hide yes)
			(effects
				(font
					(size 1 1)
					(thickness 0.15)
				)
				(justify mirror)
			)
		)
		(property "Dielectric" "X5R"
			(at -23.425499 318.175501 0)
			(layer "B.Fab")
			(hide yes)
			(effects
				(font
					(size 1 1)
					(thickness 0.15)
				)
				(justify mirror)
			)
		)
		(property "License" "Apache-2.0"
			(at -23.425499 318.175501 0)
			(layer "B.Fab")
			(hide yes)
			(effects
				(font
					(size 1 1)
					(thickness 0.15)
				)
				(justify mirror)
			)
		)
		(property "MPN" "GRM155R61H104KE14D"
			(at -23.425499 318.175501 0)
			(layer "B.Fab")
			(hide yes)
			(effects
				(font
					(size 1 1)
					(thickness 0.15)
				)
				(justify mirror)
			)
		)
		(property "Manufacturer" "Murata"
			(at -23.425499 318.175501 0)
			(layer "B.Fab")
			(hide yes)
			(effects
				(font
					(size 1 1)
					(thickness 0.15)
				)
				(justify mirror)
			)
		)
		(property "Val" "100n"
			(at -23.425499 318.175501 0)
			(layer "B.Fab")
			(hide yes)
			(effects
				(font
					(size 1 1)
					(thickness 0.15)
				)
				(justify mirror)
			)
		)
		(property "Voltage" "50V"
			(at -23.425499 318.175501 0)
			(layer "B.Fab")
			(hide yes)
			(effects
				(font
					(size 1 1)
					(thickness 0.15)
				)
				(justify mirror)
			)
		)
		(sheetname "/FPGA power/")
		(sheetfile "fpga-power.kicad_sch")
		(attr smd)
		(fp_rect
			(start -0.9656 0.4572)
			(end 0.9652 -0.4828)
			(stroke
				(width 0.05)
				(type solid)
			)
			(fill no)
			(layer "B.CrtYd")
		)
		(fp_line
			(start -0.5 0.25)
			(end 0.498 0.25)
			(stroke
				(width 0.15)
				(type solid)
			)
			(layer "B.Fab")
		)
		(fp_line
			(start 0.498 0.25)
			(end 0.498 -0.248)
			(stroke
				(width 0.15)
				(type solid)
			)
			(layer "B.Fab")
		)
		(fp_line
			(start -0.5 -0.248)
			(end -0.5 0.25)
			(stroke
				(width 0.15)
				(type solid)
			)
			(layer "B.Fab")
		)
		(fp_line
			(start 0.498 -0.248)
			(end -0.5 -0.248)
			(stroke
				(width 0.15)
				(type solid)
			)
			(layer "B.Fab")
		)
		(pad "1" smd roundrect
			(at -0.5 0 180)
			(size 0.6 0.6)
			(layers "B.Cu" "B.Mask" "B.Paste")
			(roundrect_rratio 0.25)
			(net 1 "GND")
			(pintype "passive")
		)
		(pad "2" smd roundrect
			(at 0.498 0 270)
			(size 0.6 0.6)
			(layers "B.Cu" "B.Mask" "B.Paste")
			(roundrect_rratio 0.25)
			(net 200 "+3V3")
			(pintype "passive")
		)
	)
	(footprint "antmicro-footprints:C_0402_1005Metric"
		(layer "B.Cu")
		(at 141.525501 204.850501 90)
		(descr "Capacitor SMD 0402")
		(tags "capacitor SMD 0402")
		(property "Reference" "C231"
			(at 0 0.699 270)
			(layer "B.SilkS")
			(hide yes)
			(effects
				(font
					(size 0.7 0.7)
					(thickness 0.15)
				)
				(justify left bottom mirror)
			)
		)
		(property "Value" "C_100n_0402"
			(at -1.022927 -2.155213 270)
			(layer "B.Fab")
			(effects
				(font
					(size 0.7 0.7)
					(thickness 0.15)
				)
				(justify left bottom mirror)
			)
		)
		(property "Datasheet" "https://www.murata.com/products/productdetail?partno=GRM155R61H104KE14%23"
			(at 0 0 90)
			(layer "F.Fab")
			(hide yes)
			(effects
				(font
					(size 1.27 1.27)
					(thickness 0.15)
				)
			)
		)
		(property "Author" "Antmicro"
			(at 346.376002 63.325 0)
			(layer "B.Fab")
			(hide yes)
			(effects
				(font
					(size 1 1)
					(thickness 0.15)
				)
				(justify mirror)
			)
		)
		(property "Dielectric" "X5R"
			(at 346.376002 63.325 0)
			(layer "B.Fab")
			(hide yes)
			(effects
				(font
					(size 1 1)
					(thickness 0.15)
				)
				(justify mirror)
			)
		)
		(property "License" "Apache-2.0"
			(at 346.376002 63.325 0)
			(layer "B.Fab")
			(hide yes)
			(effects
				(font
					(size 1 1)
					(thickness 0.15)
				)
				(justify mirror)
			)
		)
		(property "MPN" "GRM155R61H104KE14D"
			(at 346.376002 63.325 0)
			(layer "B.Fab")
			(hide yes)
			(effects
				(font
					(size 1 1)
					(thickness 0.15)
				)
				(justify mirror)
			)
		)
		(property "Manufacturer" "Murata"
			(at 346.376002 63.325 0)
			(layer "B.Fab")
			(hide yes)
			(effects
				(font
					(size 1 1)
					(thickness 0.15)
				)
				(justify mirror)
			)
		)
		(property "Val" "100n"
			(at 346.376002 63.325 0)
			(layer "B.Fab")
			(hide yes)
			(effects
				(font
					(size 1 1)
					(thickness 0.15)
				)
				(justify mirror)
			)
		)
		(property "Voltage" "50V"
			(at 346.376002 63.325 0)
			(layer "B.Fab")
			(hide yes)
			(effects
				(font
					(size 1 1)
					(thickness 0.15)
				)
				(justify mirror)
			)
		)
		(sheetname "/FPGA MGT Interface/")
		(sheetfile "fpga-mgt.kicad_sch")
		(attr smd)
		(fp_rect
			(start -0.9659 0.481258)
			(end 0.9649 -0.458742)
			(stroke
				(width 0.05)
				(type solid)
			)
			(fill no)
			(layer "B.CrtYd")
		)
		(fp_line
			(start 0.499 -0.248)
			(end -0.499 -0.248)
			(stroke
				(width 0.15)
				(type solid)
			)
			(layer "B.Fab")
		)
		(fp_line
			(start -0.499 -0.248)
			(end -0.499 0.25)
			(stroke
				(width 0.15)
				(type solid)
			)
			(layer "B.Fab")
		)
		(fp_line
			(start 0.499 0.25)
			(end 0.499 -0.248)
			(stroke
				(width 0.15)
				(type solid)
			)
			(layer "B.Fab")
		)
		(fp_line
			(start -0.499 0.25)
			(end 0.499 0.25)
			(stroke
				(width 0.15)
				(type solid)
			)
			(layer "B.Fab")
		)
		(pad "1" smd roundrect
			(at -0.484 0 90)
			(size 0.59 0.64)
			(layers "B.Cu" "B.Mask" "B.Paste")
			(roundrect_rratio 0.25)
			(net 26 "/FPGA MGT Interface/PCIE.TXD2_N")
			(pintype "passive")
		)
		(pad "2" smd roundrect
			(at 0.484 0 90)
			(size 0.59 0.64)
			(layers "B.Cu" "B.Mask" "B.Paste")
			(roundrect_rratio 0.25)
			(net 27 "/FPGA MGT Interface/GTX_TX1_N")
			(pintype "passive")
		)
	)
	(footprint "antmicro-footprints:R_0402_1005Metric"
		(layer "B.Cu")
		(at 158.500501 175.276 180)
		(descr "Resistor SMD 0402")
		(tags "resistor SMD 0402")
		(property "Reference" "R170"
			(at -1.122484 0.772697 0)
			(layer "B.SilkS")
			(hide yes)
			(effects
				(font
					(size 0.7 0.7)
					(thickness 0.15)
				)
				(justify left bottom mirror)
			)
		)
		(property "Value" "R_10k_0402"
			(at -1.011843 -1.772047 0)
			(layer "B.Fab")
			(effects
				(font
					(size 0.7 0.7)
					(thickness 0.15)
				)
				(justify left bottom mirror)
			)
		)
		(property "Datasheet" "https://www.bourns.com/docs/product-datasheets/cr.pdf"
			(at 0 0 180)
			(layer "F.Fab")
			(hide yes)
			(effects
				(font
					(size 1.27 1.27)
					(thickness 0.15)
				)
			)
		)
		(property "Author" "Antmicro"
			(at 317.001002 350.552 0)
			(layer "B.Fab")
			(hide yes)
			(effects
				(font
					(size 1 1)
					(thickness 0.15)
				)
				(justify mirror)
			)
		)
		(property "License" "Apache-2.0"
			(at 317.001002 350.552 0)
			(layer "B.Fab")
			(hide yes)
			(effects
				(font
					(size 1 1)
					(thickness 0.15)
				)
				(justify mirror)
			)
		)
		(property "MPN" "CR0402-FX-1002GLF"
			(at 317.001002 350.552 0)
			(layer "B.Fab")
			(hide yes)
			(effects
				(font
					(size 1 1)
					(thickness 0.15)
				)
				(justify mirror)
			)
		)
		(property "Manufacturer" "Bourns"
			(at 317.001002 350.552 0)
			(layer "B.Fab")
			(hide yes)
			(effects
				(font
					(size 1 1)
					(thickness 0.15)
				)
				(justify mirror)
			)
		)
		(property "Tolerance" "1%"
			(at 317.001002 350.552 0)
			(layer "B.Fab")
			(hide yes)
			(effects
				(font
					(size 1 1)
					(thickness 0.15)
				)
				(justify mirror)
			)
		)
		(property "Val" "10k"
			(at 317.001002 350.552 0)
			(layer "B.Fab")
			(hide yes)
			(effects
				(font
					(size 1 1)
					(thickness 0.15)
				)
				(justify mirror)
			)
		)
		(sheetname "/Supply/")
		(sheetfile "supply.kicad_sch")
		(attr smd)
		(fp_rect
			(start -0.93 0.47)
			(end 0.93 -0.47)
			(stroke
				(width 0.05)
				(type solid)
			)
			(fill no)
			(layer "B.CrtYd")
		)
		(fp_rect
			(start -0.5 0.25)
			(end 0.5 -0.25)
			(stroke
				(width 0.15)
				(type solid)
			)
			(fill no)
			(layer "B.Fab")
		)
		(pad "1" smd roundrect
			(at -0.485 0 180)
			(size 0.59 0.64)
			(layers "B.Cu" "B.Mask" "B.Paste")
			(roundrect_rratio 0.25)
			(net 332 "Net-(J8-Pin_4)")
			(pintype "passive")
		)
		(pad "2" smd roundrect
			(at 0.485 0 180)
			(size 0.59 0.64)
			(layers "B.Cu" "B.Mask" "B.Paste")
			(roundrect_rratio 0.25)
			(net 201 "+5V")
			(pintype "passive")
		)
	)
	(footprint "antmicro-footprints:C_0402_1005Metric"
		(layer "B.Cu")
		(at 137.375001 179.8025 90)
		(descr "Capacitor SMD 0402 (1005 Metric), square (rectangular) end terminal, IPC_7351 nominal, (Body size source: IPC-SM-782 page 76, https://www.pcb-3d.com/wordpress/wp-content/uploads/ipc-sm-782a_amendment_1_and_2.pdf)")
		(tags "capacitor 0402")
		(property "Reference" "C55"
			(at 0 1.17 270)
			(layer "B.SilkS")
			(hide yes)
			(effects
				(font
					(size 0.7 0.7)
					(thickness 0.15)
				)
				(justify left bottom mirror)
			)
		)
		(property "Value" "C_100n_0402"
			(at 0 -1.169 270)
			(layer "B.Fab")
			(effects
				(font
					(size 0.7 0.7)
					(thickness 0.15)
				)
				(justify left bottom mirror)
			)
		)
		(property "Datasheet" "https://www.murata.com/products/productdetail?partno=GRM155R61H104KE14%23"
			(at 0 0 90)
			(layer "F.Fab")
			(hide yes)
			(effects
				(font
					(size 1.27 1.27)
					(thickness 0.15)
				)
			)
		)
		(property "Author" "Antmicro"
			(at 317.177501 42.427499 0)
			(layer "B.Fab")
			(hide yes)
			(effects
				(font
					(size 1 1)
					(thickness 0.15)
				)
				(justify mirror)
			)
		)
		(property "Dielectric" "X5R"
			(at 317.177501 42.427499 0)
			(layer "B.Fab")
			(hide yes)
			(effects
				(font
					(size 1 1)
					(thickness 0.15)
				)
				(justify mirror)
			)
		)
		(property "License" "Apache-2.0"
			(at 317.177501 42.427499 0)
			(layer "B.Fab")
			(hide yes)
			(effects
				(font
					(size 1 1)
					(thickness 0.15)
				)
				(justify mirror)
			)
		)
		(property "MPN" "GRM155R61H104KE14D"
			(at 317.177501 42.427499 0)
			(layer "B.Fab")
			(hide yes)
			(effects
				(font
					(size 1 1)
					(thickness 0.15)
				)
				(justify mirror)
			)
		)
		(property "Manufacturer" "Murata"
			(at 317.177501 42.427499 0)
			(layer "B.Fab")
			(hide yes)
			(effects
				(font
					(size 1 1)
					(thickness 0.15)
				)
				(justify mirror)
			)
		)
		(property "Val" "100n"
			(at 317.177501 42.427499 0)
			(layer "B.Fab")
			(hide yes)
			(effects
				(font
					(size 1 1)
					(thickness 0.15)
				)
				(justify mirror)
			)
		)
		(property "Voltage" "50V"
			(at 317.177501 42.427499 0)
			(layer "B.Fab")
			(hide yes)
			(effects
				(font
					(size 1 1)
					(thickness 0.15)
				)
				(justify mirror)
			)
		)
		(sheetname "/FPGA power/")
		(sheetfile "fpga-power.kicad_sch")
		(attr smd)
		(fp_rect
			(start -0.9656 0.4572)
			(end 0.9652 -0.4828)
			(stroke
				(width 0.05)
				(type solid)
			)
			(fill no)
			(layer "B.CrtYd")
		)
		(fp_line
			(start 0.498 -0.248)
			(end -0.5 -0.248)
			(stroke
				(width 0.15)
				(type solid)
			)
			(layer "B.Fab")
		)
		(fp_line
			(start -0.5 -0.248)
			(end -0.5 0.25)
			(stroke
				(width 0.15)
				(type solid)
			)
			(layer "B.Fab")
		)
		(fp_line
			(start 0.498 0.25)
			(end 0.498 -0.248)
			(stroke
				(width 0.15)
				(type solid)
			)
			(layer "B.Fab")
		)
		(fp_line
			(start -0.5 0.25)
			(end 0.498 0.25)
			(stroke
				(width 0.15)
				(type solid)
			)
			(layer "B.Fab")
		)
		(pad "1" smd roundrect
			(at -0.5 0)
			(size 0.6 0.6)
			(layers "B.Cu" "B.Mask" "B.Paste")
			(roundrect_rratio 0.25)
			(net 1 "GND")
			(pintype "passive")
		)
		(pad "2" smd roundrect
			(at 0.498 0 90)
			(size 0.6 0.6)
			(layers "B.Cu" "B.Mask" "B.Paste")
			(roundrect_rratio 0.25)
			(net 227 "+1V0")
			(pintype "passive")
		)
	)
	(footprint "antmicro-footprints:R_0402_1005Metric"
		(layer "B.Cu")
		(at 202.875 164.85 90)
		(descr "Resistor SMD 0402")
		(tags "resistor SMD 0402")
		(property "Reference" "R167"
			(at 3.85 0.375 270)
			(layer "B.SilkS")
			(effects
				(font
					(size 0.7 0.7)
					(thickness 0.15)
				)
				(justify left bottom mirror)
			)
		)
		(property "Value" "R_0R_0402"
			(at -1.011843 -1.772047 270)
			(layer "B.Fab")
			(effects
				(font
					(size 0.7 0.7)
					(thickness 0.15)
				)
				(justify left bottom mirror)
			)
		)
		(property "Datasheet" "https://industrial.panasonic.com/cdbs/www-data/pdf/RDA0000/AOA0000C301.pdf"
			(at 0 0 90)
			(layer "F.Fab")
			(hide yes)
			(effects
				(font
					(size 1.27 1.27)
					(thickness 0.15)
				)
			)
		)
		(property "Author" "Antmicro"
			(at 367.725 -38.025 0)
			(layer "B.Fab")
			(hide yes)
			(effects
				(font
					(size 1 1)
					(thickness 0.15)
				)
				(justify mirror)
			)
		)
		(property "Current" "1A"
			(at 367.725 -38.025 0)
			(layer "B.Fab")
			(hide yes)
			(effects
				(font
					(size 1 1)
					(thickness 0.15)
				)
				(justify mirror)
			)
		)
		(property "License" "Apache-2.0"
			(at 367.725 -38.025 0)
			(layer "B.Fab")
			(hide yes)
			(effects
				(font
					(size 1 1)
					(thickness 0.15)
				)
				(justify mirror)
			)
		)
		(property "MPN" "ERJ2GE0R00X"
			(at 367.725 -38.025 0)
			(layer "B.Fab")
			(hide yes)
			(effects
				(font
					(size 1 1)
					(thickness 0.15)
				)
				(justify mirror)
			)
		)
		(property "Manufacturer" "Panasonic"
			(at 367.725 -38.025 0)
			(layer "B.Fab")
			(hide yes)
			(effects
				(font
					(size 1 1)
					(thickness 0.15)
				)
				(justify mirror)
			)
		)
		(property "Tolerance" ""
			(at 367.725 -38.025 0)
			(layer "B.Fab")
			(hide yes)
			(effects
				(font
					(size 1 1)
					(thickness 0.15)
				)
				(justify mirror)
			)
		)
		(property "Val" "0R"
			(at 367.725 -38.025 0)
			(layer "B.Fab")
			(hide yes)
			(effects
				(font
					(size 1 1)
					(thickness 0.15)
				)
				(justify mirror)
			)
		)
		(sheetname "/Supply/")
		(sheetfile "supply.kicad_sch")
		(attr exclude_from_pos_files exclude_from_bom dnp)
		(fp_rect
			(start -0.93 0.47)
			(end 0.93 -0.47)
			(stroke
				(width 0.05)
				(type solid)
			)
			(fill no)
			(layer "B.CrtYd")
		)
		(fp_rect
			(start -0.5 0.25)
			(end 0.5 -0.25)
			(stroke
				(width 0.15)
				(type solid)
			)
			(fill no)
			(layer "B.Fab")
		)
		(pad "1" smd roundrect
			(at -0.485 0 90)
			(size 0.59 0.64)
			(layers "B.Cu" "B.Mask" "B.Paste")
			(roundrect_rratio 0.25)
			(net 1 "GND")
			(pintype "passive")
		)
		(pad "2" smd roundrect
			(at 0.485 0 90)
			(size 0.59 0.64)
			(layers "B.Cu" "B.Mask" "B.Paste")
			(roundrect_rratio 0.25)
			(net 217 "/Supply/FB7")
			(pintype "passive")
		)
	)
	(footprint "antmicro-footprints:R_0402_1005Metric"
		(layer "B.Cu")
		(at 143.4 142.4 90)
		(descr "Resistor SMD 0402")
		(tags "resistor SMD 0402")
		(property "Reference" "R35"
			(at 3 0.3 270)
			(layer "B.SilkS")
			(effects
				(font
					(size 0.7 0.7)
					(thickness 0.15)
				)
				(justify left bottom mirror)
			)
		)
		(property "Value" "R_0R_0402"
			(at -1.011843 -1.772047 270)
			(layer "B.Fab")
			(effects
				(font
					(size 0.7 0.7)
					(thickness 0.15)
				)
				(justify left bottom mirror)
			)
		)
		(property "Datasheet" "https://industrial.panasonic.com/cdbs/www-data/pdf/RDA0000/AOA0000C301.pdf"
			(at 0 0 90)
			(layer "F.Fab")
			(hide yes)
			(effects
				(font
					(size 1.27 1.27)
					(thickness 0.15)
				)
			)
		)
		(property "Author" "Antmicro"
			(at 285.8 -1 0)
			(layer "B.Fab")
			(hide yes)
			(effects
				(font
					(size 1 1)
					(thickness 0.15)
				)
				(justify mirror)
			)
		)
		(property "Current" "1A"
			(at 285.8 -1 0)
			(layer "B.Fab")
			(hide yes)
			(effects
				(font
					(size 1 1)
					(thickness 0.15)
				)
				(justify mirror)
			)
		)
		(property "License" "Apache-2.0"
			(at 285.8 -1 0)
			(layer "B.Fab")
			(hide yes)
			(effects
				(font
					(size 1 1)
					(thickness 0.15)
				)
				(justify mirror)
			)
		)
		(property "MPN" "ERJ2GE0R00X"
			(at 285.8 -1 0)
			(layer "B.Fab")
			(hide yes)
			(effects
				(font
					(size 1 1)
					(thickness 0.15)
				)
				(justify mirror)
			)
		)
		(property "Manufacturer" "Panasonic"
			(at 285.8 -1 0)
			(layer "B.Fab")
			(hide yes)
			(effects
				(font
					(size 1 1)
					(thickness 0.15)
				)
				(justify mirror)
			)
		)
		(property "Tolerance" ""
			(at 285.8 -1 0)
			(layer "B.Fab")
			(hide yes)
			(effects
				(font
					(size 1 1)
					(thickness 0.15)
				)
				(justify mirror)
			)
		)
		(property "Val" "0R"
			(at 285.8 -1 0)
			(layer "B.Fab")
			(hide yes)
			(effects
				(font
					(size 1 1)
					(thickness 0.15)
				)
				(justify mirror)
			)
		)
		(sheetname "/DDR5 SODIMM/")
		(sheetfile "ddr5-sodimm.kicad_sch")
		(attr exclude_from_pos_files exclude_from_bom dnp)
		(fp_rect
			(start -0.93 0.47)
			(end 0.93 -0.47)
			(stroke
				(width 0.05)
				(type solid)
			)
			(fill no)
			(layer "B.CrtYd")
		)
		(fp_rect
			(start -0.5 0.25)
			(end 0.5 -0.25)
			(stroke
				(width 0.15)
				(type solid)
			)
			(fill no)
			(layer "B.Fab")
		)
		(pad "1" smd roundrect
			(at -0.485 0 90)
			(size 0.59 0.64)
			(layers "B.Cu" "B.Mask" "B.Paste")
			(roundrect_rratio 0.25)
			(net 173 "/DDR5 SODIMM/RFU3")
			(pintype "passive")
		)
		(pad "2" smd roundrect
			(at 0.485 0 90)
			(size 0.59 0.64)
			(layers "B.Cu" "B.Mask" "B.Paste")
			(roundrect_rratio 0.25)
			(net 274 "RFU_3")
			(pintype "passive")
		)
	)
	(footprint "antmicro-footprints:C_0603_1608Metric"
		(layer "B.Cu")
		(at 114.275501 176.726 -90)
		(descr "Capacitor SMD 0603")
		(tags "capacitor 0603")
		(property "Reference" "C1"
			(at -1.42757 1.000252 90)
			(layer "B.SilkS")
			(hide yes)
			(effects
				(font
					(size 0.7 0.7)
					(thickness 0.15)
				)
				(justify left bottom mirror)
			)
		)
		(property "Value" "C_47u_0603"
			(at -1.42757 -1.770288 90)
			(layer "B.Fab")
			(effects
				(font
					(size 0.7 0.7)
					(thickness 0.15)
				)
				(justify left bottom mirror)
			)
		)
		(property "Datasheet" "https://www.murata.com/products/productdetail?partno=GRM188R60J476ME15%23"
			(at 0 0 270)
			(layer "F.Fab")
			(hide yes)
			(effects
				(font
					(size 1.27 1.27)
					(thickness 0.15)
				)
			)
		)
		(property "Author" "Antmicro"
			(at -62.450499 291.001501 0)
			(layer "B.Fab")
			(hide yes)
			(effects
				(font
					(size 1 1)
					(thickness 0.15)
				)
				(justify mirror)
			)
		)
		(property "Dielectric" ""
			(at -62.450499 291.001501 0)
			(layer "B.Fab")
			(hide yes)
			(effects
				(font
					(size 1 1)
					(thickness 0.15)
				)
				(justify mirror)
			)
		)
		(property "License" "Apache-2.0"
			(at -62.450499 291.001501 0)
			(layer "B.Fab")
			(hide yes)
			(effects
				(font
					(size 1 1)
					(thickness 0.15)
				)
				(justify mirror)
			)
		)
		(property "MPN" "GRM188R60J476ME15D"
			(at -62.450499 291.001501 0)
			(layer "B.Fab")
			(hide yes)
			(effects
				(font
					(size 1 1)
					(thickness 0.15)
				)
				(justify mirror)
			)
		)
		(property "Manufacturer" "Murata"
			(at -62.450499 291.001501 0)
			(layer "B.Fab")
			(hide yes)
			(effects
				(font
					(size 1 1)
					(thickness 0.15)
				)
				(justify mirror)
			)
		)
		(property "Val" "47u"
			(at -62.450499 291.001501 0)
			(layer "B.Fab")
			(hide yes)
			(effects
				(font
					(size 1 1)
					(thickness 0.15)
				)
				(justify mirror)
			)
		)
		(property "Voltage" ""
			(at -62.450499 291.001501 0)
			(layer "B.Fab")
			(hide yes)
			(effects
				(font
					(size 1 1)
					(thickness 0.15)
				)
				(justify mirror)
			)
		)
		(sheetname "/HyperRAM + QSPI Flash/")
		(sheetfile "hyperram-flash.kicad_sch")
		(attr smd)
		(fp_line
			(start -0.3 0.3)
			(end 0.3 0.3)
			(stroke
				(width 0.15)
				(type solid)
			)
			(layer "B.SilkS")
		)
		(fp_line
			(start -0.3 -0.3)
			(end 0.3 -0.3)
			(stroke
				(width 0.15)
				(type solid)
			)
			(layer "B.SilkS")
		)
		(fp_rect
			(start -1.24 0.7)
			(end 1.24 -0.7)
			(stroke
				(width 0.05)
				(type solid)
			)
			(fill no)
			(layer "B.CrtYd")
		)
		(fp_rect
			(start -0.8 0.4)
			(end 0.8 -0.4)
			(stroke
				(width 0.15)
				(type solid)
			)
			(fill no)
			(layer "B.Fab")
		)
		(pad "1" smd roundrect
			(at -0.7 0 270)
			(size 0.6 0.8)
			(layers "B.Cu" "B.Mask" "B.Paste")
			(roundrect_rratio 0.2)
			(net 200 "+3V3")
			(pintype "passive")
		)
		(pad "2" smd roundrect
			(at 0.7 0 270)
			(size 0.6 0.8)
			(layers "B.Cu" "B.Mask" "B.Paste")
			(roundrect_rratio 0.2)
			(net 1 "GND")
			(pintype "passive")
		)
	)
	(footprint "antmicro-footprints:C_0402_1005Metric"
		(layer "B.Cu")
		(at 140.875001 182.3005 180)
		(descr "Capacitor SMD 0402 (1005 Metric), square (rectangular) end terminal, IPC_7351 nominal, (Body size source: IPC-SM-782 page 76, https://www.pcb-3d.com/wordpress/wp-content/uploads/ipc-sm-782a_amendment_1_and_2.pdf)")
		(tags "capacitor 0402")
		(property "Reference" "C32"
			(at 0 1.17 0)
			(layer "B.SilkS")
			(hide yes)
			(effects
				(font
					(size 0.7 0.7)
					(thickness 0.15)
				)
				(justify left bottom mirror)
			)
		)
		(property "Value" "C_100n_0402"
			(at 0 -1.169 0)
			(layer "B.Fab")
			(effects
				(font
					(size 0.7 0.7)
					(thickness 0.15)
				)
				(justify left bottom mirror)
			)
		)
		(property "Datasheet" "https://www.murata.com/products/productdetail?partno=GRM155R61H104KE14%23"
			(at 0 0 180)
			(layer "F.Fab")
			(hide yes)
			(effects
				(font
					(size 1.27 1.27)
					(thickness 0.15)
				)
			)
		)
		(property "Author" "Antmicro"
			(at 281.750002 364.601 0)
			(layer "B.Fab")
			(hide yes)
			(effects
				(font
					(size 1 1)
					(thickness 0.15)
				)
				(justify mirror)
			)
		)
		(property "Dielectric" "X5R"
			(at 281.750002 364.601 0)
			(layer "B.Fab")
			(hide yes)
			(effects
				(font
					(size 1 1)
					(thickness 0.15)
				)
				(justify mirror)
			)
		)
		(property "License" "Apache-2.0"
			(at 281.750002 364.601 0)
			(layer "B.Fab")
			(hide yes)
			(effects
				(font
					(size 1 1)
					(thickness 0.15)
				)
				(justify mirror)
			)
		)
		(property "MPN" "GRM155R61H104KE14D"
			(at 281.750002 364.601 0)
			(layer "B.Fab")
			(hide yes)
			(effects
				(font
					(size 1 1)
					(thickness 0.15)
				)
				(justify mirror)
			)
		)
		(property "Manufacturer" "Murata"
			(at 281.750002 364.601 0)
			(layer "B.Fab")
			(hide yes)
			(effects
				(font
					(size 1 1)
					(thickness 0.15)
				)
				(justify mirror)
			)
		)
		(property "Val" "100n"
			(at 281.750002 364.601 0)
			(layer "B.Fab")
			(hide yes)
			(effects
				(font
					(size 1 1)
					(thickness 0.15)
				)
				(justify mirror)
			)
		)
		(property "Voltage" "50V"
			(at 281.750002 364.601 0)
			(layer "B.Fab")
			(hide yes)
			(effects
				(font
					(size 1 1)
					(thickness 0.15)
				)
				(justify mirror)
			)
		)
		(sheetname "/FPGA power/")
		(sheetfile "fpga-power.kicad_sch")
		(attr smd)
		(fp_rect
			(start -0.9656 0.4572)
			(end 0.9652 -0.4828)
			(stroke
				(width 0.05)
				(type solid)
			)
			(fill no)
			(layer "B.CrtYd")
		)
		(fp_line
			(start 0.498 0.25)
			(end 0.498 -0.248)
			(stroke
				(width 0.15)
				(type solid)
			)
			(layer "B.Fab")
		)
		(fp_line
			(start 0.498 -0.248)
			(end -0.5 -0.248)
			(stroke
				(width 0.15)
				(type solid)
			)
			(layer "B.Fab")
		)
		(fp_line
			(start -0.5 0.25)
			(end 0.498 0.25)
			(stroke
				(width 0.15)
				(type solid)
			)
			(layer "B.Fab")
		)
		(fp_line
			(start -0.5 -0.248)
			(end -0.5 0.25)
			(stroke
				(width 0.15)
				(type solid)
			)
			(layer "B.Fab")
		)
		(pad "1" smd roundrect
			(at -0.5 0 90)
			(size 0.6 0.6)
			(layers "B.Cu" "B.Mask" "B.Paste")
			(roundrect_rratio 0.25)
			(net 1 "GND")
			(pintype "passive")
		)
		(pad "2" smd roundrect
			(at 0.498 0 180)
			(size 0.6 0.6)
			(layers "B.Cu" "B.Mask" "B.Paste")
			(roundrect_rratio 0.25)
			(net 200 "+3V3")
			(pintype "passive")
		)
	)
	(footprint "antmicro-footprints:R_0402_1005Metric"
		(layer "B.Cu")
		(at 140.67 142.4 -90)
		(descr "Resistor SMD 0402")
		(tags "resistor SMD 0402")
		(property "Reference" "R34"
			(at -3.044968 -0.354606 90)
			(layer "B.SilkS")
			(effects
				(font
					(size 0.7 0.7)
					(thickness 0.15)
				)
				(justify left bottom mirror)
			)
		)
		(property "Value" "R_0R_0402"
			(at -1.011843 -1.772047 90)
			(layer "B.Fab")
			(effects
				(font
					(size 0.7 0.7)
					(thickness 0.15)
				)
				(justify left bottom mirror)
			)
		)
		(property "Datasheet" "https://industrial.panasonic.com/cdbs/www-data/pdf/RDA0000/AOA0000C301.pdf"
			(at 0 0 270)
			(layer "F.Fab")
			(hide yes)
			(effects
				(font
					(size 1.27 1.27)
					(thickness 0.15)
				)
			)
		)
		(property "Author" "Antmicro"
			(at -1.73 283.07 0)
			(layer "B.Fab")
			(hide yes)
			(effects
				(font
					(size 1 1)
					(thickness 0.15)
				)
				(justify mirror)
			)
		)
		(property "Current" "1A"
			(at -1.73 283.07 0)
			(layer "B.Fab")
			(hide yes)
			(effects
				(font
					(size 1 1)
					(thickness 0.15)
				)
				(justify mirror)
			)
		)
		(property "License" "Apache-2.0"
			(at -1.73 283.07 0)
			(layer "B.Fab")
			(hide yes)
			(effects
				(font
					(size 1 1)
					(thickness 0.15)
				)
				(justify mirror)
			)
		)
		(property "MPN" "ERJ2GE0R00X"
			(at -1.73 283.07 0)
			(layer "B.Fab")
			(hide yes)
			(effects
				(font
					(size 1 1)
					(thickness 0.15)
				)
				(justify mirror)
			)
		)
		(property "Manufacturer" "Panasonic"
			(at -1.73 283.07 0)
			(layer "B.Fab")
			(hide yes)
			(effects
				(font
					(size 1 1)
					(thickness 0.15)
				)
				(justify mirror)
			)
		)
		(property "Tolerance" ""
			(at -1.73 283.07 0)
			(layer "B.Fab")
			(hide yes)
			(effects
				(font
					(size 1 1)
					(thickness 0.15)
				)
				(justify mirror)
			)
		)
		(property "Val" "0R"
			(at -1.73 283.07 0)
			(layer "B.Fab")
			(hide yes)
			(effects
				(font
					(size 1 1)
					(thickness 0.15)
				)
				(justify mirror)
			)
		)
		(sheetname "/DDR5 SODIMM/")
		(sheetfile "ddr5-sodimm.kicad_sch")
		(attr exclude_from_pos_files exclude_from_bom dnp)
		(fp_rect
			(start -0.93 0.47)
			(end 0.93 -0.47)
			(stroke
				(width 0.05)
				(type solid)
			)
			(fill no)
			(layer "B.CrtYd")
		)
		(fp_rect
			(start -0.5 0.25)
			(end 0.5 -0.25)
			(stroke
				(width 0.15)
				(type solid)
			)
			(fill no)
			(layer "B.Fab")
		)
		(pad "1" smd roundrect
			(at -0.485 0 270)
			(size 0.59 0.64)
			(layers "B.Cu" "B.Mask" "B.Paste")
			(roundrect_rratio 0.25)
			(net 171 "/DDR5 SODIMM/RFU2")
			(pintype "passive")
		)
		(pad "2" smd roundrect
			(at 0.485 0 270)
			(size 0.59 0.64)
			(layers "B.Cu" "B.Mask" "B.Paste")
			(roundrect_rratio 0.25)
			(net 101 "RFU_2")
			(pintype "passive")
		)
	)
	(footprint "antmicro-footprints:R_0402_1005Metric"
		(layer "B.Cu")
		(at 146.875001 173.3025 180)
		(descr "Resistor SMD 0402 (1005 Metric), square (rectangular) end terminal, IPC_7351 nominal, (Body size source: IPC-SM-782 page 76, https://www.pcb-3d.com/wordpress/wp-content/uploads/ipc-sm-782a_amendment_1_and_2.pdf)")
		(tags "resistor 0402")
		(property "Reference" "R20"
			(at 0 1.17 0)
			(layer "B.SilkS")
			(hide yes)
			(effects
				(font
					(size 0.7 0.7)
					(thickness 0.15)
				)
				(justify left bottom mirror)
			)
		)
		(property "Value" "R_0R_0402"
			(at 0 -1.169 0)
			(layer "B.Fab")
			(effects
				(font
					(size 0.7 0.7)
					(thickness 0.15)
				)
				(justify left bottom mirror)
			)
		)
		(property "Datasheet" "https://industrial.panasonic.com/cdbs/www-data/pdf/RDA0000/AOA0000C301.pdf"
			(at 0 0 180)
			(layer "F.Fab")
			(hide yes)
			(effects
				(font
					(size 1.27 1.27)
					(thickness 0.15)
				)
			)
		)
		(property "Author" "Antmicro"
			(at 293.750002 346.605 0)
			(layer "B.Fab")
			(hide yes)
			(effects
				(font
					(size 1 1)
					(thickness 0.15)
				)
				(justify mirror)
			)
		)
		(property "Current" "1A"
			(at 293.750002 346.605 0)
			(layer "B.Fab")
			(hide yes)
			(effects
				(font
					(size 1 1)
					(thickness 0.15)
				)
				(justify mirror)
			)
		)
		(property "License" "Apache-2.0"
			(at 293.750002 346.605 0)
			(layer "B.Fab")
			(hide yes)
			(effects
				(font
					(size 1 1)
					(thickness 0.15)
				)
				(justify mirror)
			)
		)
		(property "MPN" "ERJ2GE0R00X"
			(at 293.750002 346.605 0)
			(layer "B.Fab")
			(hide yes)
			(effects
				(font
					(size 1 1)
					(thickness 0.15)
				)
				(justify mirror)
			)
		)
		(property "Manufacturer" "Panasonic"
			(at 293.750002 346.605 0)
			(layer "B.Fab")
			(hide yes)
			(effects
				(font
					(size 1 1)
					(thickness 0.15)
				)
				(justify mirror)
			)
		)
		(property "Tolerance" ""
			(at 293.750002 346.605 0)
			(layer "B.Fab")
			(hide yes)
			(effects
				(font
					(size 1 1)
					(thickness 0.15)
				)
				(justify mirror)
			)
		)
		(property "Val" "0R"
			(at 293.750002 346.605 0)
			(layer "B.Fab")
			(hide yes)
			(effects
				(font
					(size 1 1)
					(thickness 0.15)
				)
				(justify mirror)
			)
		)
		(sheetname "/FPGA Config/")
		(sheetfile "fpga-config.kicad_sch")
		(attr smd)
		(fp_line
			(start 0.9652 0.46)
			(end 0.9652 -0.45)
			(stroke
				(width 0.05)
				(type solid)
			)
			(layer "B.CrtYd")
		)
		(fp_line
			(start 0.9652 -0.45)
			(end -0.95 -0.45)
			(stroke
				(width 0.05)
				(type solid)
			)
			(layer "B.CrtYd")
		)
		(fp_line
			(start -0.95 0.46)
			(end 0.9652 0.46)
			(stroke
				(width 0.05)
				(type solid)
			)
			(layer "B.CrtYd")
		)
		(fp_line
			(start -0.95 -0.45)
			(end -0.95 0.46)
			(stroke
				(width 0.05)
				(type solid)
			)
			(layer "B.CrtYd")
		)
		(fp_line
			(start 0.499 0.25)
			(end 0.499 -0.249)
			(stroke
				(width 0.15)
				(type solid)
			)
			(layer "B.Fab")
		)
		(fp_line
			(start 0.499 -0.249)
			(end -0.5 -0.249)
			(stroke
				(width 0.15)
				(type solid)
			)
			(layer "B.Fab")
		)
		(fp_line
			(start -0.5 0.25)
			(end 0.499 0.25)
			(stroke
				(width 0.15)
				(type solid)
			)
			(layer "B.Fab")
		)
		(fp_line
			(start -0.5 -0.249)
			(end -0.5 0.25)
			(stroke
				(width 0.15)
				(type solid)
			)
			(layer "B.Fab")
		)
		(pad "1" smd roundrect
			(at -0.5 0 90)
			(size 0.6 0.6)
			(layers "B.Cu" "B.Mask" "B.Paste")
			(roundrect_rratio 0.25)
			(net 200 "+3V3")
			(pintype "passive")
		)
		(pad "2" smd roundrect
			(at 0.499 0 180)
			(size 0.6 0.6)
			(layers "B.Cu" "B.Mask" "B.Paste")
			(roundrect_rratio 0.25)
			(net 635 "/FPGA Config/CFGBVS")
			(pintype "passive")
		)
	)
	(footprint "antmicro-footprints:R_0402_1005Metric"
		(layer "B.Cu")
		(at 124.75 187.85 -90)
		(descr "Resistor SMD 0402")
		(tags "resistor SMD 0402")
		(property "Reference" "R22"
			(at 0.85 -0.35 90)
			(layer "B.SilkS")
			(effects
				(font
					(size 0.7 0.7)
					(thickness 0.15)
				)
				(justify left bottom mirror)
			)
		)
		(property "Value" "R_100R_0402"
			(at -1.011843 -1.772047 90)
			(layer "B.Fab")
			(effects
				(font
					(size 0.7 0.7)
					(thickness 0.15)
				)
				(justify left bottom mirror)
			)
		)
		(property "Datasheet" "https://www.bourns.com/docs/product-datasheets/cr.pdf"
			(at 0 0 270)
			(layer "F.Fab")
			(hide yes)
			(effects
				(font
					(size 1.27 1.27)
					(thickness 0.15)
				)
			)
		)
		(property "Author" "Antmicro"
			(at -63.1 312.6 0)
			(layer "B.Fab")
			(hide yes)
			(effects
				(font
					(size 1 1)
					(thickness 0.15)
				)
				(justify mirror)
			)
		)
		(property "License" "Apache-2.0"
			(at -63.1 312.6 0)
			(layer "B.Fab")
			(hide yes)
			(effects
				(font
					(size 1 1)
					(thickness 0.15)
				)
				(justify mirror)
			)
		)
		(property "MPN" "CR0402-FX-1000GLF"
			(at -63.1 312.6 0)
			(layer "B.Fab")
			(hide yes)
			(effects
				(font
					(size 1 1)
					(thickness 0.15)
				)
				(justify mirror)
			)
		)
		(property "Manufacturer" "Bourns"
			(at -63.1 312.6 0)
			(layer "B.Fab")
			(hide yes)
			(effects
				(font
					(size 1 1)
					(thickness 0.15)
				)
				(justify mirror)
			)
		)
		(property "Tolerance" "1%"
			(at -63.1 312.6 0)
			(layer "B.Fab")
			(hide yes)
			(effects
				(font
					(size 1 1)
					(thickness 0.15)
				)
				(justify mirror)
			)
		)
		(property "Val" "100R"
			(at -63.1 312.6 0)
			(layer "B.Fab")
			(hide yes)
			(effects
				(font
					(size 1 1)
					(thickness 0.15)
				)
				(justify mirror)
			)
		)
		(sheetname "/FPGA bank 14/")
		(sheetfile "fpga-bank-14.kicad_sch")
		(attr exclude_from_pos_files exclude_from_bom dnp)
		(fp_rect
			(start -0.93 0.47)
			(end 0.93 -0.47)
			(stroke
				(width 0.05)
				(type solid)
			)
			(fill no)
			(layer "B.CrtYd")
		)
		(fp_rect
			(start -0.5 0.25)
			(end 0.5 -0.25)
			(stroke
				(width 0.15)
				(type solid)
			)
			(fill no)
			(layer "B.Fab")
		)
		(pad "1" smd roundrect
			(at -0.485 0 270)
			(size 0.59 0.64)
			(layers "B.Cu" "B.Mask" "B.Paste")
			(roundrect_rratio 0.25)
			(net 612 "/FPGA bank 14/PUDC_B")
			(pintype "passive")
		)
		(pad "2" smd roundrect
			(at 0.485 0 270)
			(size 0.59 0.64)
			(layers "B.Cu" "B.Mask" "B.Paste")
			(roundrect_rratio 0.25)
			(net 1 "GND")
			(pintype "passive")
		)
	)
	(footprint "antmicro-footprints:R_0402_1005Metric"
		(layer "B.Cu")
		(at 153.775001 175.3 180)
		(descr "Resistor SMD 0402")
		(tags "resistor SMD 0402")
		(property "Reference" "R18"
			(at -1.122484 0.772697 0)
			(layer "B.SilkS")
			(hide yes)
			(effects
				(font
					(size 0.7 0.7)
					(thickness 0.15)
				)
				(justify left bottom mirror)
			)
		)
		(property "Value" "R_4k7_0402"
			(at -1.011843 -1.772047 0)
			(layer "B.Fab")
			(effects
				(font
					(size 0.7 0.7)
					(thickness 0.15)
				)
				(justify left bottom mirror)
			)
		)
		(property "Datasheet" "https://www.bourns.com/docs/product-datasheets/cr.pdf"
			(at 0 0 180)
			(layer "F.Fab")
			(hide yes)
			(effects
				(font
					(size 1.27 1.27)
					(thickness 0.15)
				)
			)
		)
		(property "Author" "Antmicro"
			(at 307.550002 350.6 0)
			(layer "B.Fab")
			(hide yes)
			(effects
				(font
					(size 1 1)
					(thickness 0.15)
				)
				(justify mirror)
			)
		)
		(property "License" "Apache-2.0"
			(at 307.550002 350.6 0)
			(layer "B.Fab")
			(hide yes)
			(effects
				(font
					(size 1 1)
					(thickness 0.15)
				)
				(justify mirror)
			)
		)
		(property "MPN" "CR0402-FX-4701GLF"
			(at 307.550002 350.6 0)
			(layer "B.Fab")
			(hide yes)
			(effects
				(font
					(size 1 1)
					(thickness 0.15)
				)
				(justify mirror)
			)
		)
		(property "Manufacturer" "Bourns"
			(at 307.550002 350.6 0)
			(layer "B.Fab")
			(hide yes)
			(effects
				(font
					(size 1 1)
					(thickness 0.15)
				)
				(justify mirror)
			)
		)
		(property "Tolerance" "1%"
			(at 307.550002 350.6 0)
			(layer "B.Fab")
			(hide yes)
			(effects
				(font
					(size 1 1)
					(thickness 0.15)
				)
				(justify mirror)
			)
		)
		(property "Val" "4k7"
			(at 307.550002 350.6 0)
			(layer "B.Fab")
			(hide yes)
			(effects
				(font
					(size 1 1)
					(thickness 0.15)
				)
				(justify mirror)
			)
		)
		(sheetname "/FPGA Config/")
		(sheetfile "fpga-config.kicad_sch")
		(attr smd)
		(fp_rect
			(start -0.93 0.47)
			(end 0.93 -0.47)
			(stroke
				(width 0.05)
				(type solid)
			)
			(fill no)
			(layer "B.CrtYd")
		)
		(fp_rect
			(start -0.5 0.25)
			(end 0.5 -0.25)
			(stroke
				(width 0.15)
				(type solid)
			)
			(fill no)
			(layer "B.Fab")
		)
		(pad "1" smd roundrect
			(at -0.485 0 180)
			(size 0.59 0.64)
			(layers "B.Cu" "B.Mask" "B.Paste")
			(roundrect_rratio 0.25)
			(net 200 "+3V3")
			(pintype "passive")
		)
		(pad "2" smd roundrect
			(at 0.485 0 180)
			(size 0.59 0.64)
			(layers "B.Cu" "B.Mask" "B.Paste")
			(roundrect_rratio 0.25)
			(net 634 "/FPGA Config/PROGRAM_B")
			(pintype "passive")
		)
	)
	(footprint "antmicro-footprints:C_0402_1005Metric"
		(layer "B.Cu")
		(at 144.375501 182.801 -90)
		(descr "Capacitor SMD 0402 (1005 Metric), square (rectangular) end terminal, IPC_7351 nominal, (Body size source: IPC-SM-782 page 76, https://www.pcb-3d.com/wordpress/wp-content/uploads/ipc-sm-782a_amendment_1_and_2.pdf)")
		(tags "capacitor 0402")
		(property "Reference" "C45"
			(at 0 1.17 90)
			(layer "B.SilkS")
			(hide yes)
			(effects
				(font
					(size 0.7 0.7)
					(thickness 0.15)
				)
				(justify left bottom mirror)
			)
		)
		(property "Value" "C_100n_0402"
			(at 0 -1.169 90)
			(layer "B.Fab")
			(effects
				(font
					(size 0.7 0.7)
					(thickness 0.15)
				)
				(justify left bottom mirror)
			)
		)
		(property "Datasheet" "https://www.murata.com/products/productdetail?partno=GRM155R61H104KE14%23"
			(at 0 0 270)
			(layer "F.Fab")
			(hide yes)
			(effects
				(font
					(size 1.27 1.27)
					(thickness 0.15)
				)
			)
		)
		(property "Author" "Antmicro"
			(at -38.425499 327.176501 0)
			(layer "B.Fab")
			(hide yes)
			(effects
				(font
					(size 1 1)
					(thickness 0.15)
				)
				(justify mirror)
			)
		)
		(property "Dielectric" "X5R"
			(at -38.425499 327.176501 0)
			(layer "B.Fab")
			(hide yes)
			(effects
				(font
					(size 1 1)
					(thickness 0.15)
				)
				(justify mirror)
			)
		)
		(property "License" "Apache-2.0"
			(at -38.425499 327.176501 0)
			(layer "B.Fab")
			(hide yes)
			(effects
				(font
					(size 1 1)
					(thickness 0.15)
				)
				(justify mirror)
			)
		)
		(property "MPN" "GRM155R61H104KE14D"
			(at -38.425499 327.176501 0)
			(layer "B.Fab")
			(hide yes)
			(effects
				(font
					(size 1 1)
					(thickness 0.15)
				)
				(justify mirror)
			)
		)
		(property "Manufacturer" "Murata"
			(at -38.425499 327.176501 0)
			(layer "B.Fab")
			(hide yes)
			(effects
				(font
					(size 1 1)
					(thickness 0.15)
				)
				(justify mirror)
			)
		)
		(property "Val" "100n"
			(at -38.425499 327.176501 0)
			(layer "B.Fab")
			(hide yes)
			(effects
				(font
					(size 1 1)
					(thickness 0.15)
				)
				(justify mirror)
			)
		)
		(property "Voltage" "50V"
			(at -38.425499 327.176501 0)
			(layer "B.Fab")
			(hide yes)
			(effects
				(font
					(size 1 1)
					(thickness 0.15)
				)
				(justify mirror)
			)
		)
		(sheetname "/FPGA power/")
		(sheetfile "fpga-power.kicad_sch")
		(attr smd)
		(fp_rect
			(start -0.9656 0.4572)
			(end 0.9652 -0.4828)
			(stroke
				(width 0.05)
				(type solid)
			)
			(fill no)
			(layer "B.CrtYd")
		)
		(fp_line
			(start -0.5 0.25)
			(end 0.498 0.25)
			(stroke
				(width 0.15)
				(type solid)
			)
			(layer "B.Fab")
		)
		(fp_line
			(start 0.498 0.25)
			(end 0.498 -0.248)
			(stroke
				(width 0.15)
				(type solid)
			)
			(layer "B.Fab")
		)
		(fp_line
			(start -0.5 -0.248)
			(end -0.5 0.25)
			(stroke
				(width 0.15)
				(type solid)
			)
			(layer "B.Fab")
		)
		(fp_line
			(start 0.498 -0.248)
			(end -0.5 -0.248)
			(stroke
				(width 0.15)
				(type solid)
			)
			(layer "B.Fab")
		)
		(pad "1" smd roundrect
			(at -0.5 0 180)
			(size 0.6 0.6)
			(layers "B.Cu" "B.Mask" "B.Paste")
			(roundrect_rratio 0.25)
			(net 1 "GND")
			(pintype "passive")
		)
		(pad "2" smd roundrect
			(at 0.498 0 270)
			(size 0.6 0.6)
			(layers "B.Cu" "B.Mask" "B.Paste")
			(roundrect_rratio 0.25)
			(net 200 "+3V3")
			(pintype "passive")
		)
	)
	(footprint "antmicro-footprints:C_0402_1005Metric"
		(layer "B.Cu")
		(at 146.375001 178.8005 90)
		(descr "Capacitor SMD 0402 (1005 Metric), square (rectangular) end terminal, IPC_7351 nominal, (Body size source: IPC-SM-782 page 76, https://www.pcb-3d.com/wordpress/wp-content/uploads/ipc-sm-782a_amendment_1_and_2.pdf)")
		(tags "capacitor 0402")
		(property "Reference" "C76"
			(at 0 1.17 270)
			(layer "B.SilkS")
			(hide yes)
			(effects
				(font
					(size 0.7 0.7)
					(thickness 0.15)
				)
				(justify left bottom mirror)
			)
		)
		(property "Value" "C_100n_0402"
			(at 0 -1.169 270)
			(layer "B.Fab")
			(effects
				(font
					(size 0.7 0.7)
					(thickness 0.15)
				)
				(justify left bottom mirror)
			)
		)
		(property "Datasheet" "https://www.murata.com/products/productdetail?partno=GRM155R61H104KE14%23"
			(at 0 0 90)
			(layer "F.Fab")
			(hide yes)
			(effects
				(font
					(size 1.27 1.27)
					(thickness 0.15)
				)
			)
		)
		(property "Author" "Antmicro"
			(at 325.175501 32.425499 0)
			(layer "B.Fab")
			(hide yes)
			(effects
				(font
					(size 1 1)
					(thickness 0.15)
				)
				(justify mirror)
			)
		)
		(property "Dielectric" "X5R"
			(at 325.175501 32.425499 0)
			(layer "B.Fab")
			(hide yes)
			(effects
				(font
					(size 1 1)
					(thickness 0.15)
				)
				(justify mirror)
			)
		)
		(property "License" "Apache-2.0"
			(at 325.175501 32.425499 0)
			(layer "B.Fab")
			(hide yes)
			(effects
				(font
					(size 1 1)
					(thickness 0.15)
				)
				(justify mirror)
			)
		)
		(property "MPN" "GRM155R61H104KE14D"
			(at 325.175501 32.425499 0)
			(layer "B.Fab")
			(hide yes)
			(effects
				(font
					(size 1 1)
					(thickness 0.15)
				)
				(justify mirror)
			)
		)
		(property "Manufacturer" "Murata"
			(at 325.175501 32.425499 0)
			(layer "B.Fab")
			(hide yes)
			(effects
				(font
					(size 1 1)
					(thickness 0.15)
				)
				(justify mirror)
			)
		)
		(property "Val" "100n"
			(at 325.175501 32.425499 0)
			(layer "B.Fab")
			(hide yes)
			(effects
				(font
					(size 1 1)
					(thickness 0.15)
				)
				(justify mirror)
			)
		)
		(property "Voltage" "50V"
			(at 325.175501 32.425499 0)
			(layer "B.Fab")
			(hide yes)
			(effects
				(font
					(size 1 1)
					(thickness 0.15)
				)
				(justify mirror)
			)
		)
		(sheetname "/FPGA power/")
		(sheetfile "fpga-power.kicad_sch")
		(attr smd)
		(fp_rect
			(start -0.9656 0.4572)
			(end 0.9652 -0.4828)
			(stroke
				(width 0.05)
				(type solid)
			)
			(fill no)
			(layer "B.CrtYd")
		)
		(fp_line
			(start 0.498 -0.248)
			(end -0.5 -0.248)
			(stroke
				(width 0.15)
				(type solid)
			)
			(layer "B.Fab")
		)
		(fp_line
			(start -0.5 -0.248)
			(end -0.5 0.25)
			(stroke
				(width 0.15)
				(type solid)
			)
			(layer "B.Fab")
		)
		(fp_line
			(start 0.498 0.25)
			(end 0.498 -0.248)
			(stroke
				(width 0.15)
				(type solid)
			)
			(layer "B.Fab")
		)
		(fp_line
			(start -0.5 0.25)
			(end 0.498 0.25)
			(stroke
				(width 0.15)
				(type solid)
			)
			(layer "B.Fab")
		)
		(pad "1" smd roundrect
			(at -0.5 0)
			(size 0.6 0.6)
			(layers "B.Cu" "B.Mask" "B.Paste")
			(roundrect_rratio 0.25)
			(net 1 "GND")
			(pintype "passive")
		)
		(pad "2" smd roundrect
			(at 0.498 0 90)
			(size 0.6 0.6)
			(layers "B.Cu" "B.Mask" "B.Paste")
			(roundrect_rratio 0.25)
			(net 200 "+3V3")
			(pintype "passive")
		)
	)
	(footprint "antmicro-footprints:TP_SMD_1mm"
		(layer "B.Cu")
		(at 186.94 160.03 180)
		(property "Reference" "TP33"
			(at 0 0.731898 0)
			(layer "B.SilkS")
			(hide yes)
			(effects
				(font
					(size 0.7 0.7)
					(thickness 0.15)
				)
				(justify left bottom mirror)
			)
		)
		(property "Value" "TP_1mm_SMD"
			(at 0 -1.4 0)
			(layer "B.Fab")
			(effects
				(font
					(size 0.7 0.7)
					(thickness 0.15)
				)
				(justify left bottom mirror)
			)
		)
		(property "MPN" ""
			(at 0 0 0)
			(unlocked yes)
			(layer "B.Fab")
			(hide yes)
			(effects
				(font
					(size 1 1)
					(thickness 0.15)
				)
				(justify mirror)
			)
		)
		(property "Manufacturer" ""
			(at 0 0 0)
			(unlocked yes)
			(layer "B.Fab")
			(hide yes)
			(effects
				(font
					(size 1 1)
					(thickness 0.15)
				)
				(justify mirror)
			)
		)
		(property "Author" "Antmicro"
			(at 0 0 0)
			(unlocked yes)
			(layer "B.Fab")
			(hide yes)
			(effects
				(font
					(size 1 1)
					(thickness 0.15)
				)
				(justify mirror)
			)
		)
		(property "License" "Apache-2.0"
			(at 0 0 0)
			(unlocked yes)
			(layer "B.Fab")
			(hide yes)
			(effects
				(font
					(size 1 1)
					(thickness 0.15)
				)
				(justify mirror)
			)
		)
		(sheetname "/Supply/")
		(sheetfile "supply.kicad_sch")
		(attr exclude_from_pos_files)
		(fp_circle
			(center 0 0)
			(end 0.6 0)
			(stroke
				(width 0.05)
				(type default)
			)
			(fill no)
			(layer "B.CrtYd")
		)
		(fp_text user "${REFERENCE}"
			(at -0.5 -2.8 0)
			(layer "B.Fab")
			(effects
				(font
					(size 0.7 0.7)
					(thickness 0.15)
				)
				(justify left bottom mirror)
			)
		)
		(fp_text user "Author: Antmicro"
			(at -0.5 -4 0)
			(layer "B.Fab")
			(effects
				(font
					(size 0.7 0.7)
					(thickness 0.15)
				)
				(justify left bottom mirror)
			)
		)
		(fp_text user "License: Apache-2.0"
			(at -0.5 -5.2 0)
			(layer "B.Fab")
			(effects
				(font
					(size 0.7 0.7)
					(thickness 0.15)
				)
				(justify left bottom mirror)
			)
		)
		(pad "1" smd circle
			(at 0 0 180)
			(size 1 1)
			(layers "B.Cu" "B.Mask")
			(net 206 "+1V1")
			(pinfunction "1")
			(pintype "passive")
		)
	)
	(footprint "antmicro-footprints:C_0402_1005Metric"
		(layer "B.Cu")
		(at 138.877001 173.3025 180)
		(descr "Capacitor SMD 0402 (1005 Metric), square (rectangular) end terminal, IPC_7351 nominal, (Body size source: IPC-SM-782 page 76, https://www.pcb-3d.com/wordpress/wp-content/uploads/ipc-sm-782a_amendment_1_and_2.pdf)")
		(tags "capacitor 0402")
		(property "Reference" "C75"
			(at 0 1.17 0)
			(layer "B.SilkS")
			(hide yes)
			(effects
				(font
					(size 0.7 0.7)
					(thickness 0.15)
				)
				(justify left bottom mirror)
			)
		)
		(property "Value" "C_100n_0402"
			(at 0 -1.169 0)
			(layer "B.Fab")
			(effects
				(font
					(size 0.7 0.7)
					(thickness 0.15)
				)
				(justify left bottom mirror)
			)
		)
		(property "Datasheet" "https://www.murata.com/products/productdetail?partno=GRM155R61H104KE14%23"
			(at 0 0 180)
			(layer "F.Fab")
			(hide yes)
			(effects
				(font
					(size 1.27 1.27)
					(thickness 0.15)
				)
			)
		)
		(property "Author" "Antmicro"
			(at 277.754002 346.605 0)
			(layer "B.Fab")
			(hide yes)
			(effects
				(font
					(size 1 1)
					(thickness 0.15)
				)
				(justify mirror)
			)
		)
		(property "Dielectric" "X5R"
			(at 277.754002 346.605 0)
			(layer "B.Fab")
			(hide yes)
			(effects
				(font
					(size 1 1)
					(thickness 0.15)
				)
				(justify mirror)
			)
		)
		(property "License" "Apache-2.0"
			(at 277.754002 346.605 0)
			(layer "B.Fab")
			(hide yes)
			(effects
				(font
					(size 1 1)
					(thickness 0.15)
				)
				(justify mirror)
			)
		)
		(property "MPN" "GRM155R61H104KE14D"
			(at 277.754002 346.605 0)
			(layer "B.Fab")
			(hide yes)
			(effects
				(font
					(size 1 1)
					(thickness 0.15)
				)
				(justify mirror)
			)
		)
		(property "Manufacturer" "Murata"
			(at 277.754002 346.605 0)
			(layer "B.Fab")
			(hide yes)
			(effects
				(font
					(size 1 1)
					(thickness 0.15)
				)
				(justify mirror)
			)
		)
		(property "Val" "100n"
			(at 277.754002 346.605 0)
			(layer "B.Fab")
			(hide yes)
			(effects
				(font
					(size 1 1)
					(thickness 0.15)
				)
				(justify mirror)
			)
		)
		(property "Voltage" "50V"
			(at 277.754002 346.605 0)
			(layer "B.Fab")
			(hide yes)
			(effects
				(font
					(size 1 1)
					(thickness 0.15)
				)
				(justify mirror)
			)
		)
		(sheetname "/FPGA power/")
		(sheetfile "fpga-power.kicad_sch")
		(attr smd)
		(fp_rect
			(start -0.9656 0.4572)
			(end 0.9652 -0.4828)
			(stroke
				(width 0.05)
				(type solid)
			)
			(fill no)
			(layer "B.CrtYd")
		)
		(fp_line
			(start 0.498 0.25)
			(end 0.498 -0.248)
			(stroke
				(width 0.15)
				(type solid)
			)
			(layer "B.Fab")
		)
		(fp_line
			(start 0.498 -0.248)
			(end -0.5 -0.248)
			(stroke
				(width 0.15)
				(type solid)
			)
			(layer "B.Fab")
		)
		(fp_line
			(start -0.5 0.25)
			(end 0.498 0.25)
			(stroke
				(width 0.15)
				(type solid)
			)
			(layer "B.Fab")
		)
		(fp_line
			(start -0.5 -0.248)
			(end -0.5 0.25)
			(stroke
				(width 0.15)
				(type solid)
			)
			(layer "B.Fab")
		)
		(pad "1" smd roundrect
			(at -0.5 0 90)
			(size 0.6 0.6)
			(layers "B.Cu" "B.Mask" "B.Paste")
			(roundrect_rratio 0.25)
			(net 1 "GND")
			(pintype "passive")
		)
		(pad "2" smd roundrect
			(at 0.498 0 180)
			(size 0.6 0.6)
			(layers "B.Cu" "B.Mask" "B.Paste")
			(roundrect_rratio 0.25)
			(net 227 "+1V0")
			(pintype "passive")
		)
	)
	(footprint "antmicro-footprints:R_0402_1005Metric"
		(layer "B.Cu")
		(at 123.7 187.85 90)
		(descr "Resistor SMD 0402")
		(tags "resistor SMD 0402")
		(property "Reference" "R21"
			(at -0.85 0.35 270)
			(layer "B.SilkS")
			(effects
				(font
					(size 0.7 0.7)
					(thickness 0.15)
				)
				(justify left bottom mirror)
			)
		)
		(property "Value" "R_100R_0402"
			(at -1.011843 -1.772047 270)
			(layer "B.Fab")
			(effects
				(font
					(size 0.7 0.7)
					(thickness 0.15)
				)
				(justify left bottom mirror)
			)
		)
		(property "Datasheet" "https://www.bourns.com/docs/product-datasheets/cr.pdf"
			(at 0 0 90)
			(layer "F.Fab")
			(hide yes)
			(effects
				(font
					(size 1.27 1.27)
					(thickness 0.15)
				)
			)
		)
		(property "Author" "Antmicro"
			(at 311.55 64.15 0)
			(layer "B.Fab")
			(hide yes)
			(effects
				(font
					(size 1 1)
					(thickness 0.15)
				)
				(justify mirror)
			)
		)
		(property "License" "Apache-2.0"
			(at 311.55 64.15 0)
			(layer "B.Fab")
			(hide yes)
			(effects
				(font
					(size 1 1)
					(thickness 0.15)
				)
				(justify mirror)
			)
		)
		(property "MPN" "CR0402-FX-1000GLF"
			(at 311.55 64.15 0)
			(layer "B.Fab")
			(hide yes)
			(effects
				(font
					(size 1 1)
					(thickness 0.15)
				)
				(justify mirror)
			)
		)
		(property "Manufacturer" "Bourns"
			(at 311.55 64.15 0)
			(layer "B.Fab")
			(hide yes)
			(effects
				(font
					(size 1 1)
					(thickness 0.15)
				)
				(justify mirror)
			)
		)
		(property "Tolerance" "1%"
			(at 311.55 64.15 0)
			(layer "B.Fab")
			(hide yes)
			(effects
				(font
					(size 1 1)
					(thickness 0.15)
				)
				(justify mirror)
			)
		)
		(property "Val" "100R"
			(at 311.55 64.15 0)
			(layer "B.Fab")
			(hide yes)
			(effects
				(font
					(size 1 1)
					(thickness 0.15)
				)
				(justify mirror)
			)
		)
		(sheetname "/FPGA bank 14/")
		(sheetfile "fpga-bank-14.kicad_sch")
		(attr smd)
		(fp_rect
			(start -0.93 0.47)
			(end 0.93 -0.47)
			(stroke
				(width 0.05)
				(type solid)
			)
			(fill no)
			(layer "B.CrtYd")
		)
		(fp_rect
			(start -0.5 0.25)
			(end 0.5 -0.25)
			(stroke
				(width 0.15)
				(type solid)
			)
			(fill no)
			(layer "B.Fab")
		)
		(pad "1" smd roundrect
			(at -0.485 0 90)
			(size 0.59 0.64)
			(layers "B.Cu" "B.Mask" "B.Paste")
			(roundrect_rratio 0.25)
			(net 200 "+3V3")
			(pintype "passive")
		)
		(pad "2" smd roundrect
			(at 0.485 0 90)
			(size 0.59 0.64)
			(layers "B.Cu" "B.Mask" "B.Paste")
			(roundrect_rratio 0.25)
			(net 612 "/FPGA bank 14/PUDC_B")
			(pintype "passive")
		)
	)
	(footprint "antmicro-footprints:TP_SMD_1mm"
		(layer "B.Cu")
		(at 97.5 185.775 180)
		(property "Reference" "TP42"
			(at -3.2 -0.425 0)
			(layer "B.SilkS")
			(effects
				(font
					(size 0.7 0.7)
					(thickness 0.15)
				)
				(justify left bottom mirror)
			)
		)
		(property "Value" "TP_1mm_SMD"
			(at 0 -1.4 0)
			(layer "B.Fab")
			(effects
				(font
					(size 0.7 0.7)
					(thickness 0.15)
				)
				(justify left bottom mirror)
			)
		)
		(property "MPN" ""
			(at 0 0 0)
			(unlocked yes)
			(layer "B.Fab")
			(hide yes)
			(effects
				(font
					(size 1 1)
					(thickness 0.15)
				)
				(justify mirror)
			)
		)
		(property "Manufacturer" ""
			(at 0 0 0)
			(unlocked yes)
			(layer "B.Fab")
			(hide yes)
			(effects
				(font
					(size 1 1)
					(thickness 0.15)
				)
				(justify mirror)
			)
		)
		(property "Author" "Antmicro"
			(at 0 0 0)
			(unlocked yes)
			(layer "B.Fab")
			(hide yes)
			(effects
				(font
					(size 1 1)
					(thickness 0.15)
				)
				(justify mirror)
			)
		)
		(property "License" "Apache-2.0"
			(at 0 0 0)
			(unlocked yes)
			(layer "B.Fab")
			(hide yes)
			(effects
				(font
					(size 1 1)
					(thickness 0.15)
				)
				(justify mirror)
			)
		)
		(sheetname "/Debug FTDI/")
		(sheetfile "debug-ftdi.kicad_sch")
		(attr exclude_from_pos_files)
		(fp_circle
			(center 0 0)
			(end 0.6 0)
			(stroke
				(width 0.05)
				(type default)
			)
			(fill no)
			(layer "B.CrtYd")
		)
		(fp_text user "${REFERENCE}"
			(at -0.5 -2.8 0)
			(layer "B.Fab")
			(effects
				(font
					(size 0.7 0.7)
					(thickness 0.15)
				)
				(justify left bottom mirror)
			)
		)
		(fp_text user "License: Apache-2.0"
			(at -0.5 -5.2 0)
			(layer "B.Fab")
			(effects
				(font
					(size 0.7 0.7)
					(thickness 0.15)
				)
				(justify left bottom mirror)
			)
		)
		(fp_text user "Author: Antmicro"
			(at -0.5 -4 0)
			(layer "B.Fab")
			(effects
				(font
					(size 0.7 0.7)
					(thickness 0.15)
				)
				(justify left bottom mirror)
			)
		)
		(pad "1" smd circle
			(at 0 0 180)
			(size 1 1)
			(layers "B.Cu" "B.Mask")
			(net 45 "/Debug FTDI/JTAG.TMS")
			(pinfunction "1")
			(pintype "passive")
		)
	)
	(footprint "antmicro-footprints:TP_SMD_1mm"
		(layer "B.Cu")
		(at 186.5 137 180)
		(property "Reference" "TP25"
			(at 0 0.731898 0)
			(layer "B.SilkS")
			(hide yes)
			(effects
				(font
					(size 0.7 0.7)
					(thickness 0.15)
				)
				(justify left bottom mirror)
			)
		)
		(property "Value" "TP_1mm_SMD"
			(at 0 -1.4 0)
			(layer "B.Fab")
			(effects
				(font
					(size 0.7 0.7)
					(thickness 0.15)
				)
				(justify left bottom mirror)
			)
		)
		(property "MPN" ""
			(at 0 0 0)
			(unlocked yes)
			(layer "B.Fab")
			(hide yes)
			(effects
				(font
					(size 1 1)
					(thickness 0.15)
				)
				(justify mirror)
			)
		)
		(property "Manufacturer" ""
			(at 0 0 0)
			(unlocked yes)
			(layer "B.Fab")
			(hide yes)
			(effects
				(font
					(size 1 1)
					(thickness 0.15)
				)
				(justify mirror)
			)
		)
		(property "Author" "Antmicro"
			(at 0 0 0)
			(unlocked yes)
			(layer "B.Fab")
			(hide yes)
			(effects
				(font
					(size 1 1)
					(thickness 0.15)
				)
				(justify mirror)
			)
		)
		(property "License" "Apache-2.0"
			(at 0 0 0)
			(unlocked yes)
			(layer "B.Fab")
			(hide yes)
			(effects
				(font
					(size 1 1)
					(thickness 0.15)
				)
				(justify mirror)
			)
		)
		(sheetname "/Supply/")
		(sheetfile "supply.kicad_sch")
		(attr exclude_from_pos_files)
		(fp_circle
			(center 0 0)
			(end 0.6 0)
			(stroke
				(width 0.05)
				(type default)
			)
			(fill no)
			(layer "B.CrtYd")
		)
		(fp_text user "${REFERENCE}"
			(at -0.5 -2.8 0)
			(layer "B.Fab")
			(effects
				(font
					(size 0.7 0.7)
					(thickness 0.15)
				)
				(justify left bottom mirror)
			)
		)
		(fp_text user "License: Apache-2.0"
			(at -0.5 -5.2 0)
			(layer "B.Fab")
			(effects
				(font
					(size 0.7 0.7)
					(thickness 0.15)
				)
				(justify left bottom mirror)
			)
		)
		(fp_text user "Author: Antmicro"
			(at -0.5 -4 0)
			(layer "B.Fab")
			(effects
				(font
					(size 0.7 0.7)
					(thickness 0.15)
				)
				(justify left bottom mirror)
			)
		)
		(pad "1" smd circle
			(at 0 0 180)
			(size 1 1)
			(layers "B.Cu" "B.Mask")
			(net 38 "VDC")
			(pinfunction "1")
			(pintype "passive")
		)
	)
	(footprint "antmicro-footprints:TP_SMD_1mm"
		(layer "B.Cu")
		(at 97.5 188.275 180)
		(property "Reference" "TP43"
			(at -3.3 -0.425 0)
			(layer "B.SilkS")
			(effects
				(font
					(size 0.7 0.7)
					(thickness 0.15)
				)
				(justify left bottom mirror)
			)
		)
		(property "Value" "TP_1mm_SMD"
			(at 0 -1.4 0)
			(layer "B.Fab")
			(effects
				(font
					(size 0.7 0.7)
					(thickness 0.15)
				)
				(justify left bottom mirror)
			)
		)
		(property "MPN" ""
			(at 0 0 0)
			(unlocked yes)
			(layer "B.Fab")
			(hide yes)
			(effects
				(font
					(size 1 1)
					(thickness 0.15)
				)
				(justify mirror)
			)
		)
		(property "Manufacturer" ""
			(at 0 0 0)
			(unlocked yes)
			(layer "B.Fab")
			(hide yes)
			(effects
				(font
					(size 1 1)
					(thickness 0.15)
				)
				(justify mirror)
			)
		)
		(property "Author" "Antmicro"
			(at 0 0 0)
			(unlocked yes)
			(layer "B.Fab")
			(hide yes)
			(effects
				(font
					(size 1 1)
					(thickness 0.15)
				)
				(justify mirror)
			)
		)
		(property "License" "Apache-2.0"
			(at 0 0 0)
			(unlocked yes)
			(layer "B.Fab")
			(hide yes)
			(effects
				(font
					(size 1 1)
					(thickness 0.15)
				)
				(justify mirror)
			)
		)
		(sheetname "/Debug FTDI/")
		(sheetfile "debug-ftdi.kicad_sch")
		(attr exclude_from_pos_files)
		(fp_circle
			(center 0 0)
			(end 0.6 0)
			(stroke
				(width 0.05)
				(type default)
			)
			(fill no)
			(layer "B.CrtYd")
		)
		(fp_text user "${REFERENCE}"
			(at -0.5 -2.8 0)
			(layer "B.Fab")
			(effects
				(font
					(size 0.7 0.7)
					(thickness 0.15)
				)
				(justify left bottom mirror)
			)
		)
		(fp_text user "License: Apache-2.0"
			(at -0.5 -5.2 0)
			(layer "B.Fab")
			(effects
				(font
					(size 0.7 0.7)
					(thickness 0.15)
				)
				(justify left bottom mirror)
			)
		)
		(fp_text user "Author: Antmicro"
			(at -0.5 -4 0)
			(layer "B.Fab")
			(effects
				(font
					(size 0.7 0.7)
					(thickness 0.15)
				)
				(justify left bottom mirror)
			)
		)
		(pad "1" smd circle
			(at 0 0 180)
			(size 1 1)
			(layers "B.Cu" "B.Mask")
			(net 46 "/Debug FTDI/JTAG.TCK")
			(pinfunction "1")
			(pintype "passive")
		)
	)
	(footprint "antmicro-footprints:R_0402_1005Metric"
		(layer "B.Cu")
		(at 114.800501 181.249999)
		(descr "Resistor SMD 0402")
		(tags "resistor SMD 0402")
		(property "Reference" "R10"
			(at 1.099499 -0.649999 180)
			(layer "B.SilkS")
			(effects
				(font
					(size 0.7 0.7)
					(thickness 0.15)
				)
				(justify left bottom mirror)
			)
		)
		(property "Value" "R_100R_0402"
			(at -1.011843 -1.772047 180)
			(layer "B.Fab")
			(effects
				(font
					(size 0.7 0.7)
					(thickness 0.15)
				)
				(justify left bottom mirror)
			)
		)
		(property "Datasheet" "https://www.bourns.com/docs/product-datasheets/cr.pdf"
			(at 0 0 0)
			(layer "F.Fab")
			(hide yes)
			(effects
				(font
					(size 1.27 1.27)
					(thickness 0.15)
				)
			)
		)
		(property "Author" "Antmicro"
			(at 0 0 0)
			(layer "B.Fab")
			(hide yes)
			(effects
				(font
					(size 1 1)
					(thickness 0.15)
				)
				(justify mirror)
			)
		)
		(property "License" "Apache-2.0"
			(at 0 0 0)
			(layer "B.Fab")
			(hide yes)
			(effects
				(font
					(size 1 1)
					(thickness 0.15)
				)
				(justify mirror)
			)
		)
		(property "MPN" "CR0402-FX-1000GLF"
			(at 0 0 0)
			(layer "B.Fab")
			(hide yes)
			(effects
				(font
					(size 1 1)
					(thickness 0.15)
				)
				(justify mirror)
			)
		)
		(property "Manufacturer" "Bourns"
			(at 0 0 0)
			(layer "B.Fab")
			(hide yes)
			(effects
				(font
					(size 1 1)
					(thickness 0.15)
				)
				(justify mirror)
			)
		)
		(property "Tolerance" "1%"
			(at 0 0 0)
			(layer "B.Fab")
			(hide yes)
			(effects
				(font
					(size 1 1)
					(thickness 0.15)
				)
				(justify mirror)
			)
		)
		(property "Val" "100R"
			(at 0 0 0)
			(layer "B.Fab")
			(hide yes)
			(effects
				(font
					(size 1 1)
					(thickness 0.15)
				)
				(justify mirror)
			)
		)
		(sheetname "/HyperRAM + QSPI Flash/")
		(sheetfile "hyperram-flash.kicad_sch")
		(attr exclude_from_pos_files exclude_from_bom dnp)
		(fp_rect
			(start -0.93 0.47)
			(end 0.93 -0.47)
			(stroke
				(width 0.05)
				(type solid)
			)
			(fill no)
			(layer "B.CrtYd")
		)
		(fp_rect
			(start -0.5 0.25)
			(end 0.5 -0.25)
			(stroke
				(width 0.15)
				(type solid)
			)
			(fill no)
			(layer "B.Fab")
		)
		(pad "1" smd roundrect
			(at -0.485 0)
			(size 0.59 0.64)
			(layers "B.Cu" "B.Mask" "B.Paste")
			(roundrect_rratio 0.25)
			(net 630 "/FPGA Config/FLASH.SCK")
			(pintype "passive")
		)
		(pad "2" smd roundrect
			(at 0.485 0)
			(size 0.59 0.64)
			(layers "B.Cu" "B.Mask" "B.Paste")
			(roundrect_rratio 0.25)
			(net 1 "GND")
			(pintype "passive")
		)
	)
	(footprint "antmicro-footprints:C_0402_1005Metric"
		(layer "B.Cu")
		(at 129.55 204.775 90)
		(descr "Capacitor SMD 0402")
		(tags "capacitor SMD 0402")
		(property "Reference" "C223"
			(at 0 0.699 270)
			(layer "B.SilkS")
			(hide yes)
			(effects
				(font
					(size 0.7 0.7)
					(thickness 0.15)
				)
				(justify left bottom mirror)
			)
		)
		(property "Value" "C_100n_0402"
			(at -1.022927 -2.155213 270)
			(layer "B.Fab")
			(effects
				(font
					(size 0.7 0.7)
					(thickness 0.15)
				)
				(justify left bottom mirror)
			)
		)
		(property "Datasheet" "https://www.murata.com/products/productdetail?partno=GRM155R61H104KE14%23"
			(at 0 0 90)
			(layer "F.Fab")
			(hide yes)
			(effects
				(font
					(size 1.27 1.27)
					(thickness 0.15)
				)
			)
		)
		(property "Author" "Antmicro"
			(at 334.325 75.225 0)
			(layer "B.Fab")
			(hide yes)
			(effects
				(font
					(size 1 1)
					(thickness 0.15)
				)
				(justify mirror)
			)
		)
		(property "Dielectric" "X5R"
			(at 334.325 75.225 0)
			(layer "B.Fab")
			(hide yes)
			(effects
				(font
					(size 1 1)
					(thickness 0.15)
				)
				(justify mirror)
			)
		)
		(property "License" "Apache-2.0"
			(at 334.325 75.225 0)
			(layer "B.Fab")
			(hide yes)
			(effects
				(font
					(size 1 1)
					(thickness 0.15)
				)
				(justify mirror)
			)
		)
		(property "MPN" "GRM155R61H104KE14D"
			(at 334.325 75.225 0)
			(layer "B.Fab")
			(hide yes)
			(effects
				(font
					(size 1 1)
					(thickness 0.15)
				)
				(justify mirror)
			)
		)
		(property "Manufacturer" "Murata"
			(at 334.325 75.225 0)
			(layer "B.Fab")
			(hide yes)
			(effects
				(font
					(size 1 1)
					(thickness 0.15)
				)
				(justify mirror)
			)
		)
		(property "Val" "100n"
			(at 334.325 75.225 0)
			(layer "B.Fab")
			(hide yes)
			(effects
				(font
					(size 1 1)
					(thickness 0.15)
				)
				(justify mirror)
			)
		)
		(property "Voltage" "50V"
			(at 334.325 75.225 0)
			(layer "B.Fab")
			(hide yes)
			(effects
				(font
					(size 1 1)
					(thickness 0.15)
				)
				(justify mirror)
			)
		)
		(sheetname "/FPGA MGT Interface/")
		(sheetfile "fpga-mgt.kicad_sch")
		(attr smd)
		(fp_rect
			(start -0.9659 0.481258)
			(end 0.9649 -0.458742)
			(stroke
				(width 0.05)
				(type solid)
			)
			(fill no)
			(layer "B.CrtYd")
		)
		(fp_line
			(start 0.499 -0.248)
			(end -0.499 -0.248)
			(stroke
				(width 0.15)
				(type solid)
			)
			(layer "B.Fab")
		)
		(fp_line
			(start -0.499 -0.248)
			(end -0.499 0.25)
			(stroke
				(width 0.15)
				(type solid)
			)
			(layer "B.Fab")
		)
		(fp_line
			(start 0.499 0.25)
			(end 0.499 -0.248)
			(stroke
				(width 0.15)
				(type solid)
			)
			(layer "B.Fab")
		)
		(fp_line
			(start -0.499 0.25)
			(end 0.499 0.25)
			(stroke
				(width 0.15)
				(type solid)
			)
			(layer "B.Fab")
		)
		(pad "1" smd roundrect
			(at -0.484 0 90)
			(size 0.59 0.64)
			(layers "B.Cu" "B.Mask" "B.Paste")
			(roundrect_rratio 0.25)
			(net 14 "/FPGA MGT Interface/PCIE.CLK_N")
			(pintype "passive")
		)
		(pad "2" smd roundrect
			(at 0.484 0 90)
			(size 0.59 0.64)
			(layers "B.Cu" "B.Mask" "B.Paste")
			(roundrect_rratio 0.25)
			(net 15 "/FPGA MGT Interface/GTR_REFCLK0_N")
			(pintype "passive")
		)
	)
	(footprint "antmicro-footprints:R_0402_1005Metric"
		(layer "B.Cu")
		(at 125 202.85)
		(descr "Resistor SMD 0402")
		(tags "resistor SMD 0402")
		(property "Reference" "R191"
			(at -1.1 0.4 180)
			(layer "B.SilkS")
			(effects
				(font
					(size 0.7 0.7)
					(thickness 0.15)
				)
				(justify left bottom mirror)
			)
		)
		(property "Value" "R_10k_0402"
			(at -1.011843 -1.772047 180)
			(layer "B.Fab")
			(effects
				(font
					(size 0.7 0.7)
					(thickness 0.15)
				)
				(justify left bottom mirror)
			)
		)
		(property "Datasheet" "https://www.bourns.com/docs/product-datasheets/cr.pdf"
			(at 0 0 0)
			(layer "F.Fab")
			(hide yes)
			(effects
				(font
					(size 1.27 1.27)
					(thickness 0.15)
				)
			)
		)
		(property "Author" "Antmicro"
			(at 0 0 0)
			(layer "B.Fab")
			(hide yes)
			(effects
				(font
					(size 1 1)
					(thickness 0.15)
				)
				(justify mirror)
			)
		)
		(property "License" "Apache-2.0"
			(at 0 0 0)
			(layer "B.Fab")
			(hide yes)
			(effects
				(font
					(size 1 1)
					(thickness 0.15)
				)
				(justify mirror)
			)
		)
		(property "MPN" "CR0402-FX-1002GLF"
			(at 0 0 0)
			(layer "B.Fab")
			(hide yes)
			(effects
				(font
					(size 1 1)
					(thickness 0.15)
				)
				(justify mirror)
			)
		)
		(property "Manufacturer" "Bourns"
			(at 0 0 0)
			(layer "B.Fab")
			(hide yes)
			(effects
				(font
					(size 1 1)
					(thickness 0.15)
				)
				(justify mirror)
			)
		)
		(property "Tolerance" "1%"
			(at 0 0 0)
			(layer "B.Fab")
			(hide yes)
			(effects
				(font
					(size 1 1)
					(thickness 0.15)
				)
				(justify mirror)
			)
		)
		(property "Val" "10k"
			(at 0 0 0)
			(layer "B.Fab")
			(hide yes)
			(effects
				(font
					(size 1 1)
					(thickness 0.15)
				)
				(justify mirror)
			)
		)
		(sheetname "/PCIe connector/")
		(sheetfile "pcie-connector.kicad_sch")
		(attr exclude_from_pos_files exclude_from_bom dnp)
		(fp_rect
			(start -0.93 0.47)
			(end 0.93 -0.47)
			(stroke
				(width 0.05)
				(type solid)
			)
			(fill no)
			(layer "B.CrtYd")
		)
		(fp_rect
			(start -0.5 0.25)
			(end 0.5 -0.25)
			(stroke
				(width 0.15)
				(type solid)
			)
			(fill no)
			(layer "B.Fab")
		)
		(pad "1" smd roundrect
			(at -0.485 0)
			(size 0.59 0.64)
			(layers "B.Cu" "B.Mask" "B.Paste")
			(roundrect_rratio 0.25)
			(net 135 "PCIE.PWRGD")
			(pintype "passive")
		)
		(pad "2" smd roundrect
			(at 0.485 0)
			(size 0.59 0.64)
			(layers "B.Cu" "B.Mask" "B.Paste")
			(roundrect_rratio 0.25)
			(net 200 "+3V3")
			(pintype "passive")
		)
	)
	(footprint "antmicro-footprints:R_0402_1005Metric"
		(layer "B.Cu")
		(at 135.75 142.4 -90)
		(descr "Resistor SMD 0402")
		(tags "resistor SMD 0402")
		(property "Reference" "R27"
			(at -3.044968 -0.354606 90)
			(layer "B.SilkS")
			(effects
				(font
					(size 0.7 0.7)
					(thickness 0.15)
				)
				(justify left bottom mirror)
			)
		)
		(property "Value" "R_0R_0402"
			(at -1.011843 -1.772047 90)
			(layer "B.Fab")
			(effects
				(font
					(size 0.7 0.7)
					(thickness 0.15)
				)
				(justify left bottom mirror)
			)
		)
		(property "Datasheet" "https://industrial.panasonic.com/cdbs/www-data/pdf/RDA0000/AOA0000C301.pdf"
			(at 0 0 270)
			(layer "F.Fab")
			(hide yes)
			(effects
				(font
					(size 1.27 1.27)
					(thickness 0.15)
				)
			)
		)
		(property "Author" "Antmicro"
			(at -6.65 278.15 0)
			(layer "B.Fab")
			(hide yes)
			(effects
				(font
					(size 1 1)
					(thickness 0.15)
				)
				(justify mirror)
			)
		)
		(property "Current" "1A"
			(at -6.65 278.15 0)
			(layer "B.Fab")
			(hide yes)
			(effects
				(font
					(size 1 1)
					(thickness 0.15)
				)
				(justify mirror)
			)
		)
		(property "License" "Apache-2.0"
			(at -6.65 278.15 0)
			(layer "B.Fab")
			(hide yes)
			(effects
				(font
					(size 1 1)
					(thickness 0.15)
				)
				(justify mirror)
			)
		)
		(property "MPN" "ERJ2GE0R00X"
			(at -6.65 278.15 0)
			(layer "B.Fab")
			(hide yes)
			(effects
				(font
					(size 1 1)
					(thickness 0.15)
				)
				(justify mirror)
			)
		)
		(property "Manufacturer" "Panasonic"
			(at -6.65 278.15 0)
			(layer "B.Fab")
			(hide yes)
			(effects
				(font
					(size 1 1)
					(thickness 0.15)
				)
				(justify mirror)
			)
		)
		(property "Tolerance" ""
			(at -6.65 278.15 0)
			(layer "B.Fab")
			(hide yes)
			(effects
				(font
					(size 1 1)
					(thickness 0.15)
				)
				(justify mirror)
			)
		)
		(property "Val" "0R"
			(at -6.65 278.15 0)
			(layer "B.Fab")
			(hide yes)
			(effects
				(font
					(size 1 1)
					(thickness 0.15)
				)
				(justify mirror)
			)
		)
		(sheetname "/DDR5 SODIMM/")
		(sheetfile "ddr5-sodimm.kicad_sch")
		(attr smd)
		(fp_rect
			(start -0.93 0.47)
			(end 0.93 -0.47)
			(stroke
				(width 0.05)
				(type solid)
			)
			(fill no)
			(layer "B.CrtYd")
		)
		(fp_rect
			(start -0.5 0.25)
			(end 0.5 -0.25)
			(stroke
				(width 0.15)
				(type solid)
			)
			(fill no)
			(layer "B.Fab")
		)
		(pad "1" smd roundrect
			(at -0.485 0 270)
			(size 0.59 0.64)
			(layers "B.Cu" "B.Mask" "B.Paste")
			(roundrect_rratio 0.25)
			(net 140 "/DDR5 SODIMM/VSS_DET1")
			(pintype "passive")
		)
		(pad "2" smd roundrect
			(at 0.485 0 270)
			(size 0.59 0.64)
			(layers "B.Cu" "B.Mask" "B.Paste")
			(roundrect_rratio 0.25)
			(net 248 "~{DDR_PRESENCE}")
			(pintype "passive")
		)
	)
	(footprint "antmicro-footprints:C_0402_1005Metric"
		(layer "B.Cu")
		(at 129.375501 180.801 -90)
		(descr "Capacitor SMD 0402 (1005 Metric), square (rectangular) end terminal, IPC_7351 nominal, (Body size source: IPC-SM-782 page 76, https://www.pcb-3d.com/wordpress/wp-content/uploads/ipc-sm-782a_amendment_1_and_2.pdf)")
		(tags "capacitor 0402")
		(property "Reference" "C30"
			(at 0 1.17 90)
			(layer "B.SilkS")
			(hide yes)
			(effects
				(font
					(size 0.7 0.7)
					(thickness 0.15)
				)
				(justify left bottom mirror)
			)
		)
		(property "Value" "C_100n_0402"
			(at 0 -1.169 90)
			(layer "B.Fab")
			(effects
				(font
					(size 0.7 0.7)
					(thickness 0.15)
				)
				(justify left bottom mirror)
			)
		)
		(property "Datasheet" "https://www.murata.com/products/productdetail?partno=GRM155R61H104KE14%23"
			(at 0 0 270)
			(layer "F.Fab")
			(hide yes)
			(effects
				(font
					(size 1.27 1.27)
					(thickness 0.15)
				)
			)
		)
		(property "Author" "Antmicro"
			(at -51.425499 310.176501 0)
			(layer "B.Fab")
			(hide yes)
			(effects
				(font
					(size 1 1)
					(thickness 0.15)
				)
				(justify mirror)
			)
		)
		(property "Dielectric" "X5R"
			(at -51.425499 310.176501 0)
			(layer "B.Fab")
			(hide yes)
			(effects
				(font
					(size 1 1)
					(thickness 0.15)
				)
				(justify mirror)
			)
		)
		(property "License" "Apache-2.0"
			(at -51.425499 310.176501 0)
			(layer "B.Fab")
			(hide yes)
			(effects
				(font
					(size 1 1)
					(thickness 0.15)
				)
				(justify mirror)
			)
		)
		(property "MPN" "GRM155R61H104KE14D"
			(at -51.425499 310.176501 0)
			(layer "B.Fab")
			(hide yes)
			(effects
				(font
					(size 1 1)
					(thickness 0.15)
				)
				(justify mirror)
			)
		)
		(property "Manufacturer" "Murata"
			(at -51.425499 310.176501 0)
			(layer "B.Fab")
			(hide yes)
			(effects
				(font
					(size 1 1)
					(thickness 0.15)
				)
				(justify mirror)
			)
		)
		(property "Val" "100n"
			(at -51.425499 310.176501 0)
			(layer "B.Fab")
			(hide yes)
			(effects
				(font
					(size 1 1)
					(thickness 0.15)
				)
				(justify mirror)
			)
		)
		(property "Voltage" "50V"
			(at -51.425499 310.176501 0)
			(layer "B.Fab")
			(hide yes)
			(effects
				(font
					(size 1 1)
					(thickness 0.15)
				)
				(justify mirror)
			)
		)
		(sheetname "/FPGA power/")
		(sheetfile "fpga-power.kicad_sch")
		(attr smd)
		(fp_rect
			(start -0.9656 0.4572)
			(end 0.9652 -0.4828)
			(stroke
				(width 0.05)
				(type solid)
			)
			(fill no)
			(layer "B.CrtYd")
		)
		(fp_line
			(start -0.5 0.25)
			(end 0.498 0.25)
			(stroke
				(width 0.15)
				(type solid)
			)
			(layer "B.Fab")
		)
		(fp_line
			(start 0.498 0.25)
			(end 0.498 -0.248)
			(stroke
				(width 0.15)
				(type solid)
			)
			(layer "B.Fab")
		)
		(fp_line
			(start -0.5 -0.248)
			(end -0.5 0.25)
			(stroke
				(width 0.15)
				(type solid)
			)
			(layer "B.Fab")
		)
		(fp_line
			(start 0.498 -0.248)
			(end -0.5 -0.248)
			(stroke
				(width 0.15)
				(type solid)
			)
			(layer "B.Fab")
		)
		(pad "1" smd roundrect
			(at -0.5 0 180)
			(size 0.6 0.6)
			(layers "B.Cu" "B.Mask" "B.Paste")
			(roundrect_rratio 0.25)
			(net 1 "GND")
			(pintype "passive")
		)
		(pad "2" smd roundrect
			(at 0.498 0 270)
			(size 0.6 0.6)
			(layers "B.Cu" "B.Mask" "B.Paste")
			(roundrect_rratio 0.25)
			(net 200 "+3V3")
			(pintype "passive")
		)
	)
	(footprint "antmicro-footprints:C_0402_1005Metric"
		(layer "B.Cu")
		(at 128.375501 171.801 90)
		(descr "Capacitor SMD 0402 (1005 Metric), square (rectangular) end terminal, IPC_7351 nominal, (Body size source: IPC-SM-782 page 76, https://www.pcb-3d.com/wordpress/wp-content/uploads/ipc-sm-782a_amendment_1_and_2.pdf)")
		(tags "capacitor 0402")
		(property "Reference" "C58"
			(at 0 1.17 270)
			(layer "B.SilkS")
			(hide yes)
			(effects
				(font
					(size 0.7 0.7)
					(thickness 0.15)
				)
				(justify left bottom mirror)
			)
		)
		(property "Value" "C_100n_0402"
			(at 0 -1.169 270)
			(layer "B.Fab")
			(effects
				(font
					(size 0.7 0.7)
					(thickness 0.15)
				)
				(justify left bottom mirror)
			)
		)
		(property "Datasheet" "https://www.murata.com/products/productdetail?partno=GRM155R61H104KE14%23"
			(at 0 0 90)
			(layer "F.Fab")
			(hide yes)
			(effects
				(font
					(size 1.27 1.27)
					(thickness 0.15)
				)
			)
		)
		(property "Author" "Antmicro"
			(at 300.176501 43.425499 0)
			(layer "B.Fab")
			(hide yes)
			(effects
				(font
					(size 1 1)
					(thickness 0.15)
				)
				(justify mirror)
			)
		)
		(property "Dielectric" "X5R"
			(at 300.176501 43.425499 0)
			(layer "B.Fab")
			(hide yes)
			(effects
				(font
					(size 1 1)
					(thickness 0.15)
				)
				(justify mirror)
			)
		)
		(property "License" "Apache-2.0"
			(at 300.176501 43.425499 0)
			(layer "B.Fab")
			(hide yes)
			(effects
				(font
					(size 1 1)
					(thickness 0.15)
				)
				(justify mirror)
			)
		)
		(property "MPN" "GRM155R61H104KE14D"
			(at 300.176501 43.425499 0)
			(layer "B.Fab")
			(hide yes)
			(effects
				(font
					(size 1 1)
					(thickness 0.15)
				)
				(justify mirror)
			)
		)
		(property "Manufacturer" "Murata"
			(at 300.176501 43.425499 0)
			(layer "B.Fab")
			(hide yes)
			(effects
				(font
					(size 1 1)
					(thickness 0.15)
				)
				(justify mirror)
			)
		)
		(property "Val" "100n"
			(at 300.176501 43.425499 0)
			(layer "B.Fab")
			(hide yes)
			(effects
				(font
					(size 1 1)
					(thickness 0.15)
				)
				(justify mirror)
			)
		)
		(property "Voltage" "50V"
			(at 300.176501 43.425499 0)
			(layer "B.Fab")
			(hide yes)
			(effects
				(font
					(size 1 1)
					(thickness 0.15)
				)
				(justify mirror)
			)
		)
		(sheetname "/FPGA power/")
		(sheetfile "fpga-power.kicad_sch")
		(attr smd)
		(fp_rect
			(start -0.9656 0.4572)
			(end 0.9652 -0.4828)
			(stroke
				(width 0.05)
				(type solid)
			)
			(fill no)
			(layer "B.CrtYd")
		)
		(fp_line
			(start 0.498 -0.248)
			(end -0.5 -0.248)
			(stroke
				(width 0.15)
				(type solid)
			)
			(layer "B.Fab")
		)
		(fp_line
			(start -0.5 -0.248)
			(end -0.5 0.25)
			(stroke
				(width 0.15)
				(type solid)
			)
			(layer "B.Fab")
		)
		(fp_line
			(start 0.498 0.25)
			(end 0.498 -0.248)
			(stroke
				(width 0.15)
				(type solid)
			)
			(layer "B.Fab")
		)
		(fp_line
			(start -0.5 0.25)
			(end 0.498 0.25)
			(stroke
				(width 0.15)
				(type solid)
			)
			(layer "B.Fab")
		)
		(pad "1" smd roundrect
			(at -0.5 0)
			(size 0.6 0.6)
			(layers "B.Cu" "B.Mask" "B.Paste")
			(roundrect_rratio 0.25)
			(net 1 "GND")
			(pintype "passive")
		)
		(pad "2" smd roundrect
			(at 0.498 0 90)
			(size 0.6 0.6)
			(layers "B.Cu" "B.Mask" "B.Paste")
			(roundrect_rratio 0.25)
			(net 200 "+3V3")
			(pintype "passive")
		)
	)
	(footprint "antmicro-footprints:TP_SMD_1mm"
		(layer "B.Cu")
		(at 191.86 196.94 180)
		(property "Reference" "TP65"
			(at -1.24 -1.57 0)
			(layer "B.SilkS")
			(effects
				(font
					(size 0.7 0.7)
					(thickness 0.15)
				)
				(justify left bottom mirror)
			)
		)
		(property "Value" "TP_1mm_SMD"
			(at 0 -1.4 0)
			(layer "B.Fab")
			(effects
				(font
					(size 0.7 0.7)
					(thickness 0.15)
				)
				(justify left bottom mirror)
			)
		)
		(property "MPN" ""
			(at 0 0 0)
			(unlocked yes)
			(layer "B.Fab")
			(hide yes)
			(effects
				(font
					(size 1 1)
					(thickness 0.15)
				)
				(justify mirror)
			)
		)
		(property "Manufacturer" ""
			(at 0 0 0)
			(unlocked yes)
			(layer "B.Fab")
			(hide yes)
			(effects
				(font
					(size 1 1)
					(thickness 0.15)
				)
				(justify mirror)
			)
		)
		(property "Author" "Antmicro"
			(at 0 0 0)
			(unlocked yes)
			(layer "B.Fab")
			(hide yes)
			(effects
				(font
					(size 1 1)
					(thickness 0.15)
				)
				(justify mirror)
			)
		)
		(property "License" "Apache-2.0"
			(at 0 0 0)
			(unlocked yes)
			(layer "B.Fab")
			(hide yes)
			(effects
				(font
					(size 1 1)
					(thickness 0.15)
				)
				(justify mirror)
			)
		)
		(sheetname "/Supply/")
		(sheetfile "supply.kicad_sch")
		(attr exclude_from_pos_files)
		(fp_circle
			(center 0 0)
			(end 0.6 0)
			(stroke
				(width 0.05)
				(type default)
			)
			(fill no)
			(layer "B.CrtYd")
		)
		(fp_text user "${REFERENCE}"
			(at -0.5 -2.8 0)
			(layer "B.Fab")
			(effects
				(font
					(size 0.7 0.7)
					(thickness 0.15)
				)
				(justify left bottom mirror)
			)
		)
		(fp_text user "Author: Antmicro"
			(at -0.5 -4 0)
			(layer "B.Fab")
			(effects
				(font
					(size 0.7 0.7)
					(thickness 0.15)
				)
				(justify left bottom mirror)
			)
		)
		(fp_text user "License: Apache-2.0"
			(at -0.5 -5.2 0)
			(layer "B.Fab")
			(effects
				(font
					(size 0.7 0.7)
					(thickness 0.15)
				)
				(justify left bottom mirror)
			)
		)
		(pad "1" smd circle
			(at 0 0 180)
			(size 1 1)
			(layers "B.Cu" "B.Mask")
			(net 76 "/Supply/MGTAVTT_OUT")
			(pinfunction "1")
			(pintype "passive")
		)
	)
	(footprint "antmicro-footprints:C_0402_1005Metric"
		(layer "B.Cu")
		(at 131.375501 186.801 -90)
		(descr "Capacitor SMD 0402 (1005 Metric), square (rectangular) end terminal, IPC_7351 nominal, (Body size source: IPC-SM-782 page 76, https://www.pcb-3d.com/wordpress/wp-content/uploads/ipc-sm-782a_amendment_1_and_2.pdf)")
		(tags "capacitor 0402")
		(property "Reference" "C53"
			(at 0 1.17 90)
			(layer "B.SilkS")
			(hide yes)
			(effects
				(font
					(size 0.7 0.7)
					(thickness 0.15)
				)
				(justify left bottom mirror)
			)
		)
		(property "Value" "C_100n_0402"
			(at 0 -1.169 90)
			(layer "B.Fab")
			(effects
				(font
					(size 0.7 0.7)
					(thickness 0.15)
				)
				(justify left bottom mirror)
			)
		)
		(property "Datasheet" "https://www.murata.com/products/productdetail?partno=GRM155R61H104KE14%23"
			(at 0 0 270)
			(layer "F.Fab")
			(hide yes)
			(effects
				(font
					(size 1.27 1.27)
					(thickness 0.15)
				)
			)
		)
		(property "Author" "Antmicro"
			(at -55.425499 318.176501 0)
			(layer "B.Fab")
			(hide yes)
			(effects
				(font
					(size 1 1)
					(thickness 0.15)
				)
				(justify mirror)
			)
		)
		(property "Dielectric" "X5R"
			(at -55.425499 318.176501 0)
			(layer "B.Fab")
			(hide yes)
			(effects
				(font
					(size 1 1)
					(thickness 0.15)
				)
				(justify mirror)
			)
		)
		(property "License" "Apache-2.0"
			(at -55.425499 318.176501 0)
			(layer "B.Fab")
			(hide yes)
			(effects
				(font
					(size 1 1)
					(thickness 0.15)
				)
				(justify mirror)
			)
		)
		(property "MPN" "GRM155R61H104KE14D"
			(at -55.425499 318.176501 0)
			(layer "B.Fab")
			(hide yes)
			(effects
				(font
					(size 1 1)
					(thickness 0.15)
				)
				(justify mirror)
			)
		)
		(property "Manufacturer" "Murata"
			(at -55.425499 318.176501 0)
			(layer "B.Fab")
			(hide yes)
			(effects
				(font
					(size 1 1)
					(thickness 0.15)
				)
				(justify mirror)
			)
		)
		(property "Val" "100n"
			(at -55.425499 318.176501 0)
			(layer "B.Fab")
			(hide yes)
			(effects
				(font
					(size 1 1)
					(thickness 0.15)
				)
				(justify mirror)
			)
		)
		(property "Voltage" "50V"
			(at -55.425499 318.176501 0)
			(layer "B.Fab")
			(hide yes)
			(effects
				(font
					(size 1 1)
					(thickness 0.15)
				)
				(justify mirror)
			)
		)
		(sheetname "/FPGA power/")
		(sheetfile "fpga-power.kicad_sch")
		(attr smd)
		(fp_rect
			(start -0.9656 0.4572)
			(end 0.9652 -0.4828)
			(stroke
				(width 0.05)
				(type solid)
			)
			(fill no)
			(layer "B.CrtYd")
		)
		(fp_line
			(start -0.5 0.25)
			(end 0.498 0.25)
			(stroke
				(width 0.15)
				(type solid)
			)
			(layer "B.Fab")
		)
		(fp_line
			(start 0.498 0.25)
			(end 0.498 -0.248)
			(stroke
				(width 0.15)
				(type solid)
			)
			(layer "B.Fab")
		)
		(fp_line
			(start -0.5 -0.248)
			(end -0.5 0.25)
			(stroke
				(width 0.15)
				(type solid)
			)
			(layer "B.Fab")
		)
		(fp_line
			(start 0.498 -0.248)
			(end -0.5 -0.248)
			(stroke
				(width 0.15)
				(type solid)
			)
			(layer "B.Fab")
		)
		(pad "1" smd roundrect
			(at -0.5 0 180)
			(size 0.6 0.6)
			(layers "B.Cu" "B.Mask" "B.Paste")
			(roundrect_rratio 0.25)
			(net 1 "GND")
			(pintype "passive")
		)
		(pad "2" smd roundrect
			(at 0.498 0 270)
			(size 0.6 0.6)
			(layers "B.Cu" "B.Mask" "B.Paste")
			(roundrect_rratio 0.25)
			(net 200 "+3V3")
			(pintype "passive")
		)
	)
	(footprint "antmicro-footprints:TP_SMD_1mm"
		(layer "B.Cu")
		(at 201.5 161.6 180)
		(property "Reference" "TP62"
			(at -1.4 0.8 0)
			(layer "B.SilkS")
			(effects
				(font
					(size 0.7 0.7)
					(thickness 0.15)
				)
				(justify left bottom mirror)
			)
		)
		(property "Value" "TP_1mm_SMD"
			(at 0 -1.4 0)
			(layer "B.Fab")
			(effects
				(font
					(size 0.7 0.7)
					(thickness 0.15)
				)
				(justify left bottom mirror)
			)
		)
		(property "MPN" ""
			(at 0 0 0)
			(unlocked yes)
			(layer "B.Fab")
			(hide yes)
			(effects
				(font
					(size 1 1)
					(thickness 0.15)
				)
				(justify mirror)
			)
		)
		(property "Manufacturer" ""
			(at 0 0 0)
			(unlocked yes)
			(layer "B.Fab")
			(hide yes)
			(effects
				(font
					(size 1 1)
					(thickness 0.15)
				)
				(justify mirror)
			)
		)
		(property "Author" "Antmicro"
			(at 0 0 0)
			(unlocked yes)
			(layer "B.Fab")
			(hide yes)
			(effects
				(font
					(size 1 1)
					(thickness 0.15)
				)
				(justify mirror)
			)
		)
		(property "License" "Apache-2.0"
			(at 0 0 0)
			(unlocked yes)
			(layer "B.Fab")
			(hide yes)
			(effects
				(font
					(size 1 1)
					(thickness 0.15)
				)
				(justify mirror)
			)
		)
		(sheetname "/Supply/")
		(sheetfile "supply.kicad_sch")
		(attr exclude_from_pos_files)
		(fp_circle
			(center 0 0)
			(end 0.6 0)
			(stroke
				(width 0.05)
				(type default)
			)
			(fill no)
			(layer "B.CrtYd")
		)
		(fp_text user "Author: Antmicro"
			(at -0.5 -4 0)
			(layer "B.Fab")
			(effects
				(font
					(size 0.7 0.7)
					(thickness 0.15)
				)
				(justify left bottom mirror)
			)
		)
		(fp_text user "License: Apache-2.0"
			(at -0.5 -5.2 0)
			(layer "B.Fab")
			(effects
				(font
					(size 0.7 0.7)
					(thickness 0.15)
				)
				(justify left bottom mirror)
			)
		)
		(fp_text user "${REFERENCE}"
			(at -0.5 -2.8 0)
			(layer "B.Fab")
			(effects
				(font
					(size 0.7 0.7)
					(thickness 0.15)
				)
				(justify left bottom mirror)
			)
		)
		(pad "1" smd circle
			(at 0 0 180)
			(size 1 1)
			(layers "B.Cu" "B.Mask")
			(net 53 "/Supply/1V1_local")
			(pinfunction "1")
			(pintype "passive")
		)
	)
	(footprint "antmicro-footprints:C_0402_1005Metric"
		(layer "B.Cu")
		(at 136.877001 172.3025)
		(descr "Capacitor SMD 0402 (1005 Metric), square (rectangular) end terminal, IPC_7351 nominal, (Body size source: IPC-SM-782 page 76, https://www.pcb-3d.com/wordpress/wp-content/uploads/ipc-sm-782a_amendment_1_and_2.pdf)")
		(tags "capacitor 0402")
		(property "Reference" "C19"
			(at 0 1.17 180)
			(layer "B.SilkS")
			(hide yes)
			(effects
				(font
					(size 0.7 0.7)
					(thickness 0.15)
				)
				(justify left bottom mirror)
			)
		)
		(property "Value" "C_100n_0402"
			(at 0 -1.169 180)
			(layer "B.Fab")
			(effects
				(font
					(size 0.7 0.7)
					(thickness 0.15)
				)
				(justify left bottom mirror)
			)
		)
		(property "Datasheet" "https://www.murata.com/products/productdetail?partno=GRM155R61H104KE14%23"
			(at 0 0 0)
			(layer "F.Fab")
			(hide yes)
			(effects
				(font
					(size 1.27 1.27)
					(thickness 0.15)
				)
			)
		)
		(property "Author" "Antmicro"
			(at 0 0 0)
			(layer "B.Fab")
			(hide yes)
			(effects
				(font
					(size 1 1)
					(thickness 0.15)
				)
				(justify mirror)
			)
		)
		(property "Dielectric" "X5R"
			(at 0 0 0)
			(layer "B.Fab")
			(hide yes)
			(effects
				(font
					(size 1 1)
					(thickness 0.15)
				)
				(justify mirror)
			)
		)
		(property "License" "Apache-2.0"
			(at 0 0 0)
			(layer "B.Fab")
			(hide yes)
			(effects
				(font
					(size 1 1)
					(thickness 0.15)
				)
				(justify mirror)
			)
		)
		(property "MPN" "GRM155R61H104KE14D"
			(at 0 0 0)
			(layer "B.Fab")
			(hide yes)
			(effects
				(font
					(size 1 1)
					(thickness 0.15)
				)
				(justify mirror)
			)
		)
		(property "Manufacturer" "Murata"
			(at 0 0 0)
			(layer "B.Fab")
			(hide yes)
			(effects
				(font
					(size 1 1)
					(thickness 0.15)
				)
				(justify mirror)
			)
		)
		(property "Val" "100n"
			(at 0 0 0)
			(layer "B.Fab")
			(hide yes)
			(effects
				(font
					(size 1 1)
					(thickness 0.15)
				)
				(justify mirror)
			)
		)
		(property "Voltage" "50V"
			(at 0 0 0)
			(layer "B.Fab")
			(hide yes)
			(effects
				(font
					(size 1 1)
					(thickness 0.15)
				)
				(justify mirror)
			)
		)
		(sheetname "/FPGA power/")
		(sheetfile "fpga-power.kicad_sch")
		(attr smd)
		(fp_rect
			(start -0.9656 0.4572)
			(end 0.9652 -0.4828)
			(stroke
				(width 0.05)
				(type solid)
			)
			(fill no)
			(layer "B.CrtYd")
		)
		(fp_line
			(start -0.5 -0.248)
			(end -0.5 0.25)
			(stroke
				(width 0.15)
				(type solid)
			)
			(layer "B.Fab")
		)
		(fp_line
			(start -0.5 0.25)
			(end 0.498 0.25)
			(stroke
				(width 0.15)
				(type solid)
			)
			(layer "B.Fab")
		)
		(fp_line
			(start 0.498 -0.248)
			(end -0.5 -0.248)
			(stroke
				(width 0.15)
				(type solid)
			)
			(layer "B.Fab")
		)
		(fp_line
			(start 0.498 0.25)
			(end 0.498 -0.248)
			(stroke
				(width 0.15)
				(type solid)
			)
			(layer "B.Fab")
		)
		(pad "1" smd roundrect
			(at -0.5 0 270)
			(size 0.6 0.6)
			(layers "B.Cu" "B.Mask" "B.Paste")
			(roundrect_rratio 0.25)
			(net 1 "GND")
			(pintype "passive")
		)
		(pad "2" smd roundrect
			(at 0.498 0)
			(size 0.6 0.6)
			(layers "B.Cu" "B.Mask" "B.Paste")
			(roundrect_rratio 0.25)
			(net 227 "+1V0")
			(pintype "passive")
		)
	)
	(footprint "antmicro-footprints:C_0402_1005Metric"
		(layer "B.Cu")
		(at 131.375501 176.801 -90)
		(descr "Capacitor SMD 0402 (1005 Metric), square (rectangular) end terminal, IPC_7351 nominal, (Body size source: IPC-SM-782 page 76, https://www.pcb-3d.com/wordpress/wp-content/uploads/ipc-sm-782a_amendment_1_and_2.pdf)")
		(tags "capacitor 0402")
		(property "Reference" "C23"
			(at 0 1.17 90)
			(layer "B.SilkS")
			(hide yes)
			(effects
				(font
					(size 0.7 0.7)
					(thickness 0.15)
				)
				(justify left bottom mirror)
			)
		)
		(property "Value" "C_100n_0402"
			(at 0 -1.169 90)
			(layer "B.Fab")
			(effects
				(font
					(size 0.7 0.7)
					(thickness 0.15)
				)
				(justify left bottom mirror)
			)
		)
		(property "Datasheet" "https://www.murata.com/products/productdetail?partno=GRM155R61H104KE14%23"
			(at 0 0 270)
			(layer "F.Fab")
			(hide yes)
			(effects
				(font
					(size 1.27 1.27)
					(thickness 0.15)
				)
			)
		)
		(property "Author" "Antmicro"
			(at -45.425499 308.176501 0)
			(layer "B.Fab")
			(hide yes)
			(effects
				(font
					(size 1 1)
					(thickness 0.15)
				)
				(justify mirror)
			)
		)
		(property "Dielectric" "X5R"
			(at -45.425499 308.176501 0)
			(layer "B.Fab")
			(hide yes)
			(effects
				(font
					(size 1 1)
					(thickness 0.15)
				)
				(justify mirror)
			)
		)
		(property "License" "Apache-2.0"
			(at -45.425499 308.176501 0)
			(layer "B.Fab")
			(hide yes)
			(effects
				(font
					(size 1 1)
					(thickness 0.15)
				)
				(justify mirror)
			)
		)
		(property "MPN" "GRM155R61H104KE14D"
			(at -45.425499 308.176501 0)
			(layer "B.Fab")
			(hide yes)
			(effects
				(font
					(size 1 1)
					(thickness 0.15)
				)
				(justify mirror)
			)
		)
		(property "Manufacturer" "Murata"
			(at -45.425499 308.176501 0)
			(layer "B.Fab")
			(hide yes)
			(effects
				(font
					(size 1 1)
					(thickness 0.15)
				)
				(justify mirror)
			)
		)
		(property "Val" "100n"
			(at -45.425499 308.176501 0)
			(layer "B.Fab")
			(hide yes)
			(effects
				(font
					(size 1 1)
					(thickness 0.15)
				)
				(justify mirror)
			)
		)
		(property "Voltage" "50V"
			(at -45.425499 308.176501 0)
			(layer "B.Fab")
			(hide yes)
			(effects
				(font
					(size 1 1)
					(thickness 0.15)
				)
				(justify mirror)
			)
		)
		(sheetname "/FPGA power/")
		(sheetfile "fpga-power.kicad_sch")
		(attr smd)
		(fp_rect
			(start -0.9656 0.4572)
			(end 0.9652 -0.4828)
			(stroke
				(width 0.05)
				(type solid)
			)
			(fill no)
			(layer "B.CrtYd")
		)
		(fp_line
			(start -0.5 0.25)
			(end 0.498 0.25)
			(stroke
				(width 0.15)
				(type solid)
			)
			(layer "B.Fab")
		)
		(fp_line
			(start 0.498 0.25)
			(end 0.498 -0.248)
			(stroke
				(width 0.15)
				(type solid)
			)
			(layer "B.Fab")
		)
		(fp_line
			(start -0.5 -0.248)
			(end -0.5 0.25)
			(stroke
				(width 0.15)
				(type solid)
			)
			(layer "B.Fab")
		)
		(fp_line
			(start 0.498 -0.248)
			(end -0.5 -0.248)
			(stroke
				(width 0.15)
				(type solid)
			)
			(layer "B.Fab")
		)
		(pad "1" smd roundrect
			(at -0.5 0 180)
			(size 0.6 0.6)
			(layers "B.Cu" "B.Mask" "B.Paste")
			(roundrect_rratio 0.25)
			(net 1 "GND")
			(pintype "passive")
		)
		(pad "2" smd roundrect
			(at 0.498 0 270)
			(size 0.6 0.6)
			(layers "B.Cu" "B.Mask" "B.Paste")
			(roundrect_rratio 0.25)
			(net 200 "+3V3")
			(pintype "passive")
		)
	)
	(footprint "antmicro-footprints:C_0402_1005Metric"
		(layer "B.Cu")
		(at 202.95 185.35 -90)
		(descr "Capacitor SMD 0402")
		(tags "capacitor SMD 0402")
		(property "Reference" "C172"
			(at 0 0.699 90)
			(layer "B.SilkS")
			(hide yes)
			(effects
				(font
					(size 0.7 0.7)
					(thickness 0.15)
				)
				(justify left bottom mirror)
			)
		)
		(property "Value" "C_1u_0402"
			(at -1.022927 -2.155213 90)
			(layer "B.Fab")
			(effects
				(font
					(size 0.7 0.7)
					(thickness 0.15)
				)
				(justify left bottom mirror)
			)
		)
		(property "Datasheet" "https://product.tdk.com/en/search/capacitor/ceramic/mlcc/info?part_no=C1005X6S1A105K050BC"
			(at 0 0 270)
			(layer "F.Fab")
			(hide yes)
			(effects
				(font
					(size 1.27 1.27)
					(thickness 0.15)
				)
			)
		)
		(property "Author" "Antmicro"
			(at 17.6 388.3 0)
			(layer "B.Fab")
			(hide yes)
			(effects
				(font
					(size 1 1)
					(thickness 0.15)
				)
				(justify mirror)
			)
		)
		(property "Dielectric" ""
			(at 17.6 388.3 0)
			(layer "B.Fab")
			(hide yes)
			(effects
				(font
					(size 1 1)
					(thickness 0.15)
				)
				(justify mirror)
			)
		)
		(property "License" "Apache-2.0"
			(at 17.6 388.3 0)
			(layer "B.Fab")
			(hide yes)
			(effects
				(font
					(size 1 1)
					(thickness 0.15)
				)
				(justify mirror)
			)
		)
		(property "MPN" "C1005X6S1A105K050BC"
			(at 17.6 388.3 0)
			(layer "B.Fab")
			(hide yes)
			(effects
				(font
					(size 1 1)
					(thickness 0.15)
				)
				(justify mirror)
			)
		)
		(property "Manufacturer" "TDK"
			(at 17.6 388.3 0)
			(layer "B.Fab")
			(hide yes)
			(effects
				(font
					(size 1 1)
					(thickness 0.15)
				)
				(justify mirror)
			)
		)
		(property "Val" "1u"
			(at 17.6 388.3 0)
			(layer "B.Fab")
			(hide yes)
			(effects
				(font
					(size 1 1)
					(thickness 0.15)
				)
				(justify mirror)
			)
		)
		(property "Voltage" ""
			(at 17.6 388.3 0)
			(layer "B.Fab")
			(hide yes)
			(effects
				(font
					(size 1 1)
					(thickness 0.15)
				)
				(justify mirror)
			)
		)
		(sheetname "/Supply/")
		(sheetfile "supply.kicad_sch")
		(attr smd)
		(fp_rect
			(start -0.9659 0.481258)
			(end 0.9649 -0.458742)
			(stroke
				(width 0.05)
				(type solid)
			)
			(fill no)
			(layer "B.CrtYd")
		)
		(fp_line
			(start -0.499 0.25)
			(end 0.499 0.25)
			(stroke
				(width 0.15)
				(type solid)
			)
			(layer "B.Fab")
		)
		(fp_line
			(start 0.499 0.25)
			(end 0.499 -0.248)
			(stroke
				(width 0.15)
				(type solid)
			)
			(layer "B.Fab")
		)
		(fp_line
			(start -0.499 -0.248)
			(end -0.499 0.25)
			(stroke
				(width 0.15)
				(type solid)
			)
			(layer "B.Fab")
		)
		(fp_line
			(start 0.499 -0.248)
			(end -0.499 -0.248)
			(stroke
				(width 0.15)
				(type solid)
			)
			(layer "B.Fab")
		)
		(pad "1" smd roundrect
			(at -0.484 0 270)
			(size 0.59 0.64)
			(layers "B.Cu" "B.Mask" "B.Paste")
			(roundrect_rratio 0.25)
			(net 1 "GND")
			(pintype "passive")
		)
		(pad "2" smd roundrect
			(at 0.484 0 270)
			(size 0.59 0.64)
			(layers "B.Cu" "B.Mask" "B.Paste")
			(roundrect_rratio 0.25)
			(net 39 "/Supply/QDCDC1_VCC")
			(pintype "passive")
		)
	)
	(footprint "antmicro-footprints:C_0402_1005Metric"
		(layer "B.Cu")
		(at 140.525501 204.850501 90)
		(descr "Capacitor SMD 0402")
		(tags "capacitor SMD 0402")
		(property "Reference" "C227"
			(at 0 0.699 270)
			(layer "B.SilkS")
			(hide yes)
			(effects
				(font
					(size 0.7 0.7)
					(thickness 0.15)
				)
				(justify left bottom mirror)
			)
		)
		(property "Value" "C_100n_0402"
			(at -1.022927 -2.155213 270)
			(layer "B.Fab")
			(effects
				(font
					(size 0.7 0.7)
					(thickness 0.15)
				)
				(justify left bottom mirror)
			)
		)
		(property "Datasheet" "https://www.murata.com/products/productdetail?partno=GRM155R61H104KE14%23"
			(at 0 0 90)
			(layer "F.Fab")
			(hide yes)
			(effects
				(font
					(size 1.27 1.27)
					(thickness 0.15)
				)
			)
		)
		(property "Author" "Antmicro"
			(at 345.376002 64.325 0)
			(layer "B.Fab")
			(hide yes)
			(effects
				(font
					(size 1 1)
					(thickness 0.15)
				)
				(justify mirror)
			)
		)
		(property "Dielectric" "X5R"
			(at 345.376002 64.325 0)
			(layer "B.Fab")
			(hide yes)
			(effects
				(font
					(size 1 1)
					(thickness 0.15)
				)
				(justify mirror)
			)
		)
		(property "License" "Apache-2.0"
			(at 345.376002 64.325 0)
			(layer "B.Fab")
			(hide yes)
			(effects
				(font
					(size 1 1)
					(thickness 0.15)
				)
				(justify mirror)
			)
		)
		(property "MPN" "GRM155R61H104KE14D"
			(at 345.376002 64.325 0)
			(layer "B.Fab")
			(hide yes)
			(effects
				(font
					(size 1 1)
					(thickness 0.15)
				)
				(justify mirror)
			)
		)
		(property "Manufacturer" "Murata"
			(at 345.376002 64.325 0)
			(layer "B.Fab")
			(hide yes)
			(effects
				(font
					(size 1 1)
					(thickness 0.15)
				)
				(justify mirror)
			)
		)
		(property "Val" "100n"
			(at 345.376002 64.325 0)
			(layer "B.Fab")
			(hide yes)
			(effects
				(font
					(size 1 1)
					(thickness 0.15)
				)
				(justify mirror)
			)
		)
		(property "Voltage" "50V"
			(at 345.376002 64.325 0)
			(layer "B.Fab")
			(hide yes)
			(effects
				(font
					(size 1 1)
					(thickness 0.15)
				)
				(justify mirror)
			)
		)
		(sheetname "/FPGA MGT Interface/")
		(sheetfile "fpga-mgt.kicad_sch")
		(attr smd)
		(fp_rect
			(start -0.9659 0.481258)
			(end 0.9649 -0.458742)
			(stroke
				(width 0.05)
				(type solid)
			)
			(fill no)
			(layer "B.CrtYd")
		)
		(fp_line
			(start 0.499 -0.248)
			(end -0.499 -0.248)
			(stroke
				(width 0.15)
				(type solid)
			)
			(layer "B.Fab")
		)
		(fp_line
			(start -0.499 -0.248)
			(end -0.499 0.25)
			(stroke
				(width 0.15)
				(type solid)
			)
			(layer "B.Fab")
		)
		(fp_line
			(start 0.499 0.25)
			(end 0.499 -0.248)
			(stroke
				(width 0.15)
				(type solid)
			)
			(layer "B.Fab")
		)
		(fp_line
			(start -0.499 0.25)
			(end 0.499 0.25)
			(stroke
				(width 0.15)
				(type solid)
			)
			(layer "B.Fab")
		)
		(pad "1" smd roundrect
			(at -0.484 0 90)
			(size 0.59 0.64)
			(layers "B.Cu" "B.Mask" "B.Paste")
			(roundrect_rratio 0.25)
			(net 18 "/FPGA MGT Interface/PCIE.TXD2_P")
			(pintype "passive")
		)
		(pad "2" smd roundrect
			(at 0.484 0 90)
			(size 0.59 0.64)
			(layers "B.Cu" "B.Mask" "B.Paste")
			(roundrect_rratio 0.25)
			(net 19 "/FPGA MGT Interface/GTX_TX1_P")
			(pintype "passive")
		)
	)
	(footprint "antmicro-footprints:R_0402_1005Metric"
		(layer "B.Cu")
		(at 196.7 179.4 180)
		(descr "Resistor SMD 0402")
		(tags "resistor SMD 0402")
		(property "Reference" "R154"
			(at -3.8 -0.35 0)
			(layer "B.SilkS")
			(effects
				(font
					(size 0.7 0.7)
					(thickness 0.15)
				)
				(justify left bottom mirror)
			)
		)
		(property "Value" "R_0R_0402"
			(at -1.011843 -1.772047 0)
			(layer "B.Fab")
			(effects
				(font
					(size 0.7 0.7)
					(thickness 0.15)
				)
				(justify left bottom mirror)
			)
		)
		(property "Datasheet" "https://industrial.panasonic.com/cdbs/www-data/pdf/RDA0000/AOA0000C301.pdf"
			(at 0 0 180)
			(layer "F.Fab")
			(hide yes)
			(effects
				(font
					(size 1.27 1.27)
					(thickness 0.15)
				)
			)
		)
		(property "Author" "Antmicro"
			(at 393.4 358.8 0)
			(layer "B.Fab")
			(hide yes)
			(effects
				(font
					(size 1 1)
					(thickness 0.15)
				)
				(justify mirror)
			)
		)
		(property "Current" "1A"
			(at 393.4 358.8 0)
			(layer "B.Fab")
			(hide yes)
			(effects
				(font
					(size 1 1)
					(thickness 0.15)
				)
				(justify mirror)
			)
		)
		(property "License" "Apache-2.0"
			(at 393.4 358.8 0)
			(layer "B.Fab")
			(hide yes)
			(effects
				(font
					(size 1 1)
					(thickness 0.15)
				)
				(justify mirror)
			)
		)
		(property "MPN" "ERJ2GE0R00X"
			(at 393.4 358.8 0)
			(layer "B.Fab")
			(hide yes)
			(effects
				(font
					(size 1 1)
					(thickness 0.15)
				)
				(justify mirror)
			)
		)
		(property "Manufacturer" "Panasonic"
			(at 393.4 358.8 0)
			(layer "B.Fab")
			(hide yes)
			(effects
				(font
					(size 1 1)
					(thickness 0.15)
				)
				(justify mirror)
			)
		)
		(property "Tolerance" ""
			(at 393.4 358.8 0)
			(layer "B.Fab")
			(hide yes)
			(effects
				(font
					(size 1 1)
					(thickness 0.15)
				)
				(justify mirror)
			)
		)
		(property "Val" "0R"
			(at 393.4 358.8 0)
			(layer "B.Fab")
			(hide yes)
			(effects
				(font
					(size 1 1)
					(thickness 0.15)
				)
				(justify mirror)
			)
		)
		(sheetname "/Supply/")
		(sheetfile "supply.kicad_sch")
		(attr exclude_from_pos_files exclude_from_bom dnp)
		(fp_rect
			(start -0.93 0.47)
			(end 0.93 -0.47)
			(stroke
				(width 0.05)
				(type solid)
			)
			(fill no)
			(layer "B.CrtYd")
		)
		(fp_rect
			(start -0.5 0.25)
			(end 0.5 -0.25)
			(stroke
				(width 0.15)
				(type solid)
			)
			(fill no)
			(layer "B.Fab")
		)
		(pad "1" smd roundrect
			(at -0.485 0 180)
			(size 0.59 0.64)
			(layers "B.Cu" "B.Mask" "B.Paste")
			(roundrect_rratio 0.25)
			(net 1 "GND")
			(pintype "passive")
		)
		(pad "2" smd roundrect
			(at 0.485 0 180)
			(size 0.59 0.64)
			(layers "B.Cu" "B.Mask" "B.Paste")
			(roundrect_rratio 0.25)
			(net 211 "/Supply/FB2")
			(pintype "passive")
		)
	)
	(footprint "antmicro-footprints:C_0402_1005Metric"
		(layer "B.Cu")
		(at 142.875001 176.3025)
		(descr "Capacitor SMD 0402 (1005 Metric), square (rectangular) end terminal, IPC_7351 nominal, (Body size source: IPC-SM-782 page 76, https://www.pcb-3d.com/wordpress/wp-content/uploads/ipc-sm-782a_amendment_1_and_2.pdf)")
		(tags "capacitor 0402")
		(property "Reference" "C48"
			(at 0 1.17 180)
			(layer "B.SilkS")
			(hide yes)
			(effects
				(font
					(size 0.7 0.7)
					(thickness 0.15)
				)
				(justify left bottom mirror)
			)
		)
		(property "Value" "C_100n_0402"
			(at 0 -1.169 180)
			(layer "B.Fab")
			(effects
				(font
					(size 0.7 0.7)
					(thickness 0.15)
				)
				(justify left bottom mirror)
			)
		)
		(property "Datasheet" "https://www.murata.com/products/productdetail?partno=GRM155R61H104KE14%23"
			(at 0 0 0)
			(layer "F.Fab")
			(hide yes)
			(effects
				(font
					(size 1.27 1.27)
					(thickness 0.15)
				)
			)
		)
		(property "Author" "Antmicro"
			(at 0 0 0)
			(layer "B.Fab")
			(hide yes)
			(effects
				(font
					(size 1 1)
					(thickness 0.15)
				)
				(justify mirror)
			)
		)
		(property "Dielectric" "X5R"
			(at 0 0 0)
			(layer "B.Fab")
			(hide yes)
			(effects
				(font
					(size 1 1)
					(thickness 0.15)
				)
				(justify mirror)
			)
		)
		(property "License" "Apache-2.0"
			(at 0 0 0)
			(layer "B.Fab")
			(hide yes)
			(effects
				(font
					(size 1 1)
					(thickness 0.15)
				)
				(justify mirror)
			)
		)
		(property "MPN" "GRM155R61H104KE14D"
			(at 0 0 0)
			(layer "B.Fab")
			(hide yes)
			(effects
				(font
					(size 1 1)
					(thickness 0.15)
				)
				(justify mirror)
			)
		)
		(property "Manufacturer" "Murata"
			(at 0 0 0)
			(layer "B.Fab")
			(hide yes)
			(effects
				(font
					(size 1 1)
					(thickness 0.15)
				)
				(justify mirror)
			)
		)
		(property "Val" "100n"
			(at 0 0 0)
			(layer "B.Fab")
			(hide yes)
			(effects
				(font
					(size 1 1)
					(thickness 0.15)
				)
				(justify mirror)
			)
		)
		(property "Voltage" "50V"
			(at 0 0 0)
			(layer "B.Fab")
			(hide yes)
			(effects
				(font
					(size 1 1)
					(thickness 0.15)
				)
				(justify mirror)
			)
		)
		(sheetname "/FPGA power/")
		(sheetfile "fpga-power.kicad_sch")
		(attr smd)
		(fp_rect
			(start -0.9656 0.4572)
			(end 0.9652 -0.4828)
			(stroke
				(width 0.05)
				(type solid)
			)
			(fill no)
			(layer "B.CrtYd")
		)
		(fp_line
			(start -0.5 -0.248)
			(end -0.5 0.25)
			(stroke
				(width 0.15)
				(type solid)
			)
			(layer "B.Fab")
		)
		(fp_line
			(start -0.5 0.25)
			(end 0.498 0.25)
			(stroke
				(width 0.15)
				(type solid)
			)
			(layer "B.Fab")
		)
		(fp_line
			(start 0.498 -0.248)
			(end -0.5 -0.248)
			(stroke
				(width 0.15)
				(type solid)
			)
			(layer "B.Fab")
		)
		(fp_line
			(start 0.498 0.25)
			(end 0.498 -0.248)
			(stroke
				(width 0.15)
				(type solid)
			)
			(layer "B.Fab")
		)
		(pad "1" smd roundrect
			(at -0.5 0 270)
			(size 0.6 0.6)
			(layers "B.Cu" "B.Mask" "B.Paste")
			(roundrect_rratio 0.25)
			(net 1 "GND")
			(pintype "passive")
		)
		(pad "2" smd roundrect
			(at 0.498 0)
			(size 0.6 0.6)
			(layers "B.Cu" "B.Mask" "B.Paste")
			(roundrect_rratio 0.25)
			(net 227 "+1V0")
			(pintype "passive")
		)
	)
	(footprint "antmicro-footprints:C_0402_1005Metric"
		(layer "B.Cu")
		(at 105.96 171.98 90)
		(descr "Capacitor SMD 0402")
		(tags "capacitor SMD 0402")
		(property "Reference" "C236"
			(at 0 0.699 90)
			(layer "B.SilkS")
			(hide yes)
			(effects
				(font
					(size 0.7 0.7)
					(thickness 0.15)
				)
				(justify right bottom mirror)
			)
		)
		(property "Value" "C_100n_0402"
			(at -1.022927 -2.155213 90)
			(layer "B.Fab")
			(effects
				(font
					(size 0.7 0.7)
					(thickness 0.15)
				)
				(justify right bottom mirror)
			)
		)
		(property "Datasheet" "https://www.murata.com/products/productdetail?partno=GRM155R61H104KE14%23"
			(at 0 0 90)
			(layer "F.Fab")
			(hide yes)
			(effects
				(font
					(size 1.27 1.27)
					(thickness 0.15)
				)
			)
		)
		(property "Author" "Antmicro"
			(at 277.94 66.02 0)
			(layer "B.Fab")
			(hide yes)
			(effects
				(font
					(size 1 1)
					(thickness 0.15)
				)
				(justify mirror)
			)
		)
		(property "Dielectric" "X5R"
			(at 277.94 66.02 0)
			(layer "B.Fab")
			(hide yes)
			(effects
				(font
					(size 1 1)
					(thickness 0.15)
				)
				(justify mirror)
			)
		)
		(property "License" "Apache-2.0"
			(at 277.94 66.02 0)
			(layer "B.Fab")
			(hide yes)
			(effects
				(font
					(size 1 1)
					(thickness 0.15)
				)
				(justify mirror)
			)
		)
		(property "MPN" "GRM155R61H104KE14D"
			(at 277.94 66.02 0)
			(layer "B.Fab")
			(hide yes)
			(effects
				(font
					(size 1 1)
					(thickness 0.15)
				)
				(justify mirror)
			)
		)
		(property "Manufacturer" "Murata"
			(at 277.94 66.02 0)
			(layer "B.Fab")
			(hide yes)
			(effects
				(font
					(size 1 1)
					(thickness 0.15)
				)
				(justify mirror)
			)
		)
		(property "Val" "100n"
			(at 277.94 66.02 0)
			(layer "B.Fab")
			(hide yes)
			(effects
				(font
					(size 1 1)
					(thickness 0.15)
				)
				(justify mirror)
			)
		)
		(property "Voltage" "50V"
			(at 277.94 66.02 0)
			(layer "B.Fab")
			(hide yes)
			(effects
				(font
					(size 1 1)
					(thickness 0.15)
				)
				(justify mirror)
			)
		)
		(sheetname "/Debug FTDI/")
		(sheetfile "debug-ftdi.kicad_sch")
		(attr smd)
		(fp_rect
			(start -0.925 0.47)
			(end 0.925 -0.47)
			(stroke
				(width 0.05)
				(type default)
			)
			(fill no)
			(layer "B.CrtYd")
		)
		(fp_line
			(start 0.504 -0.248)
			(end -0.494 -0.248)
			(stroke
				(width 0.15)
				(type solid)
			)
			(layer "B.Fab")
		)
		(fp_line
			(start -0.494 -0.248)
			(end -0.494 0.25)
			(stroke
				(width 0.15)
				(type solid)
			)
			(layer "B.Fab")
		)
		(fp_line
			(start 0.504 0.25)
			(end 0.504 -0.248)
			(stroke
				(width 0.15)
				(type solid)
			)
			(layer "B.Fab")
		)
		(fp_line
			(start -0.494 0.25)
			(end 0.504 0.25)
			(stroke
				(width 0.15)
				(type solid)
			)
			(layer "B.Fab")
		)
		(pad "1" smd roundrect
			(at -0.48 0 90)
			(size 0.59 0.64)
			(layers "B.Cu" "B.Mask" "B.Paste")
			(roundrect_rratio 0.25)
			(net 1 "GND")
			(pintype "passive")
		)
		(pad "2" smd roundrect
			(at 0.48 0 90)
			(size 0.59 0.64)
			(layers "B.Cu" "B.Mask" "B.Paste")
			(roundrect_rratio 0.25)
			(net 200 "+3V3")
			(pintype "passive")
		)
	)
	(footprint "antmicro-footprints:TP_SMD_1mm"
		(layer "B.Cu")
		(at 201.8 157.4 -90)
		(property "Reference" "TP39"
			(at -3.45 -0.45 90)
			(layer "B.SilkS")
			(effects
				(font
					(size 0.7 0.7)
					(thickness 0.15)
				)
				(justify left bottom mirror)
			)
		)
		(property "Value" "TP_1mm_SMD"
			(at 0 -1.4 90)
			(layer "B.Fab")
			(effects
				(font
					(size 0.7 0.7)
					(thickness 0.15)
				)
				(justify left bottom mirror)
			)
		)
		(property "MPN" ""
			(at 0 0 90)
			(unlocked yes)
			(layer "B.Fab")
			(hide yes)
			(effects
				(font
					(size 1 1)
					(thickness 0.15)
				)
				(justify mirror)
			)
		)
		(property "Manufacturer" ""
			(at 0 0 90)
			(unlocked yes)
			(layer "B.Fab")
			(hide yes)
			(effects
				(font
					(size 1 1)
					(thickness 0.15)
				)
				(justify mirror)
			)
		)
		(property "Author" "Antmicro"
			(at 0 0 90)
			(unlocked yes)
			(layer "B.Fab")
			(hide yes)
			(effects
				(font
					(size 1 1)
					(thickness 0.15)
				)
				(justify mirror)
			)
		)
		(property "License" "Apache-2.0"
			(at 0 0 90)
			(unlocked yes)
			(layer "B.Fab")
			(hide yes)
			(effects
				(font
					(size 1 1)
					(thickness 0.15)
				)
				(justify mirror)
			)
		)
		(sheetname "/I^{2}C/")
		(sheetfile "i2c.kicad_sch")
		(attr exclude_from_pos_files)
		(fp_circle
			(center 0 0)
			(end 0.6 0)
			(stroke
				(width 0.05)
				(type default)
			)
			(fill no)
			(layer "B.CrtYd")
		)
		(fp_text user "License: Apache-2.0"
			(at -0.5 -5.2 90)
			(layer "B.Fab")
			(effects
				(font
					(size 0.7 0.7)
					(thickness 0.15)
				)
				(justify left bottom mirror)
			)
		)
		(fp_text user "Author: Antmicro"
			(at -0.5 -4 90)
			(layer "B.Fab")
			(effects
				(font
					(size 0.7 0.7)
					(thickness 0.15)
				)
				(justify left bottom mirror)
			)
		)
		(fp_text user "${REFERENCE}"
			(at -0.5 -2.8 90)
			(layer "B.Fab")
			(effects
				(font
					(size 0.7 0.7)
					(thickness 0.15)
				)
				(justify left bottom mirror)
			)
		)
		(pad "1" smd circle
			(at 0 0 270)
			(size 1 1)
			(layers "B.Cu" "B.Mask")
			(net 1 "GND")
			(pinfunction "1")
			(pintype "passive")
		)
	)
	(footprint "antmicro-footprints:C_0402_1005Metric"
		(layer "B.Cu")
		(at 140.875501 176.301)
		(descr "Capacitor SMD 0402 (1005 Metric), square (rectangular) end terminal, IPC_7351 nominal, (Body size source: IPC-SM-782 page 76, https://www.pcb-3d.com/wordpress/wp-content/uploads/ipc-sm-782a_amendment_1_and_2.pdf)")
		(tags "capacitor 0402")
		(property "Reference" "C84"
			(at 0 1.17 180)
			(layer "B.SilkS")
			(hide yes)
			(effects
				(font
					(size 0.7 0.7)
					(thickness 0.15)
				)
				(justify left bottom mirror)
			)
		)
		(property "Value" "C_100n_0402"
			(at 0 -1.169 180)
			(layer "B.Fab")
			(effects
				(font
					(size 0.7 0.7)
					(thickness 0.15)
				)
				(justify left bottom mirror)
			)
		)
		(property "Datasheet" "https://www.murata.com/products/productdetail?partno=GRM155R61H104KE14%23"
			(at 0 0 0)
			(layer "F.Fab")
			(hide yes)
			(effects
				(font
					(size 1.27 1.27)
					(thickness 0.15)
				)
			)
		)
		(property "Author" "Antmicro"
			(at 0 0 0)
			(layer "B.Fab")
			(hide yes)
			(effects
				(font
					(size 1 1)
					(thickness 0.15)
				)
				(justify mirror)
			)
		)
		(property "Dielectric" "X5R"
			(at 0 0 0)
			(layer "B.Fab")
			(hide yes)
			(effects
				(font
					(size 1 1)
					(thickness 0.15)
				)
				(justify mirror)
			)
		)
		(property "License" "Apache-2.0"
			(at 0 0 0)
			(layer "B.Fab")
			(hide yes)
			(effects
				(font
					(size 1 1)
					(thickness 0.15)
				)
				(justify mirror)
			)
		)
		(property "MPN" "GRM155R61H104KE14D"
			(at 0 0 0)
			(layer "B.Fab")
			(hide yes)
			(effects
				(font
					(size 1 1)
					(thickness 0.15)
				)
				(justify mirror)
			)
		)
		(property "Manufacturer" "Murata"
			(at 0 0 0)
			(layer "B.Fab")
			(hide yes)
			(effects
				(font
					(size 1 1)
					(thickness 0.15)
				)
				(justify mirror)
			)
		)
		(property "Val" "100n"
			(at 0 0 0)
			(layer "B.Fab")
			(hide yes)
			(effects
				(font
					(size 1 1)
					(thickness 0.15)
				)
				(justify mirror)
			)
		)
		(property "Voltage" "50V"
			(at 0 0 0)
			(layer "B.Fab")
			(hide yes)
			(effects
				(font
					(size 1 1)
					(thickness 0.15)
				)
				(justify mirror)
			)
		)
		(sheetname "/FPGA power/")
		(sheetfile "fpga-power.kicad_sch")
		(attr smd)
		(fp_rect
			(start -0.9656 0.4572)
			(end 0.9652 -0.4828)
			(stroke
				(width 0.05)
				(type solid)
			)
			(fill no)
			(layer "B.CrtYd")
		)
		(fp_line
			(start -0.5 -0.248)
			(end -0.5 0.25)
			(stroke
				(width 0.15)
				(type solid)
			)
			(layer "B.Fab")
		)
		(fp_line
			(start -0.5 0.25)
			(end 0.498 0.25)
			(stroke
				(width 0.15)
				(type solid)
			)
			(layer "B.Fab")
		)
		(fp_line
			(start 0.498 -0.248)
			(end -0.5 -0.248)
			(stroke
				(width 0.15)
				(type solid)
			)
			(layer "B.Fab")
		)
		(fp_line
			(start 0.498 0.25)
			(end 0.498 -0.248)
			(stroke
				(width 0.15)
				(type solid)
			)
			(layer "B.Fab")
		)
		(pad "1" smd roundrect
			(at -0.5 0 270)
			(size 0.6 0.6)
			(layers "B.Cu" "B.Mask" "B.Paste")
			(roundrect_rratio 0.25)
			(net 1 "GND")
			(pintype "passive")
		)
		(pad "2" smd roundrect
			(at 0.498 0)
			(size 0.6 0.6)
			(layers "B.Cu" "B.Mask" "B.Paste")
			(roundrect_rratio 0.25)
			(net 188 "+1V8")
			(pintype "passive")
		)
	)
	(footprint "antmicro-footprints:C_0402_1005Metric"
		(layer "B.Cu")
		(at 146.875501 164.301)
		(descr "Capacitor SMD 0402 (1005 Metric), square (rectangular) end terminal, IPC_7351 nominal, (Body size source: IPC-SM-782 page 76, https://www.pcb-3d.com/wordpress/wp-content/uploads/ipc-sm-782a_amendment_1_and_2.pdf)")
		(tags "capacitor 0402")
		(property "Reference" "C91"
			(at 0 1.17 180)
			(layer "B.SilkS")
			(hide yes)
			(effects
				(font
					(size 0.7 0.7)
					(thickness 0.15)
				)
				(justify left bottom mirror)
			)
		)
		(property "Value" "C_100n_0402"
			(at 0 -1.169 180)
			(layer "B.Fab")
			(effects
				(font
					(size 0.7 0.7)
					(thickness 0.15)
				)
				(justify left bottom mirror)
			)
		)
		(property "Datasheet" "https://www.murata.com/products/productdetail?partno=GRM155R61H104KE14%23"
			(at 0 0 0)
			(layer "F.Fab")
			(hide yes)
			(effects
				(font
					(size 1.27 1.27)
					(thickness 0.15)
				)
			)
		)
		(property "Author" "Antmicro"
			(at 0 0 0)
			(layer "B.Fab")
			(hide yes)
			(effects
				(font
					(size 1 1)
					(thickness 0.15)
				)
				(justify mirror)
			)
		)
		(property "Dielectric" "X5R"
			(at 0 0 0)
			(layer "B.Fab")
			(hide yes)
			(effects
				(font
					(size 1 1)
					(thickness 0.15)
				)
				(justify mirror)
			)
		)
		(property "License" "Apache-2.0"
			(at 0 0 0)
			(layer "B.Fab")
			(hide yes)
			(effects
				(font
					(size 1 1)
					(thickness 0.15)
				)
				(justify mirror)
			)
		)
		(property "MPN" "GRM155R61H104KE14D"
			(at 0 0 0)
			(layer "B.Fab")
			(hide yes)
			(effects
				(font
					(size 1 1)
					(thickness 0.15)
				)
				(justify mirror)
			)
		)
		(property "Manufacturer" "Murata"
			(at 0 0 0)
			(layer "B.Fab")
			(hide yes)
			(effects
				(font
					(size 1 1)
					(thickness 0.15)
				)
				(justify mirror)
			)
		)
		(property "Val" "100n"
			(at 0 0 0)
			(layer "B.Fab")
			(hide yes)
			(effects
				(font
					(size 1 1)
					(thickness 0.15)
				)
				(justify mirror)
			)
		)
		(property "Voltage" "50V"
			(at 0 0 0)
			(layer "B.Fab")
			(hide yes)
			(effects
				(font
					(size 1 1)
					(thickness 0.15)
				)
				(justify mirror)
			)
		)
		(sheetname "/FPGA power/")
		(sheetfile "fpga-power.kicad_sch")
		(attr smd)
		(fp_rect
			(start -0.9656 0.4572)
			(end 0.9652 -0.4828)
			(stroke
				(width 0.05)
				(type solid)
			)
			(fill no)
			(layer "B.CrtYd")
		)
		(fp_line
			(start -0.5 -0.248)
			(end -0.5 0.25)
			(stroke
				(width 0.15)
				(type solid)
			)
			(layer "B.Fab")
		)
		(fp_line
			(start -0.5 0.25)
			(end 0.498 0.25)
			(stroke
				(width 0.15)
				(type solid)
			)
			(layer "B.Fab")
		)
		(fp_line
			(start 0.498 -0.248)
			(end -0.5 -0.248)
			(stroke
				(width 0.15)
				(type solid)
			)
			(layer "B.Fab")
		)
		(fp_line
			(start 0.498 0.25)
			(end 0.498 -0.248)
			(stroke
				(width 0.15)
				(type solid)
			)
			(layer "B.Fab")
		)
		(pad "1" smd roundrect
			(at -0.5 0 270)
			(size 0.6 0.6)
			(layers "B.Cu" "B.Mask" "B.Paste")
			(roundrect_rratio 0.25)
			(net 1 "GND")
			(pintype "passive")
		)
		(pad "2" smd roundrect
			(at 0.498 0)
			(size 0.6 0.6)
			(layers "B.Cu" "B.Mask" "B.Paste")
			(roundrect_rratio 0.25)
			(net 206 "+1V1")
			(pintype "passive")
		)
	)
	(footprint "antmicro-footprints:C_0402_1005Metric"
		(layer "B.Cu")
		(at 198.065 147.301 -90)
		(descr "Capacitor SMD 0402")
		(tags "capacitor SMD 0402")
		(property "Reference" "C212"
			(at 0 0.699 90)
			(layer "B.SilkS")
			(hide yes)
			(effects
				(font
					(size 0.7 0.7)
					(thickness 0.15)
				)
				(justify left bottom mirror)
			)
		)
		(property "Value" "C_100n_0402"
			(at -1.022927 -2.155213 90)
			(layer "B.Fab")
			(effects
				(font
					(size 0.7 0.7)
					(thickness 0.15)
				)
				(justify left bottom mirror)
			)
		)
		(property "Datasheet" "https://www.murata.com/products/productdetail?partno=GRM155R61H104KE14%23"
			(at 0 0 270)
			(layer "F.Fab")
			(hide yes)
			(effects
				(font
					(size 1.27 1.27)
					(thickness 0.15)
				)
			)
		)
		(property "Author" "Antmicro"
			(at 50.764 345.366 0)
			(layer "B.Fab")
			(hide yes)
			(effects
				(font
					(size 1 1)
					(thickness 0.15)
				)
				(justify mirror)
			)
		)
		(property "Dielectric" "X5R"
			(at 50.764 345.366 0)
			(layer "B.Fab")
			(hide yes)
			(effects
				(font
					(size 1 1)
					(thickness 0.15)
				)
				(justify mirror)
			)
		)
		(property "License" "Apache-2.0"
			(at 50.764 345.366 0)
			(layer "B.Fab")
			(hide yes)
			(effects
				(font
					(size 1 1)
					(thickness 0.15)
				)
				(justify mirror)
			)
		)
		(property "MPN" "GRM155R61H104KE14D"
			(at 50.764 345.366 0)
			(layer "B.Fab")
			(hide yes)
			(effects
				(font
					(size 1 1)
					(thickness 0.15)
				)
				(justify mirror)
			)
		)
		(property "Manufacturer" "Murata"
			(at 50.764 345.366 0)
			(layer "B.Fab")
			(hide yes)
			(effects
				(font
					(size 1 1)
					(thickness 0.15)
				)
				(justify mirror)
			)
		)
		(property "Val" "100n"
			(at 50.764 345.366 0)
			(layer "B.Fab")
			(hide yes)
			(effects
				(font
					(size 1 1)
					(thickness 0.15)
				)
				(justify mirror)
			)
		)
		(property "Voltage" "50V"
			(at 50.764 345.366 0)
			(layer "B.Fab")
			(hide yes)
			(effects
				(font
					(size 1 1)
					(thickness 0.15)
				)
				(justify mirror)
			)
		)
		(sheetname "/Supply/")
		(sheetfile "supply.kicad_sch")
		(attr smd)
		(fp_rect
			(start -0.9659 0.481258)
			(end 0.9649 -0.458742)
			(stroke
				(width 0.05)
				(type solid)
			)
			(fill no)
			(layer "B.CrtYd")
		)
		(fp_line
			(start -0.499 0.25)
			(end 0.499 0.25)
			(stroke
				(width 0.15)
				(type solid)
			)
			(layer "B.Fab")
		)
		(fp_line
			(start 0.499 0.25)
			(end 0.499 -0.248)
			(stroke
				(width 0.15)
				(type solid)
			)
			(layer "B.Fab")
		)
		(fp_line
			(start -0.499 -0.248)
			(end -0.499 0.25)
			(stroke
				(width 0.15)
				(type solid)
			)
			(layer "B.Fab")
		)
		(fp_line
			(start 0.499 -0.248)
			(end -0.499 -0.248)
			(stroke
				(width 0.15)
				(type solid)
			)
			(layer "B.Fab")
		)
		(pad "1" smd roundrect
			(at -0.484 0 270)
			(size 0.59 0.64)
			(layers "B.Cu" "B.Mask" "B.Paste")
			(roundrect_rratio 0.25)
			(net 1 "GND")
			(pintype "passive")
		)
		(pad "2" smd roundrect
			(at 0.484 0 270)
			(size 0.59 0.64)
			(layers "B.Cu" "B.Mask" "B.Paste")
			(roundrect_rratio 0.25)
			(net 41 "+3V3_AON")
			(pintype "passive")
		)
	)
	(footprint "antmicro-footprints:C_0402_1005Metric"
		(layer "B.Cu")
		(at 136.375501 165.801 90)
		(descr "Capacitor SMD 0402 (1005 Metric), square (rectangular) end terminal, IPC_7351 nominal, (Body size source: IPC-SM-782 page 76, https://www.pcb-3d.com/wordpress/wp-content/uploads/ipc-sm-782a_amendment_1_and_2.pdf)")
		(tags "capacitor 0402")
		(property "Reference" "C37"
			(at 0 1.17 270)
			(layer "B.SilkS")
			(hide yes)
			(effects
				(font
					(size 0.7 0.7)
					(thickness 0.15)
				)
				(justify left bottom mirror)
			)
		)
		(property "Value" "C_100n_0402"
			(at 0 -1.169 270)
			(layer "B.Fab")
			(effects
				(font
					(size 0.7 0.7)
					(thickness 0.15)
				)
				(justify left bottom mirror)
			)
		)
		(property "Datasheet" "https://www.murata.com/products/productdetail?partno=GRM155R61H104KE14%23"
			(at 0 0 90)
			(layer "F.Fab")
			(hide yes)
			(effects
				(font
					(size 1.27 1.27)
					(thickness 0.15)
				)
			)
		)
		(property "Author" "Antmicro"
			(at 302.176501 29.425499 0)
			(layer "B.Fab")
			(hide yes)
			(effects
				(font
					(size 1 1)
					(thickness 0.15)
				)
				(justify mirror)
			)
		)
		(property "Dielectric" "X5R"
			(at 302.176501 29.425499 0)
			(layer "B.Fab")
			(hide yes)
			(effects
				(font
					(size 1 1)
					(thickness 0.15)
				)
				(justify mirror)
			)
		)
		(property "License" "Apache-2.0"
			(at 302.176501 29.425499 0)
			(layer "B.Fab")
			(hide yes)
			(effects
				(font
					(size 1 1)
					(thickness 0.15)
				)
				(justify mirror)
			)
		)
		(property "MPN" "GRM155R61H104KE14D"
			(at 302.176501 29.425499 0)
			(layer "B.Fab")
			(hide yes)
			(effects
				(font
					(size 1 1)
					(thickness 0.15)
				)
				(justify mirror)
			)
		)
		(property "Manufacturer" "Murata"
			(at 302.176501 29.425499 0)
			(layer "B.Fab")
			(hide yes)
			(effects
				(font
					(size 1 1)
					(thickness 0.15)
				)
				(justify mirror)
			)
		)
		(property "Val" "100n"
			(at 302.176501 29.425499 0)
			(layer "B.Fab")
			(hide yes)
			(effects
				(font
					(size 1 1)
					(thickness 0.15)
				)
				(justify mirror)
			)
		)
		(property "Voltage" "50V"
			(at 302.176501 29.425499 0)
			(layer "B.Fab")
			(hide yes)
			(effects
				(font
					(size 1 1)
					(thickness 0.15)
				)
				(justify mirror)
			)
		)
		(sheetname "/FPGA power/")
		(sheetfile "fpga-power.kicad_sch")
		(attr smd)
		(fp_rect
			(start -0.9656 0.4572)
			(end 0.9652 -0.4828)
			(stroke
				(width 0.05)
				(type solid)
			)
			(fill no)
			(layer "B.CrtYd")
		)
		(fp_line
			(start 0.498 -0.248)
			(end -0.5 -0.248)
			(stroke
				(width 0.15)
				(type solid)
			)
			(layer "B.Fab")
		)
		(fp_line
			(start -0.5 -0.248)
			(end -0.5 0.25)
			(stroke
				(width 0.15)
				(type solid)
			)
			(layer "B.Fab")
		)
		(fp_line
			(start 0.498 0.25)
			(end 0.498 -0.248)
			(stroke
				(width 0.15)
				(type solid)
			)
			(layer "B.Fab")
		)
		(fp_line
			(start -0.5 0.25)
			(end 0.498 0.25)
			(stroke
				(width 0.15)
				(type solid)
			)
			(layer "B.Fab")
		)
		(pad "1" smd roundrect
			(at -0.5 0)
			(size 0.6 0.6)
			(layers "B.Cu" "B.Mask" "B.Paste")
			(roundrect_rratio 0.25)
			(net 1 "GND")
			(pintype "passive")
		)
		(pad "2" smd roundrect
			(at 0.498 0 90)
			(size 0.6 0.6)
			(layers "B.Cu" "B.Mask" "B.Paste")
			(roundrect_rratio 0.25)
			(net 206 "+1V1")
			(pintype "passive")
		)
	)
	(footprint "antmicro-footprints:TP_SMD_1mm"
		(layer "B.Cu")
		(at 92.5 188.275 180)
		(property "Reference" "TP45"
			(at 0.9 -0.325 0)
			(layer "B.SilkS")
			(effects
				(font
					(size 0.7 0.7)
					(thickness 0.15)
				)
				(justify left bottom mirror)
			)
		)
		(property "Value" "TP_1mm_SMD"
			(at 0 -1.4 0)
			(layer "B.Fab")
			(effects
				(font
					(size 0.7 0.7)
					(thickness 0.15)
				)
				(justify left bottom mirror)
			)
		)
		(property "MPN" ""
			(at 0 0 0)
			(unlocked yes)
			(layer "B.Fab")
			(hide yes)
			(effects
				(font
					(size 1 1)
					(thickness 0.15)
				)
				(justify mirror)
			)
		)
		(property "Manufacturer" ""
			(at 0 0 0)
			(unlocked yes)
			(layer "B.Fab")
			(hide yes)
			(effects
				(font
					(size 1 1)
					(thickness 0.15)
				)
				(justify mirror)
			)
		)
		(property "Author" "Antmicro"
			(at 0 0 0)
			(unlocked yes)
			(layer "B.Fab")
			(hide yes)
			(effects
				(font
					(size 1 1)
					(thickness 0.15)
				)
				(justify mirror)
			)
		)
		(property "License" "Apache-2.0"
			(at 0 0 0)
			(unlocked yes)
			(layer "B.Fab")
			(hide yes)
			(effects
				(font
					(size 1 1)
					(thickness 0.15)
				)
				(justify mirror)
			)
		)
		(sheetname "/Debug FTDI/")
		(sheetfile "debug-ftdi.kicad_sch")
		(attr exclude_from_pos_files)
		(fp_circle
			(center 0 0)
			(end 0.6 0)
			(stroke
				(width 0.05)
				(type default)
			)
			(fill no)
			(layer "B.CrtYd")
		)
		(fp_text user "License: Apache-2.0"
			(at -0.5 -5.2 0)
			(layer "B.Fab")
			(effects
				(font
					(size 0.7 0.7)
					(thickness 0.15)
				)
				(justify left bottom mirror)
			)
		)
		(fp_text user "Author: Antmicro"
			(at -0.5 -4 0)
			(layer "B.Fab")
			(effects
				(font
					(size 0.7 0.7)
					(thickness 0.15)
				)
				(justify left bottom mirror)
			)
		)
		(fp_text user "${REFERENCE}"
			(at -0.5 -2.8 0)
			(layer "B.Fab")
			(effects
				(font
					(size 0.7 0.7)
					(thickness 0.15)
				)
				(justify left bottom mirror)
			)
		)
		(pad "1" smd circle
			(at 0 0 180)
			(size 1 1)
			(layers "B.Cu" "B.Mask")
			(net 47 "/Debug FTDI/JTAG.TDO")
			(pinfunction "1")
			(pintype "passive")
		)
	)
	(footprint "antmicro-footprints:C_0402_1005Metric"
		(layer "B.Cu")
		(at 149.377001 186.1505 180)
		(descr "Capacitor SMD 0402 (1005 Metric), square (rectangular) end terminal, IPC_7351 nominal, (Body size source: IPC-SM-782 page 76, https://www.pcb-3d.com/wordpress/wp-content/uploads/ipc-sm-782a_amendment_1_and_2.pdf)")
		(tags "capacitor 0402")
		(property "Reference" "C103"
			(at 0 1.17 0)
			(layer "B.SilkS")
			(hide yes)
			(effects
				(font
					(size 0.7 0.7)
					(thickness 0.15)
				)
				(justify left bottom mirror)
			)
		)
		(property "Value" "C_4u7_0402"
			(at 0 -1.169 0)
			(layer "B.Fab")
			(effects
				(font
					(size 0.7 0.7)
					(thickness 0.15)
				)
				(justify left bottom mirror)
			)
		)
		(property "Datasheet" "https://www.murata.com/products/productdetail?partno=GRM155R61A475MEAA%23"
			(at 0 0 180)
			(layer "F.Fab")
			(hide yes)
			(effects
				(font
					(size 1.27 1.27)
					(thickness 0.15)
				)
			)
		)
		(property "Author" "Antmicro"
			(at 298.754002 372.301 0)
			(layer "B.Fab")
			(hide yes)
			(effects
				(font
					(size 1 1)
					(thickness 0.15)
				)
				(justify mirror)
			)
		)
		(property "Dielectric" ""
			(at 298.754002 372.301 0)
			(layer "B.Fab")
			(hide yes)
			(effects
				(font
					(size 1 1)
					(thickness 0.15)
				)
				(justify mirror)
			)
		)
		(property "License" "Apache-2.0"
			(at 298.754002 372.301 0)
			(layer "B.Fab")
			(hide yes)
			(effects
				(font
					(size 1 1)
					(thickness 0.15)
				)
				(justify mirror)
			)
		)
		(property "MPN" "GRM155R61A475MEAAD"
			(at 298.754002 372.301 0)
			(layer "B.Fab")
			(hide yes)
			(effects
				(font
					(size 1 1)
					(thickness 0.15)
				)
				(justify mirror)
			)
		)
		(property "Manufacturer" "Murata"
			(at 298.754002 372.301 0)
			(layer "B.Fab")
			(hide yes)
			(effects
				(font
					(size 1 1)
					(thickness 0.15)
				)
				(justify mirror)
			)
		)
		(property "Val" "4u7"
			(at 298.754002 372.301 0)
			(layer "B.Fab")
			(hide yes)
			(effects
				(font
					(size 1 1)
					(thickness 0.15)
				)
				(justify mirror)
			)
		)
		(property "Voltage" ""
			(at 298.754002 372.301 0)
			(layer "B.Fab")
			(hide yes)
			(effects
				(font
					(size 1 1)
					(thickness 0.15)
				)
				(justify mirror)
			)
		)
		(sheetname "/FPGA power/")
		(sheetfile "fpga-power.kicad_sch")
		(attr smd)
		(fp_rect
			(start -0.9656 0.4572)
			(end 0.9652 -0.4828)
			(stroke
				(width 0.05)
				(type solid)
			)
			(fill no)
			(layer "B.CrtYd")
		)
		(fp_line
			(start 0.498 0.25)
			(end 0.498 -0.248)
			(stroke
				(width 0.15)
				(type solid)
			)
			(layer "B.Fab")
		)
		(fp_line
			(start 0.498 -0.248)
			(end -0.5 -0.248)
			(stroke
				(width 0.15)
				(type solid)
			)
			(layer "B.Fab")
		)
		(fp_line
			(start -0.5 0.25)
			(end 0.498 0.25)
			(stroke
				(width 0.15)
				(type solid)
			)
			(layer "B.Fab")
		)
		(fp_line
			(start -0.5 -0.248)
			(end -0.5 0.25)
			(stroke
				(width 0.15)
				(type solid)
			)
			(layer "B.Fab")
		)
		(pad "1" smd roundrect
			(at -0.5 0 90)
			(size 0.6 0.6)
			(layers "B.Cu" "B.Mask" "B.Paste")
			(roundrect_rratio 0.25)
			(net 226 "+1V2_MGTAVTT")
			(pintype "passive")
		)
		(pad "2" smd roundrect
			(at 0.498 0 180)
			(size 0.6 0.6)
			(layers "B.Cu" "B.Mask" "B.Paste")
			(roundrect_rratio 0.25)
			(net 1 "GND")
			(pintype "passive")
		)
	)
	(footprint "antmicro-footprints:C_0402_1005Metric"
		(layer "B.Cu")
		(at 141.85 159.6)
		(descr "Capacitor SMD 0402")
		(tags "capacitor SMD 0402")
		(property "Reference" "C167"
			(at 0 0.699 180)
			(layer "B.SilkS")
			(hide yes)
			(effects
				(font
					(size 0.7 0.7)
					(thickness 0.15)
				)
				(justify left bottom mirror)
			)
		)
		(property "Value" "C_100n_0402"
			(at -1.022927 -2.155213 180)
			(layer "B.Fab")
			(effects
				(font
					(size 0.7 0.7)
					(thickness 0.15)
				)
				(justify left bottom mirror)
			)
		)
		(property "Datasheet" "https://www.murata.com/products/productdetail?partno=GRM155R61H104KE14%23"
			(at 0 0 0)
			(layer "F.Fab")
			(hide yes)
			(effects
				(font
					(size 1.27 1.27)
					(thickness 0.15)
				)
			)
		)
		(property "Author" "Antmicro"
			(at 0 0 0)
			(layer "B.Fab")
			(hide yes)
			(effects
				(font
					(size 1 1)
					(thickness 0.15)
				)
				(justify mirror)
			)
		)
		(property "Dielectric" "X5R"
			(at 0 0 0)
			(layer "B.Fab")
			(hide yes)
			(effects
				(font
					(size 1 1)
					(thickness 0.15)
				)
				(justify mirror)
			)
		)
		(property "License" "Apache-2.0"
			(at 0 0 0)
			(layer "B.Fab")
			(hide yes)
			(effects
				(font
					(size 1 1)
					(thickness 0.15)
				)
				(justify mirror)
			)
		)
		(property "MPN" "GRM155R61H104KE14D"
			(at 0 0 0)
			(layer "B.Fab")
			(hide yes)
			(effects
				(font
					(size 1 1)
					(thickness 0.15)
				)
				(justify mirror)
			)
		)
		(property "Manufacturer" "Murata"
			(at 0 0 0)
			(layer "B.Fab")
			(hide yes)
			(effects
				(font
					(size 1 1)
					(thickness 0.15)
				)
				(justify mirror)
			)
		)
		(property "Val" "100n"
			(at 0 0 0)
			(layer "B.Fab")
			(hide yes)
			(effects
				(font
					(size 1 1)
					(thickness 0.15)
				)
				(justify mirror)
			)
		)
		(property "Voltage" "50V"
			(at 0 0 0)
			(layer "B.Fab")
			(hide yes)
			(effects
				(font
					(size 1 1)
					(thickness 0.15)
				)
				(justify mirror)
			)
		)
		(sheetname "/FPGA banks HP/")
		(sheetfile "fpga-banks-32-34.kicad_sch")
		(attr smd)
		(fp_rect
			(start -0.9659 0.481258)
			(end 0.9649 -0.458742)
			(stroke
				(width 0.05)
				(type solid)
			)
			(fill no)
			(layer "B.CrtYd")
		)
		(fp_line
			(start -0.499 -0.248)
			(end -0.499 0.25)
			(stroke
				(width 0.15)
				(type solid)
			)
			(layer "B.Fab")
		)
		(fp_line
			(start -0.499 0.25)
			(end 0.499 0.25)
			(stroke
				(width 0.15)
				(type solid)
			)
			(layer "B.Fab")
		)
		(fp_line
			(start 0.499 -0.248)
			(end -0.499 -0.248)
			(stroke
				(width 0.15)
				(type solid)
			)
			(layer "B.Fab")
		)
		(fp_line
			(start 0.499 0.25)
			(end 0.499 -0.248)
			(stroke
				(width 0.15)
				(type solid)
			)
			(layer "B.Fab")
		)
		(pad "1" smd roundrect
			(at -0.484 0)
			(size 0.59 0.64)
			(layers "B.Cu" "B.Mask" "B.Paste")
			(roundrect_rratio 0.25)
			(net 10 "/FPGA banks HP/VREF")
			(pintype "passive")
		)
		(pad "2" smd roundrect
			(at 0.484 0)
			(size 0.59 0.64)
			(layers "B.Cu" "B.Mask" "B.Paste")
			(roundrect_rratio 0.25)
			(net 1 "GND")
			(pintype "passive")
		)
	)
	(footprint "antmicro-footprints:C_0402_1005Metric"
		(layer "B.Cu")
		(at 141.875501 172.301)
		(descr "Capacitor SMD 0402 (1005 Metric), square (rectangular) end terminal, IPC_7351 nominal, (Body size source: IPC-SM-782 page 76, https://www.pcb-3d.com/wordpress/wp-content/uploads/ipc-sm-782a_amendment_1_and_2.pdf)")
		(tags "capacitor 0402")
		(property "Reference" "C64"
			(at 0 1.17 180)
			(layer "B.SilkS")
			(hide yes)
			(effects
				(font
					(size 0.7 0.7)
					(thickness 0.15)
				)
				(justify left bottom mirror)
			)
		)
		(property "Value" "C_100n_0402"
			(at 0 -1.169 180)
			(layer "B.Fab")
			(effects
				(font
					(size 0.7 0.7)
					(thickness 0.15)
				)
				(justify left bottom mirror)
			)
		)
		(property "Datasheet" "https://www.murata.com/products/productdetail?partno=GRM155R61H104KE14%23"
			(at 0 0 0)
			(layer "F.Fab")
			(hide yes)
			(effects
				(font
					(size 1.27 1.27)
					(thickness 0.15)
				)
			)
		)
		(property "Author" "Antmicro"
			(at 0 0 0)
			(layer "B.Fab")
			(hide yes)
			(effects
				(font
					(size 1 1)
					(thickness 0.15)
				)
				(justify mirror)
			)
		)
		(property "Dielectric" "X5R"
			(at 0 0 0)
			(layer "B.Fab")
			(hide yes)
			(effects
				(font
					(size 1 1)
					(thickness 0.15)
				)
				(justify mirror)
			)
		)
		(property "License" "Apache-2.0"
			(at 0 0 0)
			(layer "B.Fab")
			(hide yes)
			(effects
				(font
					(size 1 1)
					(thickness 0.15)
				)
				(justify mirror)
			)
		)
		(property "MPN" "GRM155R61H104KE14D"
			(at 0 0 0)
			(layer "B.Fab")
			(hide yes)
			(effects
				(font
					(size 1 1)
					(thickness 0.15)
				)
				(justify mirror)
			)
		)
		(property "Manufacturer" "Murata"
			(at 0 0 0)
			(layer "B.Fab")
			(hide yes)
			(effects
				(font
					(size 1 1)
					(thickness 0.15)
				)
				(justify mirror)
			)
		)
		(property "Val" "100n"
			(at 0 0 0)
			(layer "B.Fab")
			(hide yes)
			(effects
				(font
					(size 1 1)
					(thickness 0.15)
				)
				(justify mirror)
			)
		)
		(property "Voltage" "50V"
			(at 0 0 0)
			(layer "B.Fab")
			(hide yes)
			(effects
				(font
					(size 1 1)
					(thickness 0.15)
				)
				(justify mirror)
			)
		)
		(sheetname "/FPGA power/")
		(sheetfile "fpga-power.kicad_sch")
		(attr smd)
		(fp_rect
			(start -0.9656 0.4572)
			(end 0.9652 -0.4828)
			(stroke
				(width 0.05)
				(type solid)
			)
			(fill no)
			(layer "B.CrtYd")
		)
		(fp_line
			(start -0.5 -0.248)
			(end -0.5 0.25)
			(stroke
				(width 0.15)
				(type solid)
			)
			(layer "B.Fab")
		)
		(fp_line
			(start -0.5 0.25)
			(end 0.498 0.25)
			(stroke
				(width 0.15)
				(type solid)
			)
			(layer "B.Fab")
		)
		(fp_line
			(start 0.498 -0.248)
			(end -0.5 -0.248)
			(stroke
				(width 0.15)
				(type solid)
			)
			(layer "B.Fab")
		)
		(fp_line
			(start 0.498 0.25)
			(end 0.498 -0.248)
			(stroke
				(width 0.15)
				(type solid)
			)
			(layer "B.Fab")
		)
		(pad "1" smd roundrect
			(at -0.5 0 270)
			(size 0.6 0.6)
			(layers "B.Cu" "B.Mask" "B.Paste")
			(roundrect_rratio 0.25)
			(net 1 "GND")
			(pintype "passive")
		)
		(pad "2" smd roundrect
			(at 0.498 0)
			(size 0.6 0.6)
			(layers "B.Cu" "B.Mask" "B.Paste")
			(roundrect_rratio 0.25)
			(net 188 "+1V8")
			(pintype "passive")
		)
	)
	(footprint "antmicro-footprints:TP_SMD_1mm"
		(layer "B.Cu")
		(at 177.74 165.88 180)
		(property "Reference" "TP55"
			(at 0.58 -0.43 0)
			(layer "B.SilkS")
			(effects
				(font
					(size 0.7 0.7)
					(thickness 0.15)
				)
				(justify left bottom mirror)
			)
		)
		(property "Value" "TP_1mm_SMD"
			(at 0 -1.4 0)
			(layer "B.Fab")
			(effects
				(font
					(size 0.7 0.7)
					(thickness 0.15)
				)
				(justify left bottom mirror)
			)
		)
		(property "MPN" ""
			(at 0 0 0)
			(unlocked yes)
			(layer "B.Fab")
			(hide yes)
			(effects
				(font
					(size 1 1)
					(thickness 0.15)
				)
				(justify mirror)
			)
		)
		(property "Manufacturer" ""
			(at 0 0 0)
			(unlocked yes)
			(layer "B.Fab")
			(hide yes)
			(effects
				(font
					(size 1 1)
					(thickness 0.15)
				)
				(justify mirror)
			)
		)
		(property "Author" "Antmicro"
			(at 0 0 0)
			(unlocked yes)
			(layer "B.Fab")
			(hide yes)
			(effects
				(font
					(size 1 1)
					(thickness 0.15)
				)
				(justify mirror)
			)
		)
		(property "License" "Apache-2.0"
			(at 0 0 0)
			(unlocked yes)
			(layer "B.Fab")
			(hide yes)
			(effects
				(font
					(size 1 1)
					(thickness 0.15)
				)
				(justify mirror)
			)
		)
		(sheetname "/Supply/")
		(sheetfile "supply.kicad_sch")
		(attr exclude_from_pos_files)
		(fp_circle
			(center 0 0)
			(end 0.6 0)
			(stroke
				(width 0.05)
				(type default)
			)
			(fill no)
			(layer "B.CrtYd")
		)
		(fp_text user "Author: Antmicro"
			(at -0.5 -4 0)
			(layer "B.Fab")
			(effects
				(font
					(size 0.7 0.7)
					(thickness 0.15)
				)
				(justify left bottom mirror)
			)
		)
		(fp_text user "${REFERENCE}"
			(at -0.5 -2.8 0)
			(layer "B.Fab")
			(effects
				(font
					(size 0.7 0.7)
					(thickness 0.15)
				)
				(justify left bottom mirror)
			)
		)
		(fp_text user "License: Apache-2.0"
			(at -0.5 -5.2 0)
			(layer "B.Fab")
			(effects
				(font
					(size 0.7 0.7)
					(thickness 0.15)
				)
				(justify left bottom mirror)
			)
		)
		(pad "1" smd circle
			(at 0 0 180)
			(size 1 1)
			(layers "B.Cu" "B.Mask")
			(net 297 "/Supply/PWR_SCL_2")
			(pinfunction "1")
			(pintype "passive")
		)
	)
	(footprint "antmicro-footprints:C_0402_1005Metric"
		(layer "B.Cu")
		(at 144.875501 172.301)
		(descr "Capacitor SMD 0402 (1005 Metric), square (rectangular) end terminal, IPC_7351 nominal, (Body size source: IPC-SM-782 page 76, https://www.pcb-3d.com/wordpress/wp-content/uploads/ipc-sm-782a_amendment_1_and_2.pdf)")
		(tags "capacitor 0402")
		(property "Reference" "C81"
			(at 0 1.17 180)
			(layer "B.SilkS")
			(hide yes)
			(effects
				(font
					(size 0.7 0.7)
					(thickness 0.15)
				)
				(justify left bottom mirror)
			)
		)
		(property "Value" "C_100n_0402"
			(at 0 -1.169 180)
			(layer "B.Fab")
			(effects
				(font
					(size 0.7 0.7)
					(thickness 0.15)
				)
				(justify left bottom mirror)
			)
		)
		(property "Datasheet" "https://www.murata.com/products/productdetail?partno=GRM155R61H104KE14%23"
			(at 0 0 0)
			(layer "F.Fab")
			(hide yes)
			(effects
				(font
					(size 1.27 1.27)
					(thickness 0.15)
				)
			)
		)
		(property "Author" "Antmicro"
			(at 0 0 0)
			(layer "B.Fab")
			(hide yes)
			(effects
				(font
					(size 1 1)
					(thickness 0.15)
				)
				(justify mirror)
			)
		)
		(property "Dielectric" "X5R"
			(at 0 0 0)
			(layer "B.Fab")
			(hide yes)
			(effects
				(font
					(size 1 1)
					(thickness 0.15)
				)
				(justify mirror)
			)
		)
		(property "License" "Apache-2.0"
			(at 0 0 0)
			(layer "B.Fab")
			(hide yes)
			(effects
				(font
					(size 1 1)
					(thickness 0.15)
				)
				(justify mirror)
			)
		)
		(property "MPN" "GRM155R61H104KE14D"
			(at 0 0 0)
			(layer "B.Fab")
			(hide yes)
			(effects
				(font
					(size 1 1)
					(thickness 0.15)
				)
				(justify mirror)
			)
		)
		(property "Manufacturer" "Murata"
			(at 0 0 0)
			(layer "B.Fab")
			(hide yes)
			(effects
				(font
					(size 1 1)
					(thickness 0.15)
				)
				(justify mirror)
			)
		)
		(property "Val" "100n"
			(at 0 0 0)
			(layer "B.Fab")
			(hide yes)
			(effects
				(font
					(size 1 1)
					(thickness 0.15)
				)
				(justify mirror)
			)
		)
		(property "Voltage" "50V"
			(at 0 0 0)
			(layer "B.Fab")
			(hide yes)
			(effects
				(font
					(size 1 1)
					(thickness 0.15)
				)
				(justify mirror)
			)
		)
		(sheetname "/FPGA power/")
		(sheetfile "fpga-power.kicad_sch")
		(attr smd)
		(fp_rect
			(start -0.9656 0.4572)
			(end 0.9652 -0.4828)
			(stroke
				(width 0.05)
				(type solid)
			)
			(fill no)
			(layer "B.CrtYd")
		)
		(fp_line
			(start -0.5 -0.248)
			(end -0.5 0.25)
			(stroke
				(width 0.15)
				(type solid)
			)
			(layer "B.Fab")
		)
		(fp_line
			(start -0.5 0.25)
			(end 0.498 0.25)
			(stroke
				(width 0.15)
				(type solid)
			)
			(layer "B.Fab")
		)
		(fp_line
			(start 0.498 -0.248)
			(end -0.5 -0.248)
			(stroke
				(width 0.15)
				(type solid)
			)
			(layer "B.Fab")
		)
		(fp_line
			(start 0.498 0.25)
			(end 0.498 -0.248)
			(stroke
				(width 0.15)
				(type solid)
			)
			(layer "B.Fab")
		)
		(pad "1" smd roundrect
			(at -0.5 0 270)
			(size 0.6 0.6)
			(layers "B.Cu" "B.Mask" "B.Paste")
			(roundrect_rratio 0.25)
			(net 1 "GND")
			(pintype "passive")
		)
		(pad "2" smd roundrect
			(at 0.498 0)
			(size 0.6 0.6)
			(layers "B.Cu" "B.Mask" "B.Paste")
			(roundrect_rratio 0.25)
			(net 188 "+1V8")
			(pintype "passive")
		)
	)
	(footprint "antmicro-footprints:R_0402_1005Metric"
		(layer "B.Cu")
		(at 134.75 142.4 90)
		(descr "Resistor SMD 0402")
		(tags "resistor SMD 0402")
		(property "Reference" "R26"
			(at 3.05 0.35 270)
			(layer "B.SilkS")
			(effects
				(font
					(size 0.7 0.7)
					(thickness 0.15)
				)
				(justify left bottom mirror)
			)
		)
		(property "Value" "R_0R_0402"
			(at -1.011843 -1.772047 270)
			(layer "B.Fab")
			(effects
				(font
					(size 0.7 0.7)
					(thickness 0.15)
				)
				(justify left bottom mirror)
			)
		)
		(property "Datasheet" "https://industrial.panasonic.com/cdbs/www-data/pdf/RDA0000/AOA0000C301.pdf"
			(at 0 0 90)
			(layer "F.Fab")
			(hide yes)
			(effects
				(font
					(size 1.27 1.27)
					(thickness 0.15)
				)
			)
		)
		(property "Author" "Antmicro"
			(at 277.15 7.65 0)
			(layer "B.Fab")
			(hide yes)
			(effects
				(font
					(size 1 1)
					(thickness 0.15)
				)
				(justify mirror)
			)
		)
		(property "Current" "1A"
			(at 277.15 7.65 0)
			(layer "B.Fab")
			(hide yes)
			(effects
				(font
					(size 1 1)
					(thickness 0.15)
				)
				(justify mirror)
			)
		)
		(property "License" "Apache-2.0"
			(at 277.15 7.65 0)
			(layer "B.Fab")
			(hide yes)
			(effects
				(font
					(size 1 1)
					(thickness 0.15)
				)
				(justify mirror)
			)
		)
		(property "MPN" "ERJ2GE0R00X"
			(at 277.15 7.65 0)
			(layer "B.Fab")
			(hide yes)
			(effects
				(font
					(size 1 1)
					(thickness 0.15)
				)
				(justify mirror)
			)
		)
		(property "Manufacturer" "Panasonic"
			(at 277.15 7.65 0)
			(layer "B.Fab")
			(hide yes)
			(effects
				(font
					(size 1 1)
					(thickness 0.15)
				)
				(justify mirror)
			)
		)
		(property "Tolerance" ""
			(at 277.15 7.65 0)
			(layer "B.Fab")
			(hide yes)
			(effects
				(font
					(size 1 1)
					(thickness 0.15)
				)
				(justify mirror)
			)
		)
		(property "Val" "0R"
			(at 277.15 7.65 0)
			(layer "B.Fab")
			(hide yes)
			(effects
				(font
					(size 1 1)
					(thickness 0.15)
				)
				(justify mirror)
			)
		)
		(sheetname "/DDR5 SODIMM/")
		(sheetfile "ddr5-sodimm.kicad_sch")
		(attr exclude_from_pos_files exclude_from_bom dnp)
		(fp_rect
			(start -0.93 0.47)
			(end 0.93 -0.47)
			(stroke
				(width 0.05)
				(type solid)
			)
			(fill no)
			(layer "B.CrtYd")
		)
		(fp_rect
			(start -0.5 0.25)
			(end 0.5 -0.25)
			(stroke
				(width 0.15)
				(type solid)
			)
			(fill no)
			(layer "B.Fab")
		)
		(pad "1" smd roundrect
			(at -0.485 0 90)
			(size 0.59 0.64)
			(layers "B.Cu" "B.Mask" "B.Paste")
			(roundrect_rratio 0.25)
			(net 1 "GND")
			(pintype "passive")
		)
		(pad "2" smd roundrect
			(at 0.485 0 90)
			(size 0.59 0.64)
			(layers "B.Cu" "B.Mask" "B.Paste")
			(roundrect_rratio 0.25)
			(net 140 "/DDR5 SODIMM/VSS_DET1")
			(pintype "passive")
		)
	)
	(footprint "antmicro-footprints:C_0402_1005Metric"
		(layer "B.Cu")
		(at 131.375501 165.801 -90)
		(descr "Capacitor SMD 0402 (1005 Metric), square (rectangular) end terminal, IPC_7351 nominal, (Body size source: IPC-SM-782 page 76, https://www.pcb-3d.com/wordpress/wp-content/uploads/ipc-sm-782a_amendment_1_and_2.pdf)")
		(tags "capacitor 0402")
		(property "Reference" "C40"
			(at 0 1.17 90)
			(layer "B.SilkS")
			(hide yes)
			(effects
				(font
					(size 0.7 0.7)
					(thickness 0.15)
				)
				(justify left bottom mirror)
			)
		)
		(property "Value" "C_100n_0402"
			(at 0 -1.169 90)
			(layer "B.Fab")
			(effects
				(font
					(size 0.7 0.7)
					(thickness 0.15)
				)
				(justify left bottom mirror)
			)
		)
		(property "Datasheet" "https://www.murata.com/products/productdetail?partno=GRM155R61H104KE14%23"
			(at 0 0 270)
			(layer "F.Fab")
			(hide yes)
			(effects
				(font
					(size 1.27 1.27)
					(thickness 0.15)
				)
			)
		)
		(property "Author" "Antmicro"
			(at -34.425499 297.176501 0)
			(layer "B.Fab")
			(hide yes)
			(effects
				(font
					(size 1 1)
					(thickness 0.15)
				)
				(justify mirror)
			)
		)
		(property "Dielectric" "X5R"
			(at -34.425499 297.176501 0)
			(layer "B.Fab")
			(hide yes)
			(effects
				(font
					(size 1 1)
					(thickness 0.15)
				)
				(justify mirror)
			)
		)
		(property "License" "Apache-2.0"
			(at -34.425499 297.176501 0)
			(layer "B.Fab")
			(hide yes)
			(effects
				(font
					(size 1 1)
					(thickness 0.15)
				)
				(justify mirror)
			)
		)
		(property "MPN" "GRM155R61H104KE14D"
			(at -34.425499 297.176501 0)
			(layer "B.Fab")
			(hide yes)
			(effects
				(font
					(size 1 1)
					(thickness 0.15)
				)
				(justify mirror)
			)
		)
		(property "Manufacturer" "Murata"
			(at -34.425499 297.176501 0)
			(layer "B.Fab")
			(hide yes)
			(effects
				(font
					(size 1 1)
					(thickness 0.15)
				)
				(justify mirror)
			)
		)
		(property "Val" "100n"
			(at -34.425499 297.176501 0)
			(layer "B.Fab")
			(hide yes)
			(effects
				(font
					(size 1 1)
					(thickness 0.15)
				)
				(justify mirror)
			)
		)
		(property "Voltage" "50V"
			(at -34.425499 297.176501 0)
			(layer "B.Fab")
			(hide yes)
			(effects
				(font
					(size 1 1)
					(thickness 0.15)
				)
				(justify mirror)
			)
		)
		(sheetname "/FPGA power/")
		(sheetfile "fpga-power.kicad_sch")
		(attr smd)
		(fp_rect
			(start -0.9656 0.4572)
			(end 0.9652 -0.4828)
			(stroke
				(width 0.05)
				(type solid)
			)
			(fill no)
			(layer "B.CrtYd")
		)
		(fp_line
			(start -0.5 0.25)
			(end 0.498 0.25)
			(stroke
				(width 0.15)
				(type solid)
			)
			(layer "B.Fab")
		)
		(fp_line
			(start 0.498 0.25)
			(end 0.498 -0.248)
			(stroke
				(width 0.15)
				(type solid)
			)
			(layer "B.Fab")
		)
		(fp_line
			(start -0.5 -0.248)
			(end -0.5 0.25)
			(stroke
				(width 0.15)
				(type solid)
			)
			(layer "B.Fab")
		)
		(fp_line
			(start 0.498 -0.248)
			(end -0.5 -0.248)
			(stroke
				(width 0.15)
				(type solid)
			)
			(layer "B.Fab")
		)
		(pad "1" smd roundrect
			(at -0.5 0 180)
			(size 0.6 0.6)
			(layers "B.Cu" "B.Mask" "B.Paste")
			(roundrect_rratio 0.25)
			(net 1 "GND")
			(pintype "passive")
		)
		(pad "2" smd roundrect
			(at 0.498 0 270)
			(size 0.6 0.6)
			(layers "B.Cu" "B.Mask" "B.Paste")
			(roundrect_rratio 0.25)
			(net 200 "+3V3")
			(pintype "passive")
		)
	)
	(footprint "antmicro-footprints:R_0402_1005Metric"
		(layer "B.Cu")
		(at 202.925 187.65 90)
		(descr "Resistor SMD 0402")
		(tags "resistor SMD 0402")
		(property "Reference" "R165"
			(at -1.1 0.325 270)
			(layer "B.SilkS")
			(effects
				(font
					(size 0.7 0.7)
					(thickness 0.15)
				)
				(justify left bottom mirror)
			)
		)
		(property "Value" "R_0R_0402"
			(at -1.011843 -1.772047 270)
			(layer "B.Fab")
			(effects
				(font
					(size 0.7 0.7)
					(thickness 0.15)
				)
				(justify left bottom mirror)
			)
		)
		(property "Datasheet" "https://industrial.panasonic.com/cdbs/www-data/pdf/RDA0000/AOA0000C301.pdf"
			(at 0 0 90)
			(layer "F.Fab")
			(hide yes)
			(effects
				(font
					(size 1.27 1.27)
					(thickness 0.15)
				)
			)
		)
		(property "Author" "Antmicro"
			(at 390.575 -15.275 0)
			(layer "B.Fab")
			(hide yes)
			(effects
				(font
					(size 1 1)
					(thickness 0.15)
				)
				(justify mirror)
			)
		)
		(property "Current" "1A"
			(at 390.575 -15.275 0)
			(layer "B.Fab")
			(hide yes)
			(effects
				(font
					(size 1 1)
					(thickness 0.15)
				)
				(justify mirror)
			)
		)
		(property "License" "Apache-2.0"
			(at 390.575 -15.275 0)
			(layer "B.Fab")
			(hide yes)
			(effects
				(font
					(size 1 1)
					(thickness 0.15)
				)
				(justify mirror)
			)
		)
		(property "MPN" "ERJ2GE0R00X"
			(at 390.575 -15.275 0)
			(layer "B.Fab")
			(hide yes)
			(effects
				(font
					(size 1 1)
					(thickness 0.15)
				)
				(justify mirror)
			)
		)
		(property "Manufacturer" "Panasonic"
			(at 390.575 -15.275 0)
			(layer "B.Fab")
			(hide yes)
			(effects
				(font
					(size 1 1)
					(thickness 0.15)
				)
				(justify mirror)
			)
		)
		(property "Tolerance" ""
			(at 390.575 -15.275 0)
			(layer "B.Fab")
			(hide yes)
			(effects
				(font
					(size 1 1)
					(thickness 0.15)
				)
				(justify mirror)
			)
		)
		(property "Val" "0R"
			(at 390.575 -15.275 0)
			(layer "B.Fab")
			(hide yes)
			(effects
				(font
					(size 1 1)
					(thickness 0.15)
				)
				(justify mirror)
			)
		)
		(sheetname "/Supply/")
		(sheetfile "supply.kicad_sch")
		(attr exclude_from_pos_files exclude_from_bom dnp)
		(fp_rect
			(start -0.93 0.47)
			(end 0.93 -0.47)
			(stroke
				(width 0.05)
				(type solid)
			)
			(fill no)
			(layer "B.CrtYd")
		)
		(fp_rect
			(start -0.5 0.25)
			(end 0.5 -0.25)
			(stroke
				(width 0.15)
				(type solid)
			)
			(fill no)
			(layer "B.Fab")
		)
		(pad "1" smd roundrect
			(at -0.485 0 90)
			(size 0.59 0.64)
			(layers "B.Cu" "B.Mask" "B.Paste")
			(roundrect_rratio 0.25)
			(net 1 "GND")
			(pintype "passive")
		)
		(pad "2" smd roundrect
			(at 0.485 0 90)
			(size 0.59 0.64)
			(layers "B.Cu" "B.Mask" "B.Paste")
			(roundrect_rratio 0.25)
			(net 220 "/Supply/FB4")
			(pintype "passive")
		)
	)
	(footprint "antmicro-footprints:R_0402_1005Metric"
		(layer "B.Cu")
		(at 148.55 142.4 -90)
		(descr "Resistor SMD 0402")
		(tags "resistor SMD 0402")
		(property "Reference" "R38"
			(at -3.044968 -0.354606 90)
			(layer "B.SilkS")
			(effects
				(font
					(size 0.7 0.7)
					(thickness 0.15)
				)
				(justify left bottom mirror)
			)
		)
		(property "Value" "R_0R_0402"
			(at -1.011843 -1.772047 90)
			(layer "B.Fab")
			(effects
				(font
					(size 0.7 0.7)
					(thickness 0.15)
				)
				(justify left bottom mirror)
			)
		)
		(property "Datasheet" "https://industrial.panasonic.com/cdbs/www-data/pdf/RDA0000/AOA0000C301.pdf"
			(at 0 0 270)
			(layer "F.Fab")
			(hide yes)
			(effects
				(font
					(size 1.27 1.27)
					(thickness 0.15)
				)
			)
		)
		(property "Author" "Antmicro"
			(at 6.15 290.95 0)
			(layer "B.Fab")
			(hide yes)
			(effects
				(font
					(size 1 1)
					(thickness 0.15)
				)
				(justify mirror)
			)
		)
		(property "Current" "1A"
			(at 6.15 290.95 0)
			(layer "B.Fab")
			(hide yes)
			(effects
				(font
					(size 1 1)
					(thickness 0.15)
				)
				(justify mirror)
			)
		)
		(property "License" "Apache-2.0"
			(at 6.15 290.95 0)
			(layer "B.Fab")
			(hide yes)
			(effects
				(font
					(size 1 1)
					(thickness 0.15)
				)
				(justify mirror)
			)
		)
		(property "MPN" "ERJ2GE0R00X"
			(at 6.15 290.95 0)
			(layer "B.Fab")
			(hide yes)
			(effects
				(font
					(size 1 1)
					(thickness 0.15)
				)
				(justify mirror)
			)
		)
		(property "Manufacturer" "Panasonic"
			(at 6.15 290.95 0)
			(layer "B.Fab")
			(hide yes)
			(effects
				(font
					(size 1 1)
					(thickness 0.15)
				)
				(justify mirror)
			)
		)
		(property "Tolerance" ""
			(at 6.15 290.95 0)
			(layer "B.Fab")
			(hide yes)
			(effects
				(font
					(size 1 1)
					(thickness 0.15)
				)
				(justify mirror)
			)
		)
		(property "Val" "0R"
			(at 6.15 290.95 0)
			(layer "B.Fab")
			(hide yes)
			(effects
				(font
					(size 1 1)
					(thickness 0.15)
				)
				(justify mirror)
			)
		)
		(sheetname "/DDR5 SODIMM/")
		(sheetfile "ddr5-sodimm.kicad_sch")
		(attr smd)
		(fp_rect
			(start -0.93 0.47)
			(end 0.93 -0.47)
			(stroke
				(width 0.05)
				(type solid)
			)
			(fill no)
			(layer "B.CrtYd")
		)
		(fp_rect
			(start -0.5 0.25)
			(end 0.5 -0.25)
			(stroke
				(width 0.15)
				(type solid)
			)
			(fill no)
			(layer "B.Fab")
		)
		(pad "1" smd roundrect
			(at -0.485 0 270)
			(size 0.59 0.64)
			(layers "B.Cu" "B.Mask" "B.Paste")
			(roundrect_rratio 0.25)
			(net 314 "Net-(J2C-PWR_EN)")
			(pintype "passive")
		)
		(pad "2" smd roundrect
			(at 0.485 0 270)
			(size 0.59 0.64)
			(layers "B.Cu" "B.Mask" "B.Paste")
			(roundrect_rratio 0.25)
			(net 637 "/DDR5 SODIMM/Control.PWR_EN")
			(pintype "passive")
		)
	)
	(footprint "antmicro-footprints:C_0402_1005Metric"
		(layer "B.Cu")
		(at 140.375501 185.801 90)
		(descr "Capacitor SMD 0402 (1005 Metric), square (rectangular) end terminal, IPC_7351 nominal, (Body size source: IPC-SM-782 page 76, https://www.pcb-3d.com/wordpress/wp-content/uploads/ipc-sm-782a_amendment_1_and_2.pdf)")
		(tags "capacitor 0402")
		(property "Reference" "C39"
			(at 0 1.17 270)
			(layer "B.SilkS")
			(hide yes)
			(effects
				(font
					(size 0.7 0.7)
					(thickness 0.15)
				)
				(justify left bottom mirror)
			)
		)
		(property "Value" "C_100n_0402"
			(at 0 -1.169 270)
			(layer "B.Fab")
			(effects
				(font
					(size 0.7 0.7)
					(thickness 0.15)
				)
				(justify left bottom mirror)
			)
		)
		(property "Datasheet" "https://www.murata.com/products/productdetail?partno=GRM155R61H104KE14%23"
			(at 0 0 90)
			(layer "F.Fab")
			(hide yes)
			(effects
				(font
					(size 1.27 1.27)
					(thickness 0.15)
				)
			)
		)
		(property "Author" "Antmicro"
			(at 326.176501 45.425499 0)
			(layer "B.Fab")
			(hide yes)
			(effects
				(font
					(size 1 1)
					(thickness 0.15)
				)
				(justify mirror)
			)
		)
		(property "Dielectric" "X5R"
			(at 326.176501 45.425499 0)
			(layer "B.Fab")
			(hide yes)
			(effects
				(font
					(size 1 1)
					(thickness 0.15)
				)
				(justify mirror)
			)
		)
		(property "License" "Apache-2.0"
			(at 326.176501 45.425499 0)
			(layer "B.Fab")
			(hide yes)
			(effects
				(font
					(size 1 1)
					(thickness 0.15)
				)
				(justify mirror)
			)
		)
		(property "MPN" "GRM155R61H104KE14D"
			(at 326.176501 45.425499 0)
			(layer "B.Fab")
			(hide yes)
			(effects
				(font
					(size 1 1)
					(thickness 0.15)
				)
				(justify mirror)
			)
		)
		(property "Manufacturer" "Murata"
			(at 326.176501 45.425499 0)
			(layer "B.Fab")
			(hide yes)
			(effects
				(font
					(size 1 1)
					(thickness 0.15)
				)
				(justify mirror)
			)
		)
		(property "Val" "100n"
			(at 326.176501 45.425499 0)
			(layer "B.Fab")
			(hide yes)
			(effects
				(font
					(size 1 1)
					(thickness 0.15)
				)
				(justify mirror)
			)
		)
		(property "Voltage" "50V"
			(at 326.176501 45.425499 0)
			(layer "B.Fab")
			(hide yes)
			(effects
				(font
					(size 1 1)
					(thickness 0.15)
				)
				(justify mirror)
			)
		)
		(sheetname "/FPGA power/")
		(sheetfile "fpga-power.kicad_sch")
		(attr smd)
		(fp_rect
			(start -0.9656 0.4572)
			(end 0.9652 -0.4828)
			(stroke
				(width 0.05)
				(type solid)
			)
			(fill no)
			(layer "B.CrtYd")
		)
		(fp_line
			(start 0.498 -0.248)
			(end -0.5 -0.248)
			(stroke
				(width 0.15)
				(type solid)
			)
			(layer "B.Fab")
		)
		(fp_line
			(start -0.5 -0.248)
			(end -0.5 0.25)
			(stroke
				(width 0.15)
				(type solid)
			)
			(layer "B.Fab")
		)
		(fp_line
			(start 0.498 0.25)
			(end 0.498 -0.248)
			(stroke
				(width 0.15)
				(type solid)
			)
			(layer "B.Fab")
		)
		(fp_line
			(start -0.5 0.25)
			(end 0.498 0.25)
			(stroke
				(width 0.15)
				(type solid)
			)
			(layer "B.Fab")
		)
		(pad "1" smd roundrect
			(at -0.5 0)
			(size 0.6 0.6)
			(layers "B.Cu" "B.Mask" "B.Paste")
			(roundrect_rratio 0.25)
			(net 1 "GND")
			(pintype "passive")
		)
		(pad "2" smd roundrect
			(at 0.498 0 90)
			(size 0.6 0.6)
			(layers "B.Cu" "B.Mask" "B.Paste")
			(roundrect_rratio 0.25)
			(net 200 "+3V3")
			(pintype "passive")
		)
	)
	(footprint "antmicro-footprints:R_0402_1005Metric"
		(layer "B.Cu")
		(at 134.875 186.3 180)
		(descr "Resistor SMD 0402 (1005 Metric), square (rectangular) end terminal, IPC_7351 nominal, (Body size source: IPC-SM-782 page 76, https://www.pcb-3d.com/wordpress/wp-content/uploads/ipc-sm-782a_amendment_1_and_2.pdf)")
		(tags "resistor 0402")
		(property "Reference" "R97"
			(at 0 1.17 0)
			(layer "B.SilkS")
			(hide yes)
			(effects
				(font
					(size 0.7 0.7)
					(thickness 0.15)
				)
				(justify left bottom mirror)
			)
		)
		(property "Value" "R_0R_0402"
			(at 0 -1.169 0)
			(layer "B.Fab")
			(effects
				(font
					(size 0.7 0.7)
					(thickness 0.15)
				)
				(justify left bottom mirror)
			)
		)
		(property "Datasheet" "https://industrial.panasonic.com/cdbs/www-data/pdf/RDA0000/AOA0000C301.pdf"
			(at 0 0 180)
			(layer "F.Fab")
			(hide yes)
			(effects
				(font
					(size 1.27 1.27)
					(thickness 0.15)
				)
			)
		)
		(property "Author" "Antmicro"
			(at 269.75 372.6 0)
			(layer "B.Fab")
			(hide yes)
			(effects
				(font
					(size 1 1)
					(thickness 0.15)
				)
				(justify mirror)
			)
		)
		(property "Current" "1A"
			(at 269.75 372.6 0)
			(layer "B.Fab")
			(hide yes)
			(effects
				(font
					(size 1 1)
					(thickness 0.15)
				)
				(justify mirror)
			)
		)
		(property "License" "Apache-2.0"
			(at 269.75 372.6 0)
			(layer "B.Fab")
			(hide yes)
			(effects
				(font
					(size 1 1)
					(thickness 0.15)
				)
				(justify mirror)
			)
		)
		(property "MPN" "ERJ2GE0R00X"
			(at 269.75 372.6 0)
			(layer "B.Fab")
			(hide yes)
			(effects
				(font
					(size 1 1)
					(thickness 0.15)
				)
				(justify mirror)
			)
		)
		(property "Manufacturer" "Panasonic"
			(at 269.75 372.6 0)
			(layer "B.Fab")
			(hide yes)
			(effects
				(font
					(size 1 1)
					(thickness 0.15)
				)
				(justify mirror)
			)
		)
		(property "Tolerance" ""
			(at 269.75 372.6 0)
			(layer "B.Fab")
			(hide yes)
			(effects
				(font
					(size 1 1)
					(thickness 0.15)
				)
				(justify mirror)
			)
		)
		(property "Val" "0R"
			(at 269.75 372.6 0)
			(layer "B.Fab")
			(hide yes)
			(effects
				(font
					(size 1 1)
					(thickness 0.15)
				)
				(justify mirror)
			)
		)
		(sheetname "/FPGA banks unused/")
		(sheetfile "fpga-bank-13-15.kicad_sch")
		(attr smd)
		(fp_line
			(start 0.9652 0.46)
			(end 0.9652 -0.45)
			(stroke
				(width 0.05)
				(type solid)
			)
			(layer "B.CrtYd")
		)
		(fp_line
			(start 0.9652 -0.45)
			(end -0.95 -0.45)
			(stroke
				(width 0.05)
				(type solid)
			)
			(layer "B.CrtYd")
		)
		(fp_line
			(start -0.95 0.46)
			(end 0.9652 0.46)
			(stroke
				(width 0.05)
				(type solid)
			)
			(layer "B.CrtYd")
		)
		(fp_line
			(start -0.95 -0.45)
			(end -0.95 0.46)
			(stroke
				(width 0.05)
				(type solid)
			)
			(layer "B.CrtYd")
		)
		(fp_line
			(start 0.499 0.25)
			(end 0.499 -0.249)
			(stroke
				(width 0.15)
				(type solid)
			)
			(layer "B.Fab")
		)
		(fp_line
			(start 0.499 -0.249)
			(end -0.5 -0.249)
			(stroke
				(width 0.15)
				(type solid)
			)
			(layer "B.Fab")
		)
		(fp_line
			(start -0.5 0.25)
			(end 0.499 0.25)
			(stroke
				(width 0.15)
				(type solid)
			)
			(layer "B.Fab")
		)
		(fp_line
			(start -0.5 -0.249)
			(end -0.5 0.25)
			(stroke
				(width 0.15)
				(type solid)
			)
			(layer "B.Fab")
		)
		(pad "1" smd roundrect
			(at -0.5 0 90)
			(size 0.6 0.6)
			(layers "B.Cu" "B.Mask" "B.Paste")
			(roundrect_rratio 0.25)
			(net 200 "+3V3")
			(pintype "passive")
		)
		(pad "2" smd roundrect
			(at 0.499 0 180)
			(size 0.6 0.6)
			(layers "B.Cu" "B.Mask" "B.Paste")
			(roundrect_rratio 0.25)
			(net 377 "Net-(R97-Pad2)")
			(pintype "passive")
		)
	)
	(footprint "antmicro-footprints:C_0402_1005Metric"
		(layer "B.Cu")
		(at 145.375501 178.801 90)
		(descr "Capacitor SMD 0402 (1005 Metric), square (rectangular) end terminal, IPC_7351 nominal, (Body size source: IPC-SM-782 page 76, https://www.pcb-3d.com/wordpress/wp-content/uploads/ipc-sm-782a_amendment_1_and_2.pdf)")
		(tags "capacitor 0402")
		(property "Reference" "C21"
			(at 0 1.17 270)
			(layer "B.SilkS")
			(hide yes)
			(effects
				(font
					(size 0.7 0.7)
					(thickness 0.15)
				)
				(justify left bottom mirror)
			)
		)
		(property "Value" "C_100n_0402"
			(at 0 -1.169 270)
			(layer "B.Fab")
			(effects
				(font
					(size 0.7 0.7)
					(thickness 0.15)
				)
				(justify left bottom mirror)
			)
		)
		(property "Datasheet" "https://www.murata.com/products/productdetail?partno=GRM155R61H104KE14%23"
			(at 0 0 90)
			(layer "F.Fab")
			(hide yes)
			(effects
				(font
					(size 1.27 1.27)
					(thickness 0.15)
				)
			)
		)
		(property "Author" "Antmicro"
			(at 324.176501 33.425499 0)
			(layer "B.Fab")
			(hide yes)
			(effects
				(font
					(size 1 1)
					(thickness 0.15)
				)
				(justify mirror)
			)
		)
		(property "Dielectric" "X5R"
			(at 324.176501 33.425499 0)
			(layer "B.Fab")
			(hide yes)
			(effects
				(font
					(size 1 1)
					(thickness 0.15)
				)
				(justify mirror)
			)
		)
		(property "License" "Apache-2.0"
			(at 324.176501 33.425499 0)
			(layer "B.Fab")
			(hide yes)
			(effects
				(font
					(size 1 1)
					(thickness 0.15)
				)
				(justify mirror)
			)
		)
		(property "MPN" "GRM155R61H104KE14D"
			(at 324.176501 33.425499 0)
			(layer "B.Fab")
			(hide yes)
			(effects
				(font
					(size 1 1)
					(thickness 0.15)
				)
				(justify mirror)
			)
		)
		(property "Manufacturer" "Murata"
			(at 324.176501 33.425499 0)
			(layer "B.Fab")
			(hide yes)
			(effects
				(font
					(size 1 1)
					(thickness 0.15)
				)
				(justify mirror)
			)
		)
		(property "Val" "100n"
			(at 324.176501 33.425499 0)
			(layer "B.Fab")
			(hide yes)
			(effects
				(font
					(size 1 1)
					(thickness 0.15)
				)
				(justify mirror)
			)
		)
		(property "Voltage" "50V"
			(at 324.176501 33.425499 0)
			(layer "B.Fab")
			(hide yes)
			(effects
				(font
					(size 1 1)
					(thickness 0.15)
				)
				(justify mirror)
			)
		)
		(sheetname "/FPGA power/")
		(sheetfile "fpga-power.kicad_sch")
		(attr smd)
		(fp_rect
			(start -0.9656 0.4572)
			(end 0.9652 -0.4828)
			(stroke
				(width 0.05)
				(type solid)
			)
			(fill no)
			(layer "B.CrtYd")
		)
		(fp_line
			(start 0.498 -0.248)
			(end -0.5 -0.248)
			(stroke
				(width 0.15)
				(type solid)
			)
			(layer "B.Fab")
		)
		(fp_line
			(start -0.5 -0.248)
			(end -0.5 0.25)
			(stroke
				(width 0.15)
				(type solid)
			)
			(layer "B.Fab")
		)
		(fp_line
			(start 0.498 0.25)
			(end 0.498 -0.248)
			(stroke
				(width 0.15)
				(type solid)
			)
			(layer "B.Fab")
		)
		(fp_line
			(start -0.5 0.25)
			(end 0.498 0.25)
			(stroke
				(width 0.15)
				(type solid)
			)
			(layer "B.Fab")
		)
		(pad "1" smd roundrect
			(at -0.5 0)
			(size 0.6 0.6)
			(layers "B.Cu" "B.Mask" "B.Paste")
			(roundrect_rratio 0.25)
			(net 1 "GND")
			(pintype "passive")
		)
		(pad "2" smd roundrect
			(at 0.498 0 90)
			(size 0.6 0.6)
			(layers "B.Cu" "B.Mask" "B.Paste")
			(roundrect_rratio 0.25)
			(net 200 "+3V3")
			(pintype "passive")
		)
	)
	(footprint "antmicro-footprints:C_0402_1005Metric"
		(layer "B.Cu")
		(at 150.875501 166.301)
		(descr "Capacitor SMD 0402 (1005 Metric), square (rectangular) end terminal, IPC_7351 nominal, (Body size source: IPC-SM-782 page 76, https://www.pcb-3d.com/wordpress/wp-content/uploads/ipc-sm-782a_amendment_1_and_2.pdf)")
		(tags "capacitor 0402")
		(property "Reference" "C93"
			(at 0 1.17 180)
			(layer "B.SilkS")
			(hide yes)
			(effects
				(font
					(size 0.7 0.7)
					(thickness 0.15)
				)
				(justify left bottom mirror)
			)
		)
		(property "Value" "C_100n_0402"
			(at 0 -1.169 180)
			(layer "B.Fab")
			(effects
				(font
					(size 0.7 0.7)
					(thickness 0.15)
				)
				(justify left bottom mirror)
			)
		)
		(property "Datasheet" "https://www.murata.com/products/productdetail?partno=GRM155R61H104KE14%23"
			(at 0 0 0)
			(layer "F.Fab")
			(hide yes)
			(effects
				(font
					(size 1.27 1.27)
					(thickness 0.15)
				)
			)
		)
		(property "Author" "Antmicro"
			(at 0 0 0)
			(layer "B.Fab")
			(hide yes)
			(effects
				(font
					(size 1 1)
					(thickness 0.15)
				)
				(justify mirror)
			)
		)
		(property "Dielectric" "X5R"
			(at 0 0 0)
			(layer "B.Fab")
			(hide yes)
			(effects
				(font
					(size 1 1)
					(thickness 0.15)
				)
				(justify mirror)
			)
		)
		(property "License" "Apache-2.0"
			(at 0 0 0)
			(layer "B.Fab")
			(hide yes)
			(effects
				(font
					(size 1 1)
					(thickness 0.15)
				)
				(justify mirror)
			)
		)
		(property "MPN" "GRM155R61H104KE14D"
			(at 0 0 0)
			(layer "B.Fab")
			(hide yes)
			(effects
				(font
					(size 1 1)
					(thickness 0.15)
				)
				(justify mirror)
			)
		)
		(property "Manufacturer" "Murata"
			(at 0 0 0)
			(layer "B.Fab")
			(hide yes)
			(effects
				(font
					(size 1 1)
					(thickness 0.15)
				)
				(justify mirror)
			)
		)
		(property "Val" "100n"
			(at 0 0 0)
			(layer "B.Fab")
			(hide yes)
			(effects
				(font
					(size 1 1)
					(thickness 0.15)
				)
				(justify mirror)
			)
		)
		(property "Voltage" "50V"
			(at 0 0 0)
			(layer "B.Fab")
			(hide yes)
			(effects
				(font
					(size 1 1)
					(thickness 0.15)
				)
				(justify mirror)
			)
		)
		(sheetname "/FPGA power/")
		(sheetfile "fpga-power.kicad_sch")
		(attr smd)
		(fp_rect
			(start -0.9656 0.4572)
			(end 0.9652 -0.4828)
			(stroke
				(width 0.05)
				(type solid)
			)
			(fill no)
			(layer "B.CrtYd")
		)
		(fp_line
			(start -0.5 -0.248)
			(end -0.5 0.25)
			(stroke
				(width 0.15)
				(type solid)
			)
			(layer "B.Fab")
		)
		(fp_line
			(start -0.5 0.25)
			(end 0.498 0.25)
			(stroke
				(width 0.15)
				(type solid)
			)
			(layer "B.Fab")
		)
		(fp_line
			(start 0.498 -0.248)
			(end -0.5 -0.248)
			(stroke
				(width 0.15)
				(type solid)
			)
			(layer "B.Fab")
		)
		(fp_line
			(start 0.498 0.25)
			(end 0.498 -0.248)
			(stroke
				(width 0.15)
				(type solid)
			)
			(layer "B.Fab")
		)
		(pad "1" smd roundrect
			(at -0.5 0 270)
			(size 0.6 0.6)
			(layers "B.Cu" "B.Mask" "B.Paste")
			(roundrect_rratio 0.25)
			(net 1 "GND")
			(pintype "passive")
		)
		(pad "2" smd roundrect
			(at 0.498 0)
			(size 0.6 0.6)
			(layers "B.Cu" "B.Mask" "B.Paste")
			(roundrect_rratio 0.25)
			(net 206 "+1V1")
			(pintype "passive")
		)
	)
	(footprint "antmicro-footprints:TP_SMD_1mm"
		(layer "B.Cu")
		(at 191 168.7 180)
		(property "Reference" "TP64"
			(at -3.3 -0.4 0)
			(layer "B.SilkS")
			(effects
				(font
					(size 0.7 0.7)
					(thickness 0.15)
				)
				(justify left bottom mirror)
			)
		)
		(property "Value" "TP_1mm_SMD"
			(at 0 -1.4 0)
			(layer "B.Fab")
			(effects
				(font
					(size 0.7 0.7)
					(thickness 0.15)
				)
				(justify left bottom mirror)
			)
		)
		(property "MPN" ""
			(at 0 0 0)
			(unlocked yes)
			(layer "B.Fab")
			(hide yes)
			(effects
				(font
					(size 1 1)
					(thickness 0.15)
				)
				(justify mirror)
			)
		)
		(property "Manufacturer" ""
			(at 0 0 0)
			(unlocked yes)
			(layer "B.Fab")
			(hide yes)
			(effects
				(font
					(size 1 1)
					(thickness 0.15)
				)
				(justify mirror)
			)
		)
		(property "Author" "Antmicro"
			(at 0 0 0)
			(unlocked yes)
			(layer "B.Fab")
			(hide yes)
			(effects
				(font
					(size 1 1)
					(thickness 0.15)
				)
				(justify mirror)
			)
		)
		(property "License" "Apache-2.0"
			(at 0 0 0)
			(unlocked yes)
			(layer "B.Fab")
			(hide yes)
			(effects
				(font
					(size 1 1)
					(thickness 0.15)
				)
				(justify mirror)
			)
		)
		(sheetname "/Supply/")
		(sheetfile "supply.kicad_sch")
		(attr exclude_from_pos_files)
		(fp_circle
			(center 0 0)
			(end 0.6 0)
			(stroke
				(width 0.05)
				(type default)
			)
			(fill no)
			(layer "B.CrtYd")
		)
		(fp_text user "Author: Antmicro"
			(at -0.5 -4 0)
			(layer "B.Fab")
			(effects
				(font
					(size 0.7 0.7)
					(thickness 0.15)
				)
				(justify left bottom mirror)
			)
		)
		(fp_text user "License: Apache-2.0"
			(at -0.5 -5.2 0)
			(layer "B.Fab")
			(effects
				(font
					(size 0.7 0.7)
					(thickness 0.15)
				)
				(justify left bottom mirror)
			)
		)
		(fp_text user "${REFERENCE}"
			(at -0.5 -2.8 0)
			(layer "B.Fab")
			(effects
				(font
					(size 0.7 0.7)
					(thickness 0.15)
				)
				(justify left bottom mirror)
			)
		)
		(pad "1" smd circle
			(at 0 0 180)
			(size 1 1)
			(layers "B.Cu" "B.Mask")
			(net 52 "/Supply/3V3_local")
			(pinfunction "1")
			(pintype "passive")
		)
	)
	(footprint "antmicro-footprints:TP_SMD_1mm"
		(layer "B.Cu")
		(at 202.6 174.8 180)
		(property "Reference" "TP63"
			(at 0.6 -0.4 0)
			(layer "B.SilkS")
			(effects
				(font
					(size 0.7 0.7)
					(thickness 0.15)
				)
				(justify left bottom mirror)
			)
		)
		(property "Value" "TP_1mm_SMD"
			(at 0 -1.4 0)
			(layer "B.Fab")
			(effects
				(font
					(size 0.7 0.7)
					(thickness 0.15)
				)
				(justify left bottom mirror)
			)
		)
		(property "MPN" ""
			(at 0 0 0)
			(unlocked yes)
			(layer "B.Fab")
			(hide yes)
			(effects
				(font
					(size 1 1)
					(thickness 0.15)
				)
				(justify mirror)
			)
		)
		(property "Manufacturer" ""
			(at 0 0 0)
			(unlocked yes)
			(layer "B.Fab")
			(hide yes)
			(effects
				(font
					(size 1 1)
					(thickness 0.15)
				)
				(justify mirror)
			)
		)
		(property "Author" "Antmicro"
			(at 0 0 0)
			(unlocked yes)
			(layer "B.Fab")
			(hide yes)
			(effects
				(font
					(size 1 1)
					(thickness 0.15)
				)
				(justify mirror)
			)
		)
		(property "License" "Apache-2.0"
			(at 0 0 0)
			(unlocked yes)
			(layer "B.Fab")
			(hide yes)
			(effects
				(font
					(size 1 1)
					(thickness 0.15)
				)
				(justify mirror)
			)
		)
		(sheetname "/Supply/")
		(sheetfile "supply.kicad_sch")
		(attr exclude_from_pos_files)
		(fp_circle
			(center 0 0)
			(end 0.6 0)
			(stroke
				(width 0.05)
				(type default)
			)
			(fill no)
			(layer "B.CrtYd")
		)
		(fp_text user "Author: Antmicro"
			(at -0.5 -4 0)
			(layer "B.Fab")
			(effects
				(font
					(size 0.7 0.7)
					(thickness 0.15)
				)
				(justify left bottom mirror)
			)
		)
		(fp_text user "${REFERENCE}"
			(at -0.5 -2.8 0)
			(layer "B.Fab")
			(effects
				(font
					(size 0.7 0.7)
					(thickness 0.15)
				)
				(justify left bottom mirror)
			)
		)
		(fp_text user "License: Apache-2.0"
			(at -0.5 -5.2 0)
			(layer "B.Fab")
			(effects
				(font
					(size 0.7 0.7)
					(thickness 0.15)
				)
				(justify left bottom mirror)
			)
		)
		(pad "1" smd circle
			(at 0 0 180)
			(size 1 1)
			(layers "B.Cu" "B.Mask")
			(net 56 "/Supply/1V2_local")
			(pinfunction "1")
			(pintype "passive")
		)
	)
	(footprint "antmicro-footprints:C_0402_1005Metric"
		(layer "B.Cu")
		(at 137.875001 176.3025 180)
		(descr "Capacitor SMD 0402 (1005 Metric), square (rectangular) end terminal, IPC_7351 nominal, (Body size source: IPC-SM-782 page 76, https://www.pcb-3d.com/wordpress/wp-content/uploads/ipc-sm-782a_amendment_1_and_2.pdf)")
		(tags "capacitor 0402")
		(property "Reference" "C86"
			(at 0 1.17 0)
			(layer "B.SilkS")
			(hide yes)
			(effects
				(font
					(size 0.7 0.7)
					(thickness 0.15)
				)
				(justify left bottom mirror)
			)
		)
		(property "Value" "C_100n_0402"
			(at 0 -1.169 0)
			(layer "B.Fab")
			(effects
				(font
					(size 0.7 0.7)
					(thickness 0.15)
				)
				(justify left bottom mirror)
			)
		)
		(property "Datasheet" "https://www.murata.com/products/productdetail?partno=GRM155R61H104KE14%23"
			(at 0 0 180)
			(layer "F.Fab")
			(hide yes)
			(effects
				(font
					(size 1.27 1.27)
					(thickness 0.15)
				)
			)
		)
		(property "Author" "Antmicro"
			(at 275.750002 352.605 0)
			(layer "B.Fab")
			(hide yes)
			(effects
				(font
					(size 1 1)
					(thickness 0.15)
				)
				(justify mirror)
			)
		)
		(property "Dielectric" "X5R"
			(at 275.750002 352.605 0)
			(layer "B.Fab")
			(hide yes)
			(effects
				(font
					(size 1 1)
					(thickness 0.15)
				)
				(justify mirror)
			)
		)
		(property "License" "Apache-2.0"
			(at 275.750002 352.605 0)
			(layer "B.Fab")
			(hide yes)
			(effects
				(font
					(size 1 1)
					(thickness 0.15)
				)
				(justify mirror)
			)
		)
		(property "MPN" "GRM155R61H104KE14D"
			(at 275.750002 352.605 0)
			(layer "B.Fab")
			(hide yes)
			(effects
				(font
					(size 1 1)
					(thickness 0.15)
				)
				(justify mirror)
			)
		)
		(property "Manufacturer" "Murata"
			(at 275.750002 352.605 0)
			(layer "B.Fab")
			(hide yes)
			(effects
				(font
					(size 1 1)
					(thickness 0.15)
				)
				(justify mirror)
			)
		)
		(property "Val" "100n"
			(at 275.750002 352.605 0)
			(layer "B.Fab")
			(hide yes)
			(effects
				(font
					(size 1 1)
					(thickness 0.15)
				)
				(justify mirror)
			)
		)
		(property "Voltage" "50V"
			(at 275.750002 352.605 0)
			(layer "B.Fab")
			(hide yes)
			(effects
				(font
					(size 1 1)
					(thickness 0.15)
				)
				(justify mirror)
			)
		)
		(sheetname "/FPGA power/")
		(sheetfile "fpga-power.kicad_sch")
		(attr smd)
		(fp_rect
			(start -0.9656 0.4572)
			(end 0.9652 -0.4828)
			(stroke
				(width 0.05)
				(type solid)
			)
			(fill no)
			(layer "B.CrtYd")
		)
		(fp_line
			(start 0.498 0.25)
			(end 0.498 -0.248)
			(stroke
				(width 0.15)
				(type solid)
			)
			(layer "B.Fab")
		)
		(fp_line
			(start 0.498 -0.248)
			(end -0.5 -0.248)
			(stroke
				(width 0.15)
				(type solid)
			)
			(layer "B.Fab")
		)
		(fp_line
			(start -0.5 0.25)
			(end 0.498 0.25)
			(stroke
				(width 0.15)
				(type solid)
			)
			(layer "B.Fab")
		)
		(fp_line
			(start -0.5 -0.248)
			(end -0.5 0.25)
			(stroke
				(width 0.15)
				(type solid)
			)
			(layer "B.Fab")
		)
		(pad "1" smd roundrect
			(at -0.5 0 90)
			(size 0.6 0.6)
			(layers "B.Cu" "B.Mask" "B.Paste")
			(roundrect_rratio 0.25)
			(net 1 "GND")
			(pintype "passive")
		)
		(pad "2" smd roundrect
			(at 0.498 0 180)
			(size 0.6 0.6)
			(layers "B.Cu" "B.Mask" "B.Paste")
			(roundrect_rratio 0.25)
			(net 227 "+1V0")
			(pintype "passive")
		)
	)
	(footprint "antmicro-footprints:C_0402_1005Metric"
		(layer "B.Cu")
		(at 82.75 170.25 90)
		(descr "Capacitor SMD 0402")
		(tags "capacitor SMD 0402")
		(property "Reference" "C129"
			(at 0 0.699 270)
			(layer "B.SilkS")
			(hide yes)
			(effects
				(font
					(size 0.7 0.7)
					(thickness 0.15)
				)
				(justify left bottom mirror)
			)
		)
		(property "Value" "C_1u_0402"
			(at -1.022927 -2.155213 270)
			(layer "B.Fab")
			(effects
				(font
					(size 0.7 0.7)
					(thickness 0.15)
				)
				(justify left bottom mirror)
			)
		)
		(property "Datasheet" "https://product.tdk.com/en/search/capacitor/ceramic/mlcc/info?part_no=C1005X6S1A105K050BC"
			(at 0 0 90)
			(layer "F.Fab")
			(hide yes)
			(effects
				(font
					(size 1.27 1.27)
					(thickness 0.15)
				)
			)
		)
		(property "Author" "Antmicro"
			(at 253 87.5 0)
			(layer "B.Fab")
			(hide yes)
			(effects
				(font
					(size 1 1)
					(thickness 0.15)
				)
				(justify mirror)
			)
		)
		(property "Dielectric" ""
			(at 253 87.5 0)
			(layer "B.Fab")
			(hide yes)
			(effects
				(font
					(size 1 1)
					(thickness 0.15)
				)
				(justify mirror)
			)
		)
		(property "License" "Apache-2.0"
			(at 253 87.5 0)
			(layer "B.Fab")
			(hide yes)
			(effects
				(font
					(size 1 1)
					(thickness 0.15)
				)
				(justify mirror)
			)
		)
		(property "MPN" "C1005X6S1A105K050BC"
			(at 253 87.5 0)
			(layer "B.Fab")
			(hide yes)
			(effects
				(font
					(size 1 1)
					(thickness 0.15)
				)
				(justify mirror)
			)
		)
		(property "Manufacturer" "TDK"
			(at 253 87.5 0)
			(layer "B.Fab")
			(hide yes)
			(effects
				(font
					(size 1 1)
					(thickness 0.15)
				)
				(justify mirror)
			)
		)
		(property "Val" "1u"
			(at 253 87.5 0)
			(layer "B.Fab")
			(hide yes)
			(effects
				(font
					(size 1 1)
					(thickness 0.15)
				)
				(justify mirror)
			)
		)
		(property "Voltage" ""
			(at 253 87.5 0)
			(layer "B.Fab")
			(hide yes)
			(effects
				(font
					(size 1 1)
					(thickness 0.15)
				)
				(justify mirror)
			)
		)
		(sheetname "/HDMI + SD Card/")
		(sheetfile "hdmi-sd-card.kicad_sch")
		(attr smd)
		(fp_rect
			(start -0.9659 0.481258)
			(end 0.9649 -0.458742)
			(stroke
				(width 0.05)
				(type solid)
			)
			(fill no)
			(layer "B.CrtYd")
		)
		(fp_line
			(start 0.499 -0.248)
			(end -0.499 -0.248)
			(stroke
				(width 0.15)
				(type solid)
			)
			(layer "B.Fab")
		)
		(fp_line
			(start -0.499 -0.248)
			(end -0.499 0.25)
			(stroke
				(width 0.15)
				(type solid)
			)
			(layer "B.Fab")
		)
		(fp_line
			(start 0.499 0.25)
			(end 0.499 -0.248)
			(stroke
				(width 0.15)
				(type solid)
			)
			(layer "B.Fab")
		)
		(fp_line
			(start -0.499 0.25)
			(end 0.499 0.25)
			(stroke
				(width 0.15)
				(type solid)
			)
			(layer "B.Fab")
		)
		(pad "1" smd roundrect
			(at -0.484 0 90)
			(size 0.59 0.64)
			(layers "B.Cu" "B.Mask" "B.Paste")
			(roundrect_rratio 0.25)
			(net 200 "+3V3")
			(pintype "passive")
		)
		(pad "2" smd roundrect
			(at 0.484 0 90)
			(size 0.59 0.64)
			(layers "B.Cu" "B.Mask" "B.Paste")
			(roundrect_rratio 0.25)
			(net 1 "GND")
			(pintype "passive")
		)
	)
	(footprint "antmicro-footprints:R_0402_1005Metric"
		(layer "B.Cu")
		(at 184.25 189.47 -90)
		(descr "Resistor SMD 0402")
		(tags "resistor SMD 0402")
		(property "Reference" "R36"
			(at -1.47 -1.4 90)
			(layer "B.SilkS")
			(effects
				(font
					(size 0.7 0.7)
					(thickness 0.15)
				)
				(justify left bottom mirror)
			)
		)
		(property "Value" "R_0R_0402"
			(at -1.011843 -1.772046 90)
			(layer "B.Fab")
			(effects
				(font
					(size 0.7 0.7)
					(thickness 0.15)
				)
				(justify left bottom mirror)
			)
		)
		(property "Datasheet" "https://industrial.panasonic.com/cdbs/www-data/pdf/RDA0000/AOA0000C301.pdf"
			(at 0 0 90)
			(layer "B.Fab")
			(hide yes)
			(effects
				(font
					(size 1.27 1.27)
					(thickness 0.15)
				)
				(justify mirror)
			)
		)
		(property "Manufacturer" "Panasonic"
			(at 0 0 90)
			(unlocked yes)
			(layer "B.Fab")
			(hide yes)
			(effects
				(font
					(size 1 1)
					(thickness 0.15)
				)
				(justify mirror)
			)
		)
		(property "MPN" "ERJ2GE0R00X"
			(at 0 0 90)
			(unlocked yes)
			(layer "B.Fab")
			(hide yes)
			(effects
				(font
					(size 1 1)
					(thickness 0.15)
				)
				(justify mirror)
			)
		)
		(property "Val" "0R"
			(at 0 0 90)
			(unlocked yes)
			(layer "B.Fab")
			(hide yes)
			(effects
				(font
					(size 1 1)
					(thickness 0.15)
				)
				(justify mirror)
			)
		)
		(property "License" "Apache-2.0"
			(at 0 0 90)
			(unlocked yes)
			(layer "B.Fab")
			(hide yes)
			(effects
				(font
					(size 1 1)
					(thickness 0.15)
				)
				(justify mirror)
			)
		)
		(property "Author" "Antmicro"
			(at 0 0 90)
			(unlocked yes)
			(layer "B.Fab")
			(hide yes)
			(effects
				(font
					(size 1 1)
					(thickness 0.15)
				)
				(justify mirror)
			)
		)
		(property "Tolerance" ""
			(at 0 0 90)
			(unlocked yes)
			(layer "B.Fab")
			(hide yes)
			(effects
				(font
					(size 1 1)
					(thickness 0.15)
				)
				(justify mirror)
			)
		)
		(property "Current" "1A"
			(at 0 0 90)
			(unlocked yes)
			(layer "B.Fab")
			(hide yes)
			(effects
				(font
					(size 1 1)
					(thickness 0.15)
				)
				(justify mirror)
			)
		)
		(sheetname "/I^{2}C/")
		(sheetfile "i2c.kicad_sch")
		(attr smd)
		(fp_poly
			(pts
				(xy -0.925 0.47) (xy -0.925 -0.47) (xy 0.925 -0.47) (xy 0.925 0.47)
			)
			(stroke
				(width 0.05)
				(type default)
			)
			(fill no)
			(layer "B.CrtYd")
		)
		(fp_poly
			(pts
				(xy -0.5 0.25) (xy -0.5 -0.25) (xy 0.5 -0.25) (xy 0.5 0.25)
			)
			(stroke
				(width 0.15)
				(type solid)
			)
			(fill no)
			(layer "B.Fab")
		)
		(fp_text user "Author: Antmicro"
			(at -0.95 -4.169 90)
			(layer "B.Fab")
			(effects
				(font
					(size 0.7 0.7)
					(thickness 0.15)
				)
				(justify left bottom mirror)
			)
		)
		(fp_text user "License: Apache-2.0"
			(at -0.949999 -5.169 90)
			(layer "B.Fab")
			(effects
				(font
					(size 0.7 0.7)
					(thickness 0.15)
				)
				(justify left bottom mirror)
			)
		)
		(fp_text user "${REFERENCE}"
			(at -0.95 -3.168 90)
			(layer "B.Fab")
			(effects
				(font
					(size 0.7 0.7)
					(thickness 0.15)
				)
				(justify left bottom mirror)
			)
		)
		(pad "1" smd roundrect
			(at -0.48 0 270)
			(size 0.59 0.64)
			(layers "B.Cu" "B.Mask" "B.Paste")
			(roundrect_rratio 0.25)
			(net 690 "/I^{2}C/PWR.SDA")
			(pintype "passive")
		)
		(pad "2" smd roundrect
			(at 0.48 0 270)
			(size 0.59 0.64)
			(layers "B.Cu" "B.Mask" "B.Paste")
			(roundrect_rratio 0.25)
			(net 761 "Net-(U34-SDA)")
			(pintype "passive")
		)
	)
	(footprint "antmicro-footprints:C_0402_1005Metric"
		(layer "B.Cu")
		(at 139.375001 176.8025 90)
		(descr "Capacitor SMD 0402 (1005 Metric), square (rectangular) end terminal, IPC_7351 nominal, (Body size source: IPC-SM-782 page 76, https://www.pcb-3d.com/wordpress/wp-content/uploads/ipc-sm-782a_amendment_1_and_2.pdf)")
		(tags "capacitor 0402")
		(property "Reference" "C65"
			(at 0 1.17 270)
			(layer "B.SilkS")
			(hide yes)
			(effects
				(font
					(size 0.7 0.7)
					(thickness 0.15)
				)
				(justify left bottom mirror)
			)
		)
		(property "Value" "C_100n_0402"
			(at 0 -1.169 270)
			(layer "B.Fab")
			(effects
				(font
					(size 0.7 0.7)
					(thickness 0.15)
				)
				(justify left bottom mirror)
			)
		)
		(property "Datasheet" "https://www.murata.com/products/productdetail?partno=GRM155R61H104KE14%23"
			(at 0 0 90)
			(layer "F.Fab")
			(hide yes)
			(effects
				(font
					(size 1.27 1.27)
					(thickness 0.15)
				)
			)
		)
		(property "Author" "Antmicro"
			(at 316.177501 37.427499 0)
			(layer "B.Fab")
			(hide yes)
			(effects
				(font
					(size 1 1)
					(thickness 0.15)
				)
				(justify mirror)
			)
		)
		(property "Dielectric" "X5R"
			(at 316.177501 37.427499 0)
			(layer "B.Fab")
			(hide yes)
			(effects
				(font
					(size 1 1)
					(thickness 0.15)
				)
				(justify mirror)
			)
		)
		(property "License" "Apache-2.0"
			(at 316.177501 37.427499 0)
			(layer "B.Fab")
			(hide yes)
			(effects
				(font
					(size 1 1)
					(thickness 0.15)
				)
				(justify mirror)
			)
		)
		(property "MPN" "GRM155R61H104KE14D"
			(at 316.177501 37.427499 0)
			(layer "B.Fab")
			(hide yes)
			(effects
				(font
					(size 1 1)
					(thickness 0.15)
				)
				(justify mirror)
			)
		)
		(property "Manufacturer" "Murata"
			(at 316.177501 37.427499 0)
			(layer "B.Fab")
			(hide yes)
			(effects
				(font
					(size 1 1)
					(thickness 0.15)
				)
				(justify mirror)
			)
		)
		(property "Val" "100n"
			(at 316.177501 37.427499 0)
			(layer "B.Fab")
			(hide yes)
			(effects
				(font
					(size 1 1)
					(thickness 0.15)
				)
				(justify mirror)
			)
		)
		(property "Voltage" "50V"
			(at 316.177501 37.427499 0)
			(layer "B.Fab")
			(hide yes)
			(effects
				(font
					(size 1 1)
					(thickness 0.15)
				)
				(justify mirror)
			)
		)
		(sheetname "/FPGA power/")
		(sheetfile "fpga-power.kicad_sch")
		(attr smd)
		(fp_rect
			(start -0.9656 0.4572)
			(end 0.9652 -0.4828)
			(stroke
				(width 0.05)
				(type solid)
			)
			(fill no)
			(layer "B.CrtYd")
		)
		(fp_line
			(start 0.498 -0.248)
			(end -0.5 -0.248)
			(stroke
				(width 0.15)
				(type solid)
			)
			(layer "B.Fab")
		)
		(fp_line
			(start -0.5 -0.248)
			(end -0.5 0.25)
			(stroke
				(width 0.15)
				(type solid)
			)
			(layer "B.Fab")
		)
		(fp_line
			(start 0.498 0.25)
			(end 0.498 -0.248)
			(stroke
				(width 0.15)
				(type solid)
			)
			(layer "B.Fab")
		)
		(fp_line
			(start -0.5 0.25)
			(end 0.498 0.25)
			(stroke
				(width 0.15)
				(type solid)
			)
			(layer "B.Fab")
		)
		(pad "1" smd roundrect
			(at -0.5 0)
			(size 0.6 0.6)
			(layers "B.Cu" "B.Mask" "B.Paste")
			(roundrect_rratio 0.25)
			(net 1 "GND")
			(pintype "passive")
		)
		(pad "2" smd roundrect
			(at 0.498 0 90)
			(size 0.6 0.6)
			(layers "B.Cu" "B.Mask" "B.Paste")
			(roundrect_rratio 0.25)
			(net 227 "+1V0")
			(pintype "passive")
		)
	)
	(footprint "antmicro-footprints:R_0402_1005Metric"
		(layer "B.Cu")
		(at 196.7 161.95 180)
		(descr "Resistor SMD 0402")
		(tags "resistor SMD 0402")
		(property "Reference" "R158"
			(at -1.1 0.7 0)
			(layer "B.SilkS")
			(effects
				(font
					(size 0.7 0.7)
					(thickness 0.15)
				)
				(justify left bottom mirror)
			)
		)
		(property "Value" "R_0R_0402"
			(at -1.011843 -1.772047 0)
			(layer "B.Fab")
			(effects
				(font
					(size 0.7 0.7)
					(thickness 0.15)
				)
				(justify left bottom mirror)
			)
		)
		(property "Datasheet" "https://industrial.panasonic.com/cdbs/www-data/pdf/RDA0000/AOA0000C301.pdf"
			(at 0 0 180)
			(layer "F.Fab")
			(hide yes)
			(effects
				(font
					(size 1.27 1.27)
					(thickness 0.15)
				)
			)
		)
		(property "Author" "Antmicro"
			(at 393.4 323.9 0)
			(layer "B.Fab")
			(hide yes)
			(effects
				(font
					(size 1 1)
					(thickness 0.15)
				)
				(justify mirror)
			)
		)
		(property "Current" "1A"
			(at 393.4 323.9 0)
			(layer "B.Fab")
			(hide yes)
			(effects
				(font
					(size 1 1)
					(thickness 0.15)
				)
				(justify mirror)
			)
		)
		(property "License" "Apache-2.0"
			(at 393.4 323.9 0)
			(layer "B.Fab")
			(hide yes)
			(effects
				(font
					(size 1 1)
					(thickness 0.15)
				)
				(justify mirror)
			)
		)
		(property "MPN" "ERJ2GE0R00X"
			(at 393.4 323.9 0)
			(layer "B.Fab")
			(hide yes)
			(effects
				(font
					(size 1 1)
					(thickness 0.15)
				)
				(justify mirror)
			)
		)
		(property "Manufacturer" "Panasonic"
			(at 393.4 323.9 0)
			(layer "B.Fab")
			(hide yes)
			(effects
				(font
					(size 1 1)
					(thickness 0.15)
				)
				(justify mirror)
			)
		)
		(property "Tolerance" ""
			(at 393.4 323.9 0)
			(layer "B.Fab")
			(hide yes)
			(effects
				(font
					(size 1 1)
					(thickness 0.15)
				)
				(justify mirror)
			)
		)
		(property "Val" "0R"
			(at 393.4 323.9 0)
			(layer "B.Fab")
			(hide yes)
			(effects
				(font
					(size 1 1)
					(thickness 0.15)
				)
				(justify mirror)
			)
		)
		(sheetname "/Supply/")
		(sheetfile "supply.kicad_sch")
		(attr exclude_from_pos_files exclude_from_bom dnp)
		(fp_rect
			(start -0.93 0.47)
			(end 0.93 -0.47)
			(stroke
				(width 0.05)
				(type solid)
			)
			(fill no)
			(layer "B.CrtYd")
		)
		(fp_rect
			(start -0.5 0.25)
			(end 0.5 -0.25)
			(stroke
				(width 0.15)
				(type solid)
			)
			(fill no)
			(layer "B.Fab")
		)
		(pad "1" smd roundrect
			(at -0.485 0 180)
			(size 0.59 0.64)
			(layers "B.Cu" "B.Mask" "B.Paste")
			(roundrect_rratio 0.25)
			(net 1 "GND")
			(pintype "passive")
		)
		(pad "2" smd roundrect
			(at 0.485 0 180)
			(size 0.59 0.64)
			(layers "B.Cu" "B.Mask" "B.Paste")
			(roundrect_rratio 0.25)
			(net 208 "/Supply/FB6")
			(pintype "passive")
		)
	)
	(footprint "antmicro-footprints:TP_SMD_1mm"
		(layer "B.Cu")
		(at 179.4 189.5 180)
		(property "Reference" "TP70"
			(at -3.5 -0.3 0)
			(layer "B.SilkS")
			(effects
				(font
					(size 0.7 0.7)
					(thickness 0.15)
				)
				(justify left bottom mirror)
			)
		)
		(property "Value" "TP_1mm_SMD"
			(at 0 -1.4 0)
			(layer "B.Fab")
			(effects
				(font
					(size 0.7 0.7)
					(thickness 0.15)
				)
				(justify left bottom mirror)
			)
		)
		(property "MPN" ""
			(at 0 0 0)
			(unlocked yes)
			(layer "B.Fab")
			(hide yes)
			(effects
				(font
					(size 1 1)
					(thickness 0.15)
				)
				(justify mirror)
			)
		)
		(property "Manufacturer" ""
			(at 0 0 0)
			(unlocked yes)
			(layer "B.Fab")
			(hide yes)
			(effects
				(font
					(size 1 1)
					(thickness 0.15)
				)
				(justify mirror)
			)
		)
		(property "Author" "Antmicro"
			(at 0 0 0)
			(unlocked yes)
			(layer "B.Fab")
			(hide yes)
			(effects
				(font
					(size 1 1)
					(thickness 0.15)
				)
				(justify mirror)
			)
		)
		(property "License" "Apache-2.0"
			(at 0 0 0)
			(unlocked yes)
			(layer "B.Fab")
			(hide yes)
			(effects
				(font
					(size 1 1)
					(thickness 0.15)
				)
				(justify mirror)
			)
		)
		(sheetname "/I^{2}C/")
		(sheetfile "i2c.kicad_sch")
		(attr exclude_from_pos_files)
		(fp_circle
			(center 0 0)
			(end 0.6 0)
			(stroke
				(width 0.05)
				(type default)
			)
			(fill no)
			(layer "B.CrtYd")
		)
		(fp_text user "Author: Antmicro"
			(at -0.5 -4 0)
			(layer "B.Fab")
			(effects
				(font
					(size 0.7 0.7)
					(thickness 0.15)
				)
				(justify left bottom mirror)
			)
		)
		(fp_text user "${REFERENCE}"
			(at -0.5 -2.8 0)
			(layer "B.Fab")
			(effects
				(font
					(size 0.7 0.7)
					(thickness 0.15)
				)
				(justify left bottom mirror)
			)
		)
		(fp_text user "License: Apache-2.0"
			(at -0.5 -5.2 0)
			(layer "B.Fab")
			(effects
				(font
					(size 0.7 0.7)
					(thickness 0.15)
				)
				(justify left bottom mirror)
			)
		)
		(pad "1" smd circle
			(at 0 0 180)
			(size 1 1)
			(layers "B.Cu" "B.Mask")
			(net 762 "Net-(U34-SCL)")
			(pinfunction "1")
			(pintype "passive")
		)
	)
	(footprint "antmicro-footprints:R_0402_1005Metric"
		(layer "B.Cu")
		(at 108.4 142.4 90)
		(descr "Resistor SMD 0402")
		(tags "resistor SMD 0402")
		(property "Reference" "R32"
			(at 3.044968 0.254606 270)
			(layer "B.SilkS")
			(effects
				(font
					(size 0.7 0.7)
					(thickness 0.15)
				)
				(justify left bottom mirror)
			)
		)
		(property "Value" "R_0R_0402"
			(at -1.011843 -1.772047 270)
			(layer "B.Fab")
			(effects
				(font
					(size 0.7 0.7)
					(thickness 0.15)
				)
				(justify left bottom mirror)
			)
		)
		(property "Datasheet" "https://industrial.panasonic.com/cdbs/www-data/pdf/RDA0000/AOA0000C301.pdf"
			(at 0 0 90)
			(layer "F.Fab")
			(hide yes)
			(effects
				(font
					(size 1.27 1.27)
					(thickness 0.15)
				)
			)
		)
		(property "Author" "Antmicro"
			(at 250.8 34 0)
			(layer "B.Fab")
			(hide yes)
			(effects
				(font
					(size 1 1)
					(thickness 0.15)
				)
				(justify mirror)
			)
		)
		(property "Current" "1A"
			(at 250.8 34 0)
			(layer "B.Fab")
			(hide yes)
			(effects
				(font
					(size 1 1)
					(thickness 0.15)
				)
				(justify mirror)
			)
		)
		(property "License" "Apache-2.0"
			(at 250.8 34 0)
			(layer "B.Fab")
			(hide yes)
			(effects
				(font
					(size 1 1)
					(thickness 0.15)
				)
				(justify mirror)
			)
		)
		(property "MPN" "ERJ2GE0R00X"
			(at 250.8 34 0)
			(layer "B.Fab")
			(hide yes)
			(effects
				(font
					(size 1 1)
					(thickness 0.15)
				)
				(justify mirror)
			)
		)
		(property "Manufacturer" "Panasonic"
			(at 250.8 34 0)
			(layer "B.Fab")
			(hide yes)
			(effects
				(font
					(size 1 1)
					(thickness 0.15)
				)
				(justify mirror)
			)
		)
		(property "Tolerance" ""
			(at 250.8 34 0)
			(layer "B.Fab")
			(hide yes)
			(effects
				(font
					(size 1 1)
					(thickness 0.15)
				)
				(justify mirror)
			)
		)
		(property "Val" "0R"
			(at 250.8 34 0)
			(layer "B.Fab")
			(hide yes)
			(effects
				(font
					(size 1 1)
					(thickness 0.15)
				)
				(justify mirror)
			)
		)
		(sheetname "/DDR5 SODIMM/")
		(sheetfile "ddr5-sodimm.kicad_sch")
		(attr exclude_from_pos_files exclude_from_bom dnp)
		(fp_rect
			(start -0.93 0.47)
			(end 0.93 -0.47)
			(stroke
				(width 0.05)
				(type solid)
			)
			(fill no)
			(layer "B.CrtYd")
		)
		(fp_rect
			(start -0.5 0.25)
			(end 0.5 -0.25)
			(stroke
				(width 0.15)
				(type solid)
			)
			(fill no)
			(layer "B.Fab")
		)
		(pad "1" smd roundrect
			(at -0.485 0 90)
			(size 0.59 0.64)
			(layers "B.Cu" "B.Mask" "B.Paste")
			(roundrect_rratio 0.25)
			(net 1 "GND")
			(pintype "passive")
		)
		(pad "2" smd roundrect
			(at 0.485 0 90)
			(size 0.59 0.64)
			(layers "B.Cu" "B.Mask" "B.Paste")
			(roundrect_rratio 0.25)
			(net 137 "/DDR5 SODIMM/RFU1")
			(pintype "passive")
		)
	)
	(footprint "antmicro-footprints:R_0402_1005Metric"
		(layer "B.Cu")
		(at 195.415 147.851)
		(descr "Resistor SMD 0402")
		(tags "resistor SMD 0402")
		(property "Reference" "R184"
			(at -1.122484 0.772697 180)
			(layer "B.SilkS")
			(hide yes)
			(effects
				(font
					(size 0.7 0.7)
					(thickness 0.15)
				)
				(justify left bottom mirror)
			)
		)
		(property "Value" "R_47k_0402"
			(at -1.011843 -1.772047 180)
			(layer "B.Fab")
			(effects
				(font
					(size 0.7 0.7)
					(thickness 0.15)
				)
				(justify left bottom mirror)
			)
		)
		(property "Datasheet" "https://www.bourns.com/docs/product-datasheets/cr.pdf"
			(at 0 0 0)
			(layer "F.Fab")
			(hide yes)
			(effects
				(font
					(size 1.27 1.27)
					(thickness 0.15)
				)
			)
		)
		(property "Author" "Antmicro"
			(at 0 0 0)
			(layer "B.Fab")
			(hide yes)
			(effects
				(font
					(size 1 1)
					(thickness 0.15)
				)
				(justify mirror)
			)
		)
		(property "License" "Apache-2.0"
			(at 0 0 0)
			(layer "B.Fab")
			(hide yes)
			(effects
				(font
					(size 1 1)
					(thickness 0.15)
				)
				(justify mirror)
			)
		)
		(property "MPN" "CR0402-FX-4702GLF"
			(at 0 0 0)
			(layer "B.Fab")
			(hide yes)
			(effects
				(font
					(size 1 1)
					(thickness 0.15)
				)
				(justify mirror)
			)
		)
		(property "Manufacturer" "Bourns"
			(at 0 0 0)
			(layer "B.Fab")
			(hide yes)
			(effects
				(font
					(size 1 1)
					(thickness 0.15)
				)
				(justify mirror)
			)
		)
		(property "Tolerance" "1%"
			(at 0 0 0)
			(layer "B.Fab")
			(hide yes)
			(effects
				(font
					(size 1 1)
					(thickness 0.15)
				)
				(justify mirror)
			)
		)
		(property "Val" "47k"
			(at 0 0 0)
			(layer "B.Fab")
			(hide yes)
			(effects
				(font
					(size 1 1)
					(thickness 0.15)
				)
				(justify mirror)
			)
		)
		(sheetname "/Supply/")
		(sheetfile "supply.kicad_sch")
		(attr smd)
		(fp_rect
			(start -0.93 0.47)
			(end 0.93 -0.47)
			(stroke
				(width 0.05)
				(type solid)
			)
			(fill no)
			(layer "B.CrtYd")
		)
		(fp_rect
			(start -0.5 0.25)
			(end 0.5 -0.25)
			(stroke
				(width 0.15)
				(type solid)
			)
			(fill no)
			(layer "B.Fab")
		)
		(pad "1" smd roundrect
			(at -0.485 0)
			(size 0.59 0.64)
			(layers "B.Cu" "B.Mask" "B.Paste")
			(roundrect_rratio 0.25)
			(net 221 "/Supply/EN1")
			(pintype "passive")
		)
		(pad "2" smd roundrect
			(at 0.485 0)
			(size 0.59 0.64)
			(layers "B.Cu" "B.Mask" "B.Paste")
			(roundrect_rratio 0.25)
			(net 41 "+3V3_AON")
			(pintype "passive")
		)
	)
	(footprint "antmicro-footprints:R_0402_1005Metric"
		(layer "B.Cu")
		(at 196.953499 152.8535 180)
		(descr "Resistor SMD 0402")
		(tags "resistor SMD 0402")
		(property "Reference" "R140"
			(at -1.122484 0.772697 0)
			(layer "B.SilkS")
			(hide yes)
			(effects
				(font
					(size 0.7 0.7)
					(thickness 0.15)
				)
				(justify left bottom mirror)
			)
		)
		(property "Value" "R_47k_0402"
			(at -1.011843 -1.772047 0)
			(layer "B.Fab")
			(effects
				(font
					(size 0.7 0.7)
					(thickness 0.15)
				)
				(justify left bottom mirror)
			)
		)
		(property "Datasheet" "https://www.bourns.com/docs/product-datasheets/cr.pdf"
			(at 0 0 180)
			(layer "F.Fab")
			(hide yes)
			(effects
				(font
					(size 1.27 1.27)
					(thickness 0.15)
				)
			)
		)
		(property "Author" "Antmicro"
			(at 393.906998 305.707 0)
			(layer "B.Fab")
			(hide yes)
			(effects
				(font
					(size 1 1)
					(thickness 0.15)
				)
				(justify mirror)
			)
		)
		(property "License" "Apache-2.0"
			(at 393.906998 305.707 0)
			(layer "B.Fab")
			(hide yes)
			(effects
				(font
					(size 1 1)
					(thickness 0.15)
				)
				(justify mirror)
			)
		)
		(property "MPN" "CR0402-FX-4702GLF"
			(at 393.906998 305.707 0)
			(layer "B.Fab")
			(hide yes)
			(effects
				(font
					(size 1 1)
					(thickness 0.15)
				)
				(justify mirror)
			)
		)
		(property "Manufacturer" "Bourns"
			(at 393.906998 305.707 0)
			(layer "B.Fab")
			(hide yes)
			(effects
				(font
					(size 1 1)
					(thickness 0.15)
				)
				(justify mirror)
			)
		)
		(property "Tolerance" "1%"
			(at 393.906998 305.707 0)
			(layer "B.Fab")
			(hide yes)
			(effects
				(font
					(size 1 1)
					(thickness 0.15)
				)
				(justify mirror)
			)
		)
		(property "Val" "47k"
			(at 393.906998 305.707 0)
			(layer "B.Fab")
			(hide yes)
			(effects
				(font
					(size 1 1)
					(thickness 0.15)
				)
				(justify mirror)
			)
		)
		(sheetname "/Supply/")
		(sheetfile "supply.kicad_sch")
		(attr smd)
		(fp_rect
			(start -0.93 0.47)
			(end 0.93 -0.47)
			(stroke
				(width 0.05)
				(type solid)
			)
			(fill no)
			(layer "B.CrtYd")
		)
		(fp_rect
			(start -0.5 0.25)
			(end 0.5 -0.25)
			(stroke
				(width 0.15)
				(type solid)
			)
			(fill no)
			(layer "B.Fab")
		)
		(pad "1" smd roundrect
			(at -0.485 0 180)
			(size 0.59 0.64)
			(layers "B.Cu" "B.Mask" "B.Paste")
			(roundrect_rratio 0.25)
			(net 687 "IN2")
			(pintype "passive")
		)
		(pad "2" smd roundrect
			(at 0.485 0 180)
			(size 0.59 0.64)
			(layers "B.Cu" "B.Mask" "B.Paste")
			(roundrect_rratio 0.25)
			(net 41 "+3V3_AON")
			(pintype "passive")
		)
	)
	(footprint "antmicro-footprints:C_0402_1005Metric"
		(layer "B.Cu")
		(at 127.375501 184.801 -90)
		(descr "Capacitor SMD 0402 (1005 Metric), square (rectangular) end terminal, IPC_7351 nominal, (Body size source: IPC-SM-782 page 76, https://www.pcb-3d.com/wordpress/wp-content/uploads/ipc-sm-782a_amendment_1_and_2.pdf)")
		(tags "capacitor 0402")
		(property "Reference" "C47"
			(at 0 1.17 90)
			(layer "B.SilkS")
			(hide yes)
			(effects
				(font
					(size 0.7 0.7)
					(thickness 0.15)
				)
				(justify left bottom mirror)
			)
		)
		(property "Value" "C_100n_0402"
			(at 0 -1.169 90)
			(layer "B.Fab")
			(effects
				(font
					(size 0.7 0.7)
					(thickness 0.15)
				)
				(justify left bottom mirror)
			)
		)
		(property "Datasheet" "https://www.murata.com/products/productdetail?partno=GRM155R61H104KE14%23"
			(at 0 0 270)
			(layer "F.Fab")
			(hide yes)
			(effects
				(font
					(size 1.27 1.27)
					(thickness 0.15)
				)
			)
		)
		(property "Author" "Antmicro"
			(at -57.425499 312.176501 0)
			(layer "B.Fab")
			(hide yes)
			(effects
				(font
					(size 1 1)
					(thickness 0.15)
				)
				(justify mirror)
			)
		)
		(property "Dielectric" "X5R"
			(at -57.425499 312.176501 0)
			(layer "B.Fab")
			(hide yes)
			(effects
				(font
					(size 1 1)
					(thickness 0.15)
				)
				(justify mirror)
			)
		)
		(property "License" "Apache-2.0"
			(at -57.425499 312.176501 0)
			(layer "B.Fab")
			(hide yes)
			(effects
				(font
					(size 1 1)
					(thickness 0.15)
				)
				(justify mirror)
			)
		)
		(property "MPN" "GRM155R61H104KE14D"
			(at -57.425499 312.176501 0)
			(layer "B.Fab")
			(hide yes)
			(effects
				(font
					(size 1 1)
					(thickness 0.15)
				)
				(justify mirror)
			)
		)
		(property "Manufacturer" "Murata"
			(at -57.425499 312.176501 0)
			(layer "B.Fab")
			(hide yes)
			(effects
				(font
					(size 1 1)
					(thickness 0.15)
				)
				(justify mirror)
			)
		)
		(property "Val" "100n"
			(at -57.425499 312.176501 0)
			(layer "B.Fab")
			(hide yes)
			(effects
				(font
					(size 1 1)
					(thickness 0.15)
				)
				(justify mirror)
			)
		)
		(property "Voltage" "50V"
			(at -57.425499 312.176501 0)
			(layer "B.Fab")
			(hide yes)
			(effects
				(font
					(size 1 1)
					(thickness 0.15)
				)
				(justify mirror)
			)
		)
		(sheetname "/FPGA power/")
		(sheetfile "fpga-power.kicad_sch")
		(attr smd)
		(fp_rect
			(start -0.9656 0.4572)
			(end 0.9652 -0.4828)
			(stroke
				(width 0.05)
				(type solid)
			)
			(fill no)
			(layer "B.CrtYd")
		)
		(fp_line
			(start -0.5 0.25)
			(end 0.498 0.25)
			(stroke
				(width 0.15)
				(type solid)
			)
			(layer "B.Fab")
		)
		(fp_line
			(start 0.498 0.25)
			(end 0.498 -0.248)
			(stroke
				(width 0.15)
				(type solid)
			)
			(layer "B.Fab")
		)
		(fp_line
			(start -0.5 -0.248)
			(end -0.5 0.25)
			(stroke
				(width 0.15)
				(type solid)
			)
			(layer "B.Fab")
		)
		(fp_line
			(start 0.498 -0.248)
			(end -0.5 -0.248)
			(stroke
				(width 0.15)
				(type solid)
			)
			(layer "B.Fab")
		)
		(pad "1" smd roundrect
			(at -0.5 0 180)
			(size 0.6 0.6)
			(layers "B.Cu" "B.Mask" "B.Paste")
			(roundrect_rratio 0.25)
			(net 1 "GND")
			(pintype "passive")
		)
		(pad "2" smd roundrect
			(at 0.498 0 270)
			(size 0.6 0.6)
			(layers "B.Cu" "B.Mask" "B.Paste")
			(roundrect_rratio 0.25)
			(net 200 "+3V3")
			(pintype "passive")
		)
	)
	(footprint "antmicro-footprints:C_0402_1005Metric"
		(layer "B.Cu")
		(at 103.34 176.204 90)
		(descr "Capacitor SMD 0402")
		(tags "capacitor SMD 0402")
		(property "Reference" "C235"
			(at 0 0.699 90)
			(layer "B.SilkS")
			(hide yes)
			(effects
				(font
					(size 0.7 0.7)
					(thickness 0.15)
				)
				(justify right bottom mirror)
			)
		)
		(property "Value" "C_100n_0402"
			(at -1.022927 -2.155213 90)
			(layer "B.Fab")
			(effects
				(font
					(size 0.7 0.7)
					(thickness 0.15)
				)
				(justify right bottom mirror)
			)
		)
		(property "Datasheet" "https://www.murata.com/products/productdetail?partno=GRM155R61H104KE14%23"
			(at 0 0 90)
			(layer "F.Fab")
			(hide yes)
			(effects
				(font
					(size 1.27 1.27)
					(thickness 0.15)
				)
			)
		)
		(property "Author" "Antmicro"
			(at 279.544 72.864 0)
			(layer "B.Fab")
			(hide yes)
			(effects
				(font
					(size 1 1)
					(thickness 0.15)
				)
				(justify mirror)
			)
		)
		(property "Dielectric" "X5R"
			(at 279.544 72.864 0)
			(layer "B.Fab")
			(hide yes)
			(effects
				(font
					(size 1 1)
					(thickness 0.15)
				)
				(justify mirror)
			)
		)
		(property "License" "Apache-2.0"
			(at 279.544 72.864 0)
			(layer "B.Fab")
			(hide yes)
			(effects
				(font
					(size 1 1)
					(thickness 0.15)
				)
				(justify mirror)
			)
		)
		(property "MPN" "GRM155R61H104KE14D"
			(at 279.544 72.864 0)
			(layer "B.Fab")
			(hide yes)
			(effects
				(font
					(size 1 1)
					(thickness 0.15)
				)
				(justify mirror)
			)
		)
		(property "Manufacturer" "Murata"
			(at 279.544 72.864 0)
			(layer "B.Fab")
			(hide yes)
			(effects
				(font
					(size 1 1)
					(thickness 0.15)
				)
				(justify mirror)
			)
		)
		(property "Val" "100n"
			(at 279.544 72.864 0)
			(layer "B.Fab")
			(hide yes)
			(effects
				(font
					(size 1 1)
					(thickness 0.15)
				)
				(justify mirror)
			)
		)
		(property "Voltage" "50V"
			(at 279.544 72.864 0)
			(layer "B.Fab")
			(hide yes)
			(effects
				(font
					(size 1 1)
					(thickness 0.15)
				)
				(justify mirror)
			)
		)
		(sheetname "/Debug FTDI/")
		(sheetfile "debug-ftdi.kicad_sch")
		(attr smd)
		(fp_rect
			(start -0.925 0.47)
			(end 0.925 -0.47)
			(stroke
				(width 0.05)
				(type default)
			)
			(fill no)
			(layer "B.CrtYd")
		)
		(fp_line
			(start 0.504 -0.248)
			(end -0.494 -0.248)
			(stroke
				(width 0.15)
				(type solid)
			)
			(layer "B.Fab")
		)
		(fp_line
			(start -0.494 -0.248)
			(end -0.494 0.25)
			(stroke
				(width 0.15)
				(type solid)
			)
			(layer "B.Fab")
		)
		(fp_line
			(start 0.504 0.25)
			(end 0.504 -0.248)
			(stroke
				(width 0.15)
				(type solid)
			)
			(layer "B.Fab")
		)
		(fp_line
			(start -0.494 0.25)
			(end 0.504 0.25)
			(stroke
				(width 0.15)
				(type solid)
			)
			(layer "B.Fab")
		)
		(pad "1" smd roundrect
			(at -0.48 0 90)
			(size 0.59 0.64)
			(layers "B.Cu" "B.Mask" "B.Paste")
			(roundrect_rratio 0.25)
			(net 1 "GND")
			(pintype "passive")
		)
		(pad "2" smd roundrect
			(at 0.48 0 90)
			(size 0.59 0.64)
			(layers "B.Cu" "B.Mask" "B.Paste")
			(roundrect_rratio 0.25)
			(net 6 "/Debug FTDI/FTDI_3V3")
			(pintype "passive")
		)
	)
	(footprint "antmicro-footprints:C_0402_1005Metric"
		(layer "B.Cu")
		(at 142.375501 186.801 -90)
		(descr "Capacitor SMD 0402 (1005 Metric), square (rectangular) end terminal, IPC_7351 nominal, (Body size source: IPC-SM-782 page 76, https://www.pcb-3d.com/wordpress/wp-content/uploads/ipc-sm-782a_amendment_1_and_2.pdf)")
		(tags "capacitor 0402")
		(property "Reference" "C56"
			(at 0 1.17 90)
			(layer "B.SilkS")
			(hide yes)
			(effects
				(font
					(size 0.7 0.7)
					(thickness 0.15)
				)
				(justify left bottom mirror)
			)
		)
		(property "Value" "C_100n_0402"
			(at 0 -1.169 90)
			(layer "B.Fab")
			(effects
				(font
					(size 0.7 0.7)
					(thickness 0.15)
				)
				(justify left bottom mirror)
			)
		)
		(property "Datasheet" "https://www.murata.com/products/productdetail?partno=GRM155R61H104KE14%23"
			(at 0 0 270)
			(layer "F.Fab")
			(hide yes)
			(effects
				(font
					(size 1.27 1.27)
					(thickness 0.15)
				)
			)
		)
		(property "Author" "Antmicro"
			(at -44.425499 329.176501 0)
			(layer "B.Fab")
			(hide yes)
			(effects
				(font
					(size 1 1)
					(thickness 0.15)
				)
				(justify mirror)
			)
		)
		(property "Dielectric" "X5R"
			(at -44.425499 329.176501 0)
			(layer "B.Fab")
			(hide yes)
			(effects
				(font
					(size 1 1)
					(thickness 0.15)
				)
				(justify mirror)
			)
		)
		(property "License" "Apache-2.0"
			(at -44.425499 329.176501 0)
			(layer "B.Fab")
			(hide yes)
			(effects
				(font
					(size 1 1)
					(thickness 0.15)
				)
				(justify mirror)
			)
		)
		(property "MPN" "GRM155R61H104KE14D"
			(at -44.425499 329.176501 0)
			(layer "B.Fab")
			(hide yes)
			(effects
				(font
					(size 1 1)
					(thickness 0.15)
				)
				(justify mirror)
			)
		)
		(property "Manufacturer" "Murata"
			(at -44.425499 329.176501 0)
			(layer "B.Fab")
			(hide yes)
			(effects
				(font
					(size 1 1)
					(thickness 0.15)
				)
				(justify mirror)
			)
		)
		(property "Val" "100n"
			(at -44.425499 329.176501 0)
			(layer "B.Fab")
			(hide yes)
			(effects
				(font
					(size 1 1)
					(thickness 0.15)
				)
				(justify mirror)
			)
		)
		(property "Voltage" "50V"
			(at -44.425499 329.176501 0)
			(layer "B.Fab")
			(hide yes)
			(effects
				(font
					(size 1 1)
					(thickness 0.15)
				)
				(justify mirror)
			)
		)
		(sheetname "/FPGA power/")
		(sheetfile "fpga-power.kicad_sch")
		(attr smd)
		(fp_rect
			(start -0.9656 0.4572)
			(end 0.9652 -0.4828)
			(stroke
				(width 0.05)
				(type solid)
			)
			(fill no)
			(layer "B.CrtYd")
		)
		(fp_line
			(start -0.5 0.25)
			(end 0.498 0.25)
			(stroke
				(width 0.15)
				(type solid)
			)
			(layer "B.Fab")
		)
		(fp_line
			(start 0.498 0.25)
			(end 0.498 -0.248)
			(stroke
				(width 0.15)
				(type solid)
			)
			(layer "B.Fab")
		)
		(fp_line
			(start -0.5 -0.248)
			(end -0.5 0.25)
			(stroke
				(width 0.15)
				(type solid)
			)
			(layer "B.Fab")
		)
		(fp_line
			(start 0.498 -0.248)
			(end -0.5 -0.248)
			(stroke
				(width 0.15)
				(type solid)
			)
			(layer "B.Fab")
		)
		(pad "1" smd roundrect
			(at -0.5 0 180)
			(size 0.6 0.6)
			(layers "B.Cu" "B.Mask" "B.Paste")
			(roundrect_rratio 0.25)
			(net 1 "GND")
			(pintype "passive")
		)
		(pad "2" smd roundrect
			(at 0.498 0 270)
			(size 0.6 0.6)
			(layers "B.Cu" "B.Mask" "B.Paste")
			(roundrect_rratio 0.25)
			(net 200 "+3V3")
			(pintype "passive")
		)
	)
	(footprint "antmicro-footprints:C_0402_1005Metric"
		(layer "B.Cu")
		(at 151.875001 177.3005 180)
		(descr "Capacitor SMD 0402 (1005 Metric), square (rectangular) end terminal, IPC_7351 nominal, (Body size source: IPC-SM-782 page 76, https://www.pcb-3d.com/wordpress/wp-content/uploads/ipc-sm-782a_amendment_1_and_2.pdf)")
		(tags "capacitor 0402")
		(property "Reference" "C105"
			(at 0 1.17 0)
			(layer "B.SilkS")
			(hide yes)
			(effects
				(font
					(size 0.7 0.7)
					(thickness 0.15)
				)
				(justify left bottom mirror)
			)
		)
		(property "Value" "C_100n_0402"
			(at 0 -1.169 0)
			(layer "B.Fab")
			(effects
				(font
					(size 0.7 0.7)
					(thickness 0.15)
				)
				(justify left bottom mirror)
			)
		)
		(property "Datasheet" "https://www.murata.com/products/productdetail?partno=GRM155R61H104KE14%23"
			(at 0 0 180)
			(layer "F.Fab")
			(hide yes)
			(effects
				(font
					(size 1.27 1.27)
					(thickness 0.15)
				)
			)
		)
		(property "Author" "Antmicro"
			(at 303.750002 354.601 0)
			(layer "B.Fab")
			(hide yes)
			(effects
				(font
					(size 1 1)
					(thickness 0.15)
				)
				(justify mirror)
			)
		)
		(property "Dielectric" "X5R"
			(at 303.750002 354.601 0)
			(layer "B.Fab")
			(hide yes)
			(effects
				(font
					(size 1 1)
					(thickness 0.15)
				)
				(justify mirror)
			)
		)
		(property "License" "Apache-2.0"
			(at 303.750002 354.601 0)
			(layer "B.Fab")
			(hide yes)
			(effects
				(font
					(size 1 1)
					(thickness 0.15)
				)
				(justify mirror)
			)
		)
		(property "MPN" "GRM155R61H104KE14D"
			(at 303.750002 354.601 0)
			(layer "B.Fab")
			(hide yes)
			(effects
				(font
					(size 1 1)
					(thickness 0.15)
				)
				(justify mirror)
			)
		)
		(property "Manufacturer" "Murata"
			(at 303.750002 354.601 0)
			(layer "B.Fab")
			(hide yes)
			(effects
				(font
					(size 1 1)
					(thickness 0.15)
				)
				(justify mirror)
			)
		)
		(property "Val" "100n"
			(at 303.750002 354.601 0)
			(layer "B.Fab")
			(hide yes)
			(effects
				(font
					(size 1 1)
					(thickness 0.15)
				)
				(justify mirror)
			)
		)
		(property "Voltage" "50V"
			(at 303.750002 354.601 0)
			(layer "B.Fab")
			(hide yes)
			(effects
				(font
					(size 1 1)
					(thickness 0.15)
				)
				(justify mirror)
			)
		)
		(sheetname "/FPGA power/")
		(sheetfile "fpga-power.kicad_sch")
		(attr smd)
		(fp_rect
			(start -0.9656 0.4572)
			(end 0.9652 -0.4828)
			(stroke
				(width 0.05)
				(type solid)
			)
			(fill no)
			(layer "B.CrtYd")
		)
		(fp_line
			(start 0.498 0.25)
			(end 0.498 -0.248)
			(stroke
				(width 0.15)
				(type solid)
			)
			(layer "B.Fab")
		)
		(fp_line
			(start 0.498 -0.248)
			(end -0.5 -0.248)
			(stroke
				(width 0.15)
				(type solid)
			)
			(layer "B.Fab")
		)
		(fp_line
			(start -0.5 0.25)
			(end 0.498 0.25)
			(stroke
				(width 0.15)
				(type solid)
			)
			(layer "B.Fab")
		)
		(fp_line
			(start -0.5 -0.248)
			(end -0.5 0.25)
			(stroke
				(width 0.15)
				(type solid)
			)
			(layer "B.Fab")
		)
		(pad "1" smd roundrect
			(at -0.5 0 90)
			(size 0.6 0.6)
			(layers "B.Cu" "B.Mask" "B.Paste")
			(roundrect_rratio 0.25)
			(net 1 "GND")
			(pintype "passive")
		)
		(pad "2" smd roundrect
			(at 0.498 0 180)
			(size 0.6 0.6)
			(layers "B.Cu" "B.Mask" "B.Paste")
			(roundrect_rratio 0.25)
			(net 226 "+1V2_MGTAVTT")
			(pintype "passive")
		)
	)
	(footprint "antmicro-footprints:C_0603_1608Metric"
		(layer "B.Cu")
		(at 138.877001 169.4025 -90)
		(descr "Capacitor SMD 0603")
		(tags "capacitor 0603")
		(property "Reference" "C14"
			(at 0 0.9 90)
			(layer "B.SilkS")
			(hide yes)
			(effects
				(font
					(size 0.7 0.7)
					(thickness 0.15)
				)
				(justify left bottom mirror)
			)
		)
		(property "Value" "C_47u_0603"
			(at 0 -1.6 90)
			(layer "B.Fab")
			(effects
				(font
					(size 0.7 0.7)
					(thickness 0.15)
				)
				(justify left bottom mirror)
			)
		)
		(property "Datasheet" "https://www.murata.com/products/productdetail?partno=GRM188R60J476ME15%23"
			(at 0 0 270)
			(layer "F.Fab")
			(hide yes)
			(effects
				(font
					(size 1.27 1.27)
					(thickness 0.15)
				)
			)
		)
		(property "Author" "Antmicro"
			(at -30.525499 308.279501 0)
			(layer "B.Fab")
			(hide yes)
			(effects
				(font
					(size 1 1)
					(thickness 0.15)
				)
				(justify mirror)
			)
		)
		(property "Dielectric" ""
			(at -30.525499 308.279501 0)
			(layer "B.Fab")
			(hide yes)
			(effects
				(font
					(size 1 1)
					(thickness 0.15)
				)
				(justify mirror)
			)
		)
		(property "License" "Apache-2.0"
			(at -30.525499 308.279501 0)
			(layer "B.Fab")
			(hide yes)
			(effects
				(font
					(size 1 1)
					(thickness 0.15)
				)
				(justify mirror)
			)
		)
		(property "MPN" "GRM188R60J476ME15D"
			(at -30.525499 308.279501 0)
			(layer "B.Fab")
			(hide yes)
			(effects
				(font
					(size 1 1)
					(thickness 0.15)
				)
				(justify mirror)
			)
		)
		(property "Manufacturer" "Murata"
			(at -30.525499 308.279501 0)
			(layer "B.Fab")
			(hide yes)
			(effects
				(font
					(size 1 1)
					(thickness 0.15)
				)
				(justify mirror)
			)
		)
		(property "Val" "47u"
			(at -30.525499 308.279501 0)
			(layer "B.Fab")
			(hide yes)
			(effects
				(font
					(size 1 1)
					(thickness 0.15)
				)
				(justify mirror)
			)
		)
		(property "Voltage" ""
			(at -30.525499 308.279501 0)
			(layer "B.Fab")
			(hide yes)
			(effects
				(font
					(size 1 1)
					(thickness 0.15)
				)
				(justify mirror)
			)
		)
		(sheetname "/FPGA power/")
		(sheetfile "fpga-power.kicad_sch")
		(attr smd)
		(fp_line
			(start -0.3 0.3)
			(end 0.3 0.3)
			(stroke
				(width 0.15)
				(type solid)
			)
			(layer "B.SilkS")
		)
		(fp_line
			(start -0.3 -0.3)
			(end 0.3 -0.3)
			(stroke
				(width 0.15)
				(type solid)
			)
			(layer "B.SilkS")
		)
		(fp_rect
			(start -1.24 0.7)
			(end 1.24 -0.7)
			(stroke
				(width 0.05)
				(type solid)
			)
			(fill no)
			(layer "B.CrtYd")
		)
		(fp_rect
			(start -0.8 0.4)
			(end 0.8 -0.4)
			(stroke
				(width 0.15)
				(type solid)
			)
			(fill no)
			(layer "B.Fab")
		)
		(pad "1" smd roundrect
			(at -0.7 0 270)
			(size 0.6 0.8)
			(layers "B.Cu" "B.Mask" "B.Paste")
			(roundrect_rratio 0.2)
			(net 206 "+1V1")
			(pintype "passive")
		)
		(pad "2" smd roundrect
			(at 0.7 0 270)
			(size 0.6 0.8)
			(layers "B.Cu" "B.Mask" "B.Paste")
			(roundrect_rratio 0.2)
			(net 1 "GND")
			(pintype "passive")
		)
	)
	(footprint "antmicro-footprints:C_0402_1005Metric"
		(layer "B.Cu")
		(at 143.875501 165.301)
		(descr "Capacitor SMD 0402 (1005 Metric), square (rectangular) end terminal, IPC_7351 nominal, (Body size source: IPC-SM-782 page 76, https://www.pcb-3d.com/wordpress/wp-content/uploads/ipc-sm-782a_amendment_1_and_2.pdf)")
		(tags "capacitor 0402")
		(property "Reference" "C69"
			(at 0 1.17 180)
			(layer "B.SilkS")
			(hide yes)
			(effects
				(font
					(size 0.7 0.7)
					(thickness 0.15)
				)
				(justify left bottom mirror)
			)
		)
		(property "Value" "C_100n_0402"
			(at 0 -1.169 180)
			(layer "B.Fab")
			(effects
				(font
					(size 0.7 0.7)
					(thickness 0.15)
				)
				(justify left bottom mirror)
			)
		)
		(property "Datasheet" "https://www.murata.com/products/productdetail?partno=GRM155R61H104KE14%23"
			(at 0 0 0)
			(layer "F.Fab")
			(hide yes)
			(effects
				(font
					(size 1.27 1.27)
					(thickness 0.15)
				)
			)
		)
		(property "Author" "Antmicro"
			(at 0 0 0)
			(layer "B.Fab")
			(hide yes)
			(effects
				(font
					(size 1 1)
					(thickness 0.15)
				)
				(justify mirror)
			)
		)
		(property "Dielectric" "X5R"
			(at 0 0 0)
			(layer "B.Fab")
			(hide yes)
			(effects
				(font
					(size 1 1)
					(thickness 0.15)
				)
				(justify mirror)
			)
		)
		(property "License" "Apache-2.0"
			(at 0 0 0)
			(layer "B.Fab")
			(hide yes)
			(effects
				(font
					(size 1 1)
					(thickness 0.15)
				)
				(justify mirror)
			)
		)
		(property "MPN" "GRM155R61H104KE14D"
			(at 0 0 0)
			(layer "B.Fab")
			(hide yes)
			(effects
				(font
					(size 1 1)
					(thickness 0.15)
				)
				(justify mirror)
			)
		)
		(property "Manufacturer" "Murata"
			(at 0 0 0)
			(layer "B.Fab")
			(hide yes)
			(effects
				(font
					(size 1 1)
					(thickness 0.15)
				)
				(justify mirror)
			)
		)
		(property "Val" "100n"
			(at 0 0 0)
			(layer "B.Fab")
			(hide yes)
			(effects
				(font
					(size 1 1)
					(thickness 0.15)
				)
				(justify mirror)
			)
		)
		(property "Voltage" "50V"
			(at 0 0 0)
			(layer "B.Fab")
			(hide yes)
			(effects
				(font
					(size 1 1)
					(thickness 0.15)
				)
				(justify mirror)
			)
		)
		(sheetname "/FPGA power/")
		(sheetfile "fpga-power.kicad_sch")
		(attr smd)
		(fp_rect
			(start -0.9656 0.4572)
			(end 0.9652 -0.4828)
			(stroke
				(width 0.05)
				(type solid)
			)
			(fill no)
			(layer "B.CrtYd")
		)
		(fp_line
			(start -0.5 -0.248)
			(end -0.5 0.25)
			(stroke
				(width 0.15)
				(type solid)
			)
			(layer "B.Fab")
		)
		(fp_line
			(start -0.5 0.25)
			(end 0.498 0.25)
			(stroke
				(width 0.15)
				(type solid)
			)
			(layer "B.Fab")
		)
		(fp_line
			(start 0.498 -0.248)
			(end -0.5 -0.248)
			(stroke
				(width 0.15)
				(type solid)
			)
			(layer "B.Fab")
		)
		(fp_line
			(start 0.498 0.25)
			(end 0.498 -0.248)
			(stroke
				(width 0.15)
				(type solid)
			)
			(layer "B.Fab")
		)
		(pad "1" smd roundrect
			(at -0.5 0 270)
			(size 0.6 0.6)
			(layers "B.Cu" "B.Mask" "B.Paste")
			(roundrect_rratio 0.25)
			(net 1 "GND")
			(pintype "passive")
		)
		(pad "2" smd roundrect
			(at 0.498 0)
			(size 0.6 0.6)
			(layers "B.Cu" "B.Mask" "B.Paste")
			(roundrect_rratio 0.25)
			(net 206 "+1V1")
			(pintype "passive")
		)
	)
	(footprint "antmicro-footprints:TP_SMD_1mm"
		(layer "B.Cu")
		(at 200.4 189.5 180)
		(property "Reference" "TP60"
			(at -1.43 0.68 0)
			(layer "B.SilkS")
			(effects
				(font
					(size 0.7 0.7)
					(thickness 0.15)
				)
				(justify left bottom mirror)
			)
		)
		(property "Value" "TP_1mm_SMD"
			(at 0 -1.4 0)
			(layer "B.Fab")
			(effects
				(font
					(size 0.7 0.7)
					(thickness 0.15)
				)
				(justify left bottom mirror)
			)
		)
		(property "MPN" ""
			(at 0 0 0)
			(unlocked yes)
			(layer "B.Fab")
			(hide yes)
			(effects
				(font
					(size 1 1)
					(thickness 0.15)
				)
				(justify mirror)
			)
		)
		(property "Manufacturer" ""
			(at 0 0 0)
			(unlocked yes)
			(layer "B.Fab")
			(hide yes)
			(effects
				(font
					(size 1 1)
					(thickness 0.15)
				)
				(justify mirror)
			)
		)
		(property "Author" "Antmicro"
			(at 0 0 0)
			(unlocked yes)
			(layer "B.Fab")
			(hide yes)
			(effects
				(font
					(size 1 1)
					(thickness 0.15)
				)
				(justify mirror)
			)
		)
		(property "License" "Apache-2.0"
			(at 0 0 0)
			(unlocked yes)
			(layer "B.Fab")
			(hide yes)
			(effects
				(font
					(size 1 1)
					(thickness 0.15)
				)
				(justify mirror)
			)
		)
		(sheetname "/Supply/")
		(sheetfile "supply.kicad_sch")
		(attr exclude_from_pos_files)
		(fp_circle
			(center 0 0)
			(end 0.6 0)
			(stroke
				(width 0.05)
				(type default)
			)
			(fill no)
			(layer "B.CrtYd")
		)
		(fp_text user "Author: Antmicro"
			(at -0.5 -4 0)
			(layer "B.Fab")
			(effects
				(font
					(size 0.7 0.7)
					(thickness 0.15)
				)
				(justify left bottom mirror)
			)
		)
		(fp_text user "License: Apache-2.0"
			(at -0.5 -5.2 0)
			(layer "B.Fab")
			(effects
				(font
					(size 0.7 0.7)
					(thickness 0.15)
				)
				(justify left bottom mirror)
			)
		)
		(fp_text user "${REFERENCE}"
			(at -0.5 -2.8 0)
			(layer "B.Fab")
			(effects
				(font
					(size 0.7 0.7)
					(thickness 0.15)
				)
				(justify left bottom mirror)
			)
		)
		(pad "1" smd circle
			(at 0 0 180)
			(size 1 1)
			(layers "B.Cu" "B.Mask")
			(net 58 "/Supply/1V7_local")
			(pinfunction "1")
			(pintype "passive")
		)
	)
	(footprint "antmicro-footprints:R_0402_1005Metric"
		(layer "B.Cu")
		(at 123.15 182)
		(descr "Resistor SMD 0402")
		(tags "resistor SMD 0402")
		(property "Reference" "R5"
			(at -1.122484 0.772697 180)
			(layer "B.SilkS")
			(hide yes)
			(effects
				(font
					(size 0.7 0.7)
					(thickness 0.15)
				)
				(justify left bottom mirror)
			)
		)
		(property "Value" "R_4k7_0402"
			(at -1.011843 -1.772047 180)
			(layer "B.Fab")
			(effects
				(font
					(size 0.7 0.7)
					(thickness 0.15)
				)
				(justify left bottom mirror)
			)
		)
		(property "Datasheet" "https://www.bourns.com/docs/product-datasheets/cr.pdf"
			(at 0 0 0)
			(layer "F.Fab")
			(hide yes)
			(effects
				(font
					(size 1.27 1.27)
					(thickness 0.15)
				)
			)
		)
		(property "Author" "Antmicro"
			(at 0 0 0)
			(layer "B.Fab")
			(hide yes)
			(effects
				(font
					(size 1 1)
					(thickness 0.15)
				)
				(justify mirror)
			)
		)
		(property "License" "Apache-2.0"
			(at 0 0 0)
			(layer "B.Fab")
			(hide yes)
			(effects
				(font
					(size 1 1)
					(thickness 0.15)
				)
				(justify mirror)
			)
		)
		(property "MPN" "CR0402-FX-4701GLF"
			(at 0 0 0)
			(layer "B.Fab")
			(hide yes)
			(effects
				(font
					(size 1 1)
					(thickness 0.15)
				)
				(justify mirror)
			)
		)
		(property "Manufacturer" "Bourns"
			(at 0 0 0)
			(layer "B.Fab")
			(hide yes)
			(effects
				(font
					(size 1 1)
					(thickness 0.15)
				)
				(justify mirror)
			)
		)
		(property "Tolerance" "1%"
			(at 0 0 0)
			(layer "B.Fab")
			(hide yes)
			(effects
				(font
					(size 1 1)
					(thickness 0.15)
				)
				(justify mirror)
			)
		)
		(property "Val" "4k7"
			(at 0 0 0)
			(layer "B.Fab")
			(hide yes)
			(effects
				(font
					(size 1 1)
					(thickness 0.15)
				)
				(justify mirror)
			)
		)
		(sheetname "/HyperRAM + QSPI Flash/")
		(sheetfile "hyperram-flash.kicad_sch")
		(attr smd)
		(fp_rect
			(start -0.93 0.47)
			(end 0.93 -0.47)
			(stroke
				(width 0.05)
				(type solid)
			)
			(fill no)
			(layer "B.CrtYd")
		)
		(fp_rect
			(start -0.5 0.25)
			(end 0.5 -0.25)
			(stroke
				(width 0.15)
				(type solid)
			)
			(fill no)
			(layer "B.Fab")
		)
		(pad "1" smd roundrect
			(at -0.485 0)
			(size 0.59 0.64)
			(layers "B.Cu" "B.Mask" "B.Paste")
			(roundrect_rratio 0.25)
			(net 200 "+3V3")
			(pintype "passive")
		)
		(pad "2" smd roundrect
			(at 0.485 0)
			(size 0.59 0.64)
			(layers "B.Cu" "B.Mask" "B.Paste")
			(roundrect_rratio 0.25)
			(net 361 "/HyperRAM + QSPI Flash/IO2")
			(pintype "passive")
		)
	)
	(footprint "antmicro-footprints:C_0402_1005Metric"
		(layer "B.Cu")
		(at 141.85 160.7)
		(descr "Capacitor SMD 0402")
		(tags "capacitor SMD 0402")
		(property "Reference" "C168"
			(at 0 0.699 180)
			(layer "B.SilkS")
			(hide yes)
			(effects
				(font
					(size 0.7 0.7)
					(thickness 0.15)
				)
				(justify left bottom mirror)
			)
		)
		(property "Value" "C_100n_0402"
			(at -1.022927 -2.155213 180)
			(layer "B.Fab")
			(effects
				(font
					(size 0.7 0.7)
					(thickness 0.15)
				)
				(justify left bottom mirror)
			)
		)
		(property "Datasheet" "https://www.murata.com/products/productdetail?partno=GRM155R61H104KE14%23"
			(at 0 0 0)
			(layer "F.Fab")
			(hide yes)
			(effects
				(font
					(size 1.27 1.27)
					(thickness 0.15)
				)
			)
		)
		(property "Author" "Antmicro"
			(at 0 0 0)
			(layer "B.Fab")
			(hide yes)
			(effects
				(font
					(size 1 1)
					(thickness 0.15)
				)
				(justify mirror)
			)
		)
		(property "Dielectric" "X5R"
			(at 0 0 0)
			(layer "B.Fab")
			(hide yes)
			(effects
				(font
					(size 1 1)
					(thickness 0.15)
				)
				(justify mirror)
			)
		)
		(property "License" "Apache-2.0"
			(at 0 0 0)
			(layer "B.Fab")
			(hide yes)
			(effects
				(font
					(size 1 1)
					(thickness 0.15)
				)
				(justify mirror)
			)
		)
		(property "MPN" "GRM155R61H104KE14D"
			(at 0 0 0)
			(layer "B.Fab")
			(hide yes)
			(effects
				(font
					(size 1 1)
					(thickness 0.15)
				)
				(justify mirror)
			)
		)
		(property "Manufacturer" "Murata"
			(at 0 0 0)
			(layer "B.Fab")
			(hide yes)
			(effects
				(font
					(size 1 1)
					(thickness 0.15)
				)
				(justify mirror)
			)
		)
		(property "Val" "100n"
			(at 0 0 0)
			(layer "B.Fab")
			(hide yes)
			(effects
				(font
					(size 1 1)
					(thickness 0.15)
				)
				(justify mirror)
			)
		)
		(property "Voltage" "50V"
			(at 0 0 0)
			(layer "B.Fab")
			(hide yes)
			(effects
				(font
					(size 1 1)
					(thickness 0.15)
				)
				(justify mirror)
			)
		)
		(sheetname "/FPGA banks HP/")
		(sheetfile "fpga-banks-32-34.kicad_sch")
		(attr smd)
		(fp_rect
			(start -0.9659 0.481258)
			(end 0.9649 -0.458742)
			(stroke
				(width 0.05)
				(type solid)
			)
			(fill no)
			(layer "B.CrtYd")
		)
		(fp_line
			(start -0.499 -0.248)
			(end -0.499 0.25)
			(stroke
				(width 0.15)
				(type solid)
			)
			(layer "B.Fab")
		)
		(fp_line
			(start -0.499 0.25)
			(end 0.499 0.25)
			(stroke
				(width 0.15)
				(type solid)
			)
			(layer "B.Fab")
		)
		(fp_line
			(start 0.499 -0.248)
			(end -0.499 -0.248)
			(stroke
				(width 0.15)
				(type solid)
			)
			(layer "B.Fab")
		)
		(fp_line
			(start 0.499 0.25)
			(end 0.499 -0.248)
			(stroke
				(width 0.15)
				(type solid)
			)
			(layer "B.Fab")
		)
		(pad "1" smd roundrect
			(at -0.484 0)
			(size 0.59 0.64)
			(layers "B.Cu" "B.Mask" "B.Paste")
			(roundrect_rratio 0.25)
			(net 10 "/FPGA banks HP/VREF")
			(pintype "passive")
		)
		(pad "2" smd roundrect
			(at 0.484 0)
			(size 0.59 0.64)
			(layers "B.Cu" "B.Mask" "B.Paste")
			(roundrect_rratio 0.25)
			(net 1 "GND")
			(pintype "passive")
		)
	)
	(footprint "antmicro-footprints:C_0603_1608Metric"
		(layer "B.Cu")
		(at 132.100501 174.776)
		(descr "Capacitor SMD 0603")
		(tags "capacitor 0603")
		(property "Reference" "C17"
			(at 0 0.9 0)
			(layer "B.SilkS")
			(hide yes)
			(effects
				(font
					(size 0.7 0.7)
					(thickness 0.15)
				)
				(justify right bottom mirror)
			)
		)
		(property "Value" "C_47u_0603"
			(at 0 -1.6 0)
			(layer "B.Fab")
			(effects
				(font
					(size 0.7 0.7)
					(thickness 0.15)
				)
				(justify right bottom mirror)
			)
		)
		(property "Datasheet" "https://www.murata.com/products/productdetail?partno=GRM188R60J476ME15%23"
			(at 0 0 0)
			(layer "F.Fab")
			(hide yes)
			(effects
				(font
					(size 1.27 1.27)
					(thickness 0.15)
				)
			)
		)
		(property "Author" "Antmicro"
			(at 0 0 0)
			(layer "B.Fab")
			(hide yes)
			(effects
				(font
					(size 1 1)
					(thickness 0.15)
				)
				(justify mirror)
			)
		)
		(property "Dielectric" ""
			(at 0 0 0)
			(layer "B.Fab")
			(hide yes)
			(effects
				(font
					(size 1 1)
					(thickness 0.15)
				)
				(justify mirror)
			)
		)
		(property "License" "Apache-2.0"
			(at 0 0 0)
			(layer "B.Fab")
			(hide yes)
			(effects
				(font
					(size 1 1)
					(thickness 0.15)
				)
				(justify mirror)
			)
		)
		(property "MPN" "GRM188R60J476ME15D"
			(at 0 0 0)
			(layer "B.Fab")
			(hide yes)
			(effects
				(font
					(size 1 1)
					(thickness 0.15)
				)
				(justify mirror)
			)
		)
		(property "Manufacturer" "Murata"
			(at 0 0 0)
			(layer "B.Fab")
			(hide yes)
			(effects
				(font
					(size 1 1)
					(thickness 0.15)
				)
				(justify mirror)
			)
		)
		(property "Val" "47u"
			(at 0 0 0)
			(layer "B.Fab")
			(hide yes)
			(effects
				(font
					(size 1 1)
					(thickness 0.15)
				)
				(justify mirror)
			)
		)
		(property "Voltage" ""
			(at 0 0 0)
			(layer "B.Fab")
			(hide yes)
			(effects
				(font
					(size 1 1)
					(thickness 0.15)
				)
				(justify mirror)
			)
		)
		(sheetname "/FPGA power/")
		(sheetfile "fpga-power.kicad_sch")
		(attr smd)
		(fp_line
			(start -0.3 -0.3)
			(end 0.3 -0.3)
			(stroke
				(width 0.15)
				(type solid)
			)
			(layer "B.SilkS")
		)
		(fp_line
			(start -0.3 0.3)
			(end 0.3 0.3)
			(stroke
				(width 0.15)
				(type solid)
			)
			(layer "B.SilkS")
		)
		(fp_rect
			(start -1.24 0.7)
			(end 1.24 -0.7)
			(stroke
				(width 0.05)
				(type solid)
			)
			(fill no)
			(layer "B.CrtYd")
		)
		(fp_rect
			(start -0.8 0.4)
			(end 0.8 -0.4)
			(stroke
				(width 0.15)
				(type solid)
			)
			(fill no)
			(layer "B.Fab")
		)
		(pad "1" smd roundrect
			(at -0.7 0)
			(size 0.6 0.8)
			(layers "B.Cu" "B.Mask" "B.Paste")
			(roundrect_rratio 0.2)
			(net 200 "+3V3")
			(pintype "passive")
		)
		(pad "2" smd roundrect
			(at 0.7 0)
			(size 0.6 0.8)
			(layers "B.Cu" "B.Mask" "B.Paste")
			(roundrect_rratio 0.2)
			(net 1 "GND")
			(pintype "passive")
		)
	)
	(footprint "antmicro-footprints:TP_SMD_1mm"
		(layer "B.Cu")
		(at 189.1 177 180)
		(property "Reference" "TP59"
			(at 0.6 -0.5 0)
			(layer "B.SilkS")
			(effects
				(font
					(size 0.7 0.7)
					(thickness 0.15)
				)
				(justify left bottom mirror)
			)
		)
		(property "Value" "TP_1mm_SMD"
			(at 0 -1.4 0)
			(layer "B.Fab")
			(effects
				(font
					(size 0.7 0.7)
					(thickness 0.15)
				)
				(justify left bottom mirror)
			)
		)
		(property "MPN" ""
			(at 0 0 0)
			(unlocked yes)
			(layer "B.Fab")
			(hide yes)
			(effects
				(font
					(size 1 1)
					(thickness 0.15)
				)
				(justify mirror)
			)
		)
		(property "Manufacturer" ""
			(at 0 0 0)
			(unlocked yes)
			(layer "B.Fab")
			(hide yes)
			(effects
				(font
					(size 1 1)
					(thickness 0.15)
				)
				(justify mirror)
			)
		)
		(property "Author" "Antmicro"
			(at 0 0 0)
			(unlocked yes)
			(layer "B.Fab")
			(hide yes)
			(effects
				(font
					(size 1 1)
					(thickness 0.15)
				)
				(justify mirror)
			)
		)
		(property "License" "Apache-2.0"
			(at 0 0 0)
			(unlocked yes)
			(layer "B.Fab")
			(hide yes)
			(effects
				(font
					(size 1 1)
					(thickness 0.15)
				)
				(justify mirror)
			)
		)
		(sheetname "/Supply/")
		(sheetfile "supply.kicad_sch")
		(attr exclude_from_pos_files)
		(fp_circle
			(center 0 0)
			(end 0.6 0)
			(stroke
				(width 0.05)
				(type default)
			)
			(fill no)
			(layer "B.CrtYd")
		)
		(fp_text user "License: Apache-2.0"
			(at -0.5 -5.2 0)
			(layer "B.Fab")
			(effects
				(font
					(size 0.7 0.7)
					(thickness 0.15)
				)
				(justify left bottom mirror)
			)
		)
		(fp_text user "Author: Antmicro"
			(at -0.5 -4 0)
			(layer "B.Fab")
			(effects
				(font
					(size 0.7 0.7)
					(thickness 0.15)
				)
				(justify left bottom mirror)
			)
		)
		(fp_text user "${REFERENCE}"
			(at -0.5 -2.8 0)
			(layer "B.Fab")
			(effects
				(font
					(size 0.7 0.7)
					(thickness 0.15)
				)
				(justify left bottom mirror)
			)
		)
		(pad "1" smd circle
			(at 0 0 180)
			(size 1 1)
			(layers "B.Cu" "B.Mask")
			(net 51 "/Supply/1V8_local")
			(pinfunction "1")
			(pintype "passive")
		)
	)
	(footprint "antmicro-footprints:TP_SMD_1mm"
		(layer "B.Cu")
		(at 103.362904 187.9 90)
		(property "Reference" "TP54"
			(at -3.68 -0.272904 90)
			(layer "B.SilkS")
			(effects
				(font
					(size 0.7 0.7)
					(thickness 0.15)
				)
				(justify right top mirror)
			)
		)
		(property "Value" "TP_1mm_SMD"
			(at 0 -1.4 90)
			(layer "B.Fab")
			(effects
				(font
					(size 0.7 0.7)
					(thickness 0.15)
				)
				(justify right top mirror)
			)
		)
		(property "MPN" ""
			(at 0 0 270)
			(unlocked yes)
			(layer "B.Fab")
			(hide yes)
			(effects
				(font
					(size 1 1)
					(thickness 0.15)
				)
				(justify mirror)
			)
		)
		(property "Manufacturer" ""
			(at 0 0 270)
			(unlocked yes)
			(layer "B.Fab")
			(hide yes)
			(effects
				(font
					(size 1 1)
					(thickness 0.15)
				)
				(justify mirror)
			)
		)
		(property "Author" "Antmicro"
			(at 0 0 270)
			(unlocked yes)
			(layer "B.Fab")
			(hide yes)
			(effects
				(font
					(size 1 1)
					(thickness 0.15)
				)
				(justify mirror)
			)
		)
		(property "License" "Apache-2.0"
			(at 0 0 270)
			(unlocked yes)
			(layer "B.Fab")
			(hide yes)
			(effects
				(font
					(size 1 1)
					(thickness 0.15)
				)
				(justify mirror)
			)
		)
		(sheetname "/Debug FTDI/")
		(sheetfile "debug-ftdi.kicad_sch")
		(attr exclude_from_pos_files)
		(fp_circle
			(center 0 0)
			(end 0.6 0)
			(stroke
				(width 0.05)
				(type default)
			)
			(fill no)
			(layer "B.CrtYd")
		)
		(fp_text user "${REFERENCE}"
			(at -0.5 -2.8 90)
			(layer "B.Fab")
			(effects
				(font
					(size 0.7 0.7)
					(thickness 0.15)
				)
				(justify right top mirror)
			)
		)
		(fp_text user "Author: Antmicro"
			(at -0.5 -4 90)
			(layer "B.Fab")
			(effects
				(font
					(size 0.7 0.7)
					(thickness 0.15)
				)
				(justify right top mirror)
			)
		)
		(fp_text user "License: Apache-2.0"
			(at -0.5 -5.2 90)
			(layer "B.Fab")
			(effects
				(font
					(size 0.7 0.7)
					(thickness 0.15)
				)
				(justify right top mirror)
			)
		)
		(pad "1" smd circle
			(at 0 0 90)
			(size 1 1)
			(layers "B.Cu" "B.Mask")
			(net 672 "/Debug FTDI/FTDI.SDA")
			(pinfunction "1")
			(pintype "passive")
		)
	)
	(footprint "antmicro-footprints:C_0402_1005Metric"
		(layer "B.Cu")
		(at 134.375501 169.801 90)
		(descr "Capacitor SMD 0402 (1005 Metric), square (rectangular) end terminal, IPC_7351 nominal, (Body size source: IPC-SM-782 page 76, https://www.pcb-3d.com/wordpress/wp-content/uploads/ipc-sm-782a_amendment_1_and_2.pdf)")
		(tags "capacitor 0402")
		(property "Reference" "C44"
			(at 0 1.17 270)
			(layer "B.SilkS")
			(hide yes)
			(effects
				(font
					(size 0.7 0.7)
					(thickness 0.15)
				)
				(justify left bottom mirror)
			)
		)
		(property "Value" "C_100n_0402"
			(at 0 -1.169 270)
			(layer "B.Fab")
			(effects
				(font
					(size 0.7 0.7)
					(thickness 0.15)
				)
				(justify left bottom mirror)
			)
		)
		(property "Datasheet" "https://www.murata.com/products/productdetail?partno=GRM155R61H104KE14%23"
			(at 0 0 90)
			(layer "F.Fab")
			(hide yes)
			(effects
				(font
					(size 1.27 1.27)
					(thickness 0.15)
				)
			)
		)
		(property "Author" "Antmicro"
			(at 304.176501 35.425499 0)
			(layer "B.Fab")
			(hide yes)
			(effects
				(font
					(size 1 1)
					(thickness 0.15)
				)
				(justify mirror)
			)
		)
		(property "Dielectric" "X5R"
			(at 304.176501 35.425499 0)
			(layer "B.Fab")
			(hide yes)
			(effects
				(font
					(size 1 1)
					(thickness 0.15)
				)
				(justify mirror)
			)
		)
		(property "License" "Apache-2.0"
			(at 304.176501 35.425499 0)
			(layer "B.Fab")
			(hide yes)
			(effects
				(font
					(size 1 1)
					(thickness 0.15)
				)
				(justify mirror)
			)
		)
		(property "MPN" "GRM155R61H104KE14D"
			(at 304.176501 35.425499 0)
			(layer "B.Fab")
			(hide yes)
			(effects
				(font
					(size 1 1)
					(thickness 0.15)
				)
				(justify mirror)
			)
		)
		(property "Manufacturer" "Murata"
			(at 304.176501 35.425499 0)
			(layer "B.Fab")
			(hide yes)
			(effects
				(font
					(size 1 1)
					(thickness 0.15)
				)
				(justify mirror)
			)
		)
		(property "Val" "100n"
			(at 304.176501 35.425499 0)
			(layer "B.Fab")
			(hide yes)
			(effects
				(font
					(size 1 1)
					(thickness 0.15)
				)
				(justify mirror)
			)
		)
		(property "Voltage" "50V"
			(at 304.176501 35.425499 0)
			(layer "B.Fab")
			(hide yes)
			(effects
				(font
					(size 1 1)
					(thickness 0.15)
				)
				(justify mirror)
			)
		)
		(sheetname "/FPGA power/")
		(sheetfile "fpga-power.kicad_sch")
		(attr smd)
		(fp_rect
			(start -0.9656 0.4572)
			(end 0.9652 -0.4828)
			(stroke
				(width 0.05)
				(type solid)
			)
			(fill no)
			(layer "B.CrtYd")
		)
		(fp_line
			(start 0.498 -0.248)
			(end -0.5 -0.248)
			(stroke
				(width 0.15)
				(type solid)
			)
			(layer "B.Fab")
		)
		(fp_line
			(start -0.5 -0.248)
			(end -0.5 0.25)
			(stroke
				(width 0.15)
				(type solid)
			)
			(layer "B.Fab")
		)
		(fp_line
			(start 0.498 0.25)
			(end 0.498 -0.248)
			(stroke
				(width 0.15)
				(type solid)
			)
			(layer "B.Fab")
		)
		(fp_line
			(start -0.5 0.25)
			(end 0.498 0.25)
			(stroke
				(width 0.15)
				(type solid)
			)
			(layer "B.Fab")
		)
		(pad "1" smd roundrect
			(at -0.5 0)
			(size 0.6 0.6)
			(layers "B.Cu" "B.Mask" "B.Paste")
			(roundrect_rratio 0.25)
			(net 1 "GND")
			(pintype "passive")
		)
		(pad "2" smd roundrect
			(at 0.498 0 90)
			(size 0.6 0.6)
			(layers "B.Cu" "B.Mask" "B.Paste")
			(roundrect_rratio 0.25)
			(net 206 "+1V1")
			(pintype "passive")
		)
	)
	(footprint "antmicro-footprints:R_0402_1005Metric"
		(layer "B.Cu")
		(at 180.8 198.4 180)
		(descr "Resistor SMD 0402")
		(tags "resistor SMD 0402")
		(property "Reference" "R175"
			(at -3.95 -0.5 0)
			(layer "B.SilkS")
			(effects
				(font
					(size 0.7 0.7)
					(thickness 0.15)
				)
				(justify left bottom mirror)
			)
		)
		(property "Value" "R_0R_0402"
			(at -1.011843 -1.772047 0)
			(layer "B.Fab")
			(effects
				(font
					(size 0.7 0.7)
					(thickness 0.15)
				)
				(justify left bottom mirror)
			)
		)
		(property "Datasheet" "https://industrial.panasonic.com/cdbs/www-data/pdf/RDA0000/AOA0000C301.pdf"
			(at 0 0 180)
			(layer "F.Fab")
			(hide yes)
			(effects
				(font
					(size 1.27 1.27)
					(thickness 0.15)
				)
			)
		)
		(property "Author" "Antmicro"
			(at 361.6 396.8 0)
			(layer "B.Fab")
			(hide yes)
			(effects
				(font
					(size 1 1)
					(thickness 0.15)
				)
				(justify mirror)
			)
		)
		(property "Current" "1A"
			(at 361.6 396.8 0)
			(layer "B.Fab")
			(hide yes)
			(effects
				(font
					(size 1 1)
					(thickness 0.15)
				)
				(justify mirror)
			)
		)
		(property "License" "Apache-2.0"
			(at 361.6 396.8 0)
			(layer "B.Fab")
			(hide yes)
			(effects
				(font
					(size 1 1)
					(thickness 0.15)
				)
				(justify mirror)
			)
		)
		(property "MPN" "ERJ2GE0R00X"
			(at 361.6 396.8 0)
			(layer "B.Fab")
			(hide yes)
			(effects
				(font
					(size 1 1)
					(thickness 0.15)
				)
				(justify mirror)
			)
		)
		(property "Manufacturer" "Panasonic"
			(at 361.6 396.8 0)
			(layer "B.Fab")
			(hide yes)
			(effects
				(font
					(size 1 1)
					(thickness 0.15)
				)
				(justify mirror)
			)
		)
		(property "Tolerance" ""
			(at 361.6 396.8 0)
			(layer "B.Fab")
			(hide yes)
			(effects
				(font
					(size 1 1)
					(thickness 0.15)
				)
				(justify mirror)
			)
		)
		(property "Val" "0R"
			(at 361.6 396.8 0)
			(layer "B.Fab")
			(hide yes)
			(effects
				(font
					(size 1 1)
					(thickness 0.15)
				)
				(justify mirror)
			)
		)
		(sheetname "/I^{2}C/")
		(sheetfile "i2c.kicad_sch")
		(attr exclude_from_pos_files exclude_from_bom dnp)
		(fp_rect
			(start -0.93 0.47)
			(end 0.93 -0.47)
			(stroke
				(width 0.05)
				(type solid)
			)
			(fill no)
			(layer "B.CrtYd")
		)
		(fp_rect
			(start -0.5 0.25)
			(end 0.5 -0.25)
			(stroke
				(width 0.15)
				(type solid)
			)
			(fill no)
			(layer "B.Fab")
		)
		(pad "1" smd roundrect
			(at -0.485 0 180)
			(size 0.59 0.64)
			(layers "B.Cu" "B.Mask" "B.Paste")
			(roundrect_rratio 0.25)
			(net 690 "/I^{2}C/PWR.SDA")
			(pintype "passive")
		)
		(pad "2" smd roundrect
			(at 0.485 0 180)
			(size 0.59 0.64)
			(layers "B.Cu" "B.Mask" "B.Paste")
			(roundrect_rratio 0.25)
			(net 688 "/FPGA bank 14/FPGA_PWR.SDA")
			(pintype "passive")
		)
	)
	(footprint "antmicro-footprints:C_0603_1608Metric"
		(layer "B.Cu")
		(at 127.075501 174.801)
		(descr "Capacitor SMD 0603")
		(tags "capacitor 0603")
		(property "Reference" "C15"
			(at 0 0.9 0)
			(layer "B.SilkS")
			(hide yes)
			(effects
				(font
					(size 0.7 0.7)
					(thickness 0.15)
				)
				(justify right bottom mirror)
			)
		)
		(property "Value" "C_47u_0603"
			(at 0 -1.6 0)
			(layer "B.Fab")
			(effects
				(font
					(size 0.7 0.7)
					(thickness 0.15)
				)
				(justify right bottom mirror)
			)
		)
		(property "Datasheet" "https://www.murata.com/products/productdetail?partno=GRM188R60J476ME15%23"
			(at 0 0 0)
			(layer "F.Fab")
			(hide yes)
			(effects
				(font
					(size 1.27 1.27)
					(thickness 0.15)
				)
			)
		)
		(property "Author" "Antmicro"
			(at 0 0 0)
			(layer "B.Fab")
			(hide yes)
			(effects
				(font
					(size 1 1)
					(thickness 0.15)
				)
				(justify mirror)
			)
		)
		(property "Dielectric" ""
			(at 0 0 0)
			(layer "B.Fab")
			(hide yes)
			(effects
				(font
					(size 1 1)
					(thickness 0.15)
				)
				(justify mirror)
			)
		)
		(property "License" "Apache-2.0"
			(at 0 0 0)
			(layer "B.Fab")
			(hide yes)
			(effects
				(font
					(size 1 1)
					(thickness 0.15)
				)
				(justify mirror)
			)
		)
		(property "MPN" "GRM188R60J476ME15D"
			(at 0 0 0)
			(layer "B.Fab")
			(hide yes)
			(effects
				(font
					(size 1 1)
					(thickness 0.15)
				)
				(justify mirror)
			)
		)
		(property "Manufacturer" "Murata"
			(at 0 0 0)
			(layer "B.Fab")
			(hide yes)
			(effects
				(font
					(size 1 1)
					(thickness 0.15)
				)
				(justify mirror)
			)
		)
		(property "Val" "47u"
			(at 0 0 0)
			(layer "B.Fab")
			(hide yes)
			(effects
				(font
					(size 1 1)
					(thickness 0.15)
				)
				(justify mirror)
			)
		)
		(property "Voltage" ""
			(at 0 0 0)
			(layer "B.Fab")
			(hide yes)
			(effects
				(font
					(size 1 1)
					(thickness 0.15)
				)
				(justify mirror)
			)
		)
		(sheetname "/FPGA power/")
		(sheetfile "fpga-power.kicad_sch")
		(attr smd)
		(fp_line
			(start -0.3 -0.3)
			(end 0.3 -0.3)
			(stroke
				(width 0.15)
				(type solid)
			)
			(layer "B.SilkS")
		)
		(fp_line
			(start -0.3 0.3)
			(end 0.3 0.3)
			(stroke
				(width 0.15)
				(type solid)
			)
			(layer "B.SilkS")
		)
		(fp_rect
			(start -1.24 0.7)
			(end 1.24 -0.7)
			(stroke
				(width 0.05)
				(type solid)
			)
			(fill no)
			(layer "B.CrtYd")
		)
		(fp_rect
			(start -0.8 0.4)
			(end 0.8 -0.4)
			(stroke
				(width 0.15)
				(type solid)
			)
			(fill no)
			(layer "B.Fab")
		)
		(pad "1" smd roundrect
			(at -0.7 0)
			(size 0.6 0.8)
			(layers "B.Cu" "B.Mask" "B.Paste")
			(roundrect_rratio 0.2)
			(net 200 "+3V3")
			(pintype "passive")
		)
		(pad "2" smd roundrect
			(at 0.7 0)
			(size 0.6 0.8)
			(layers "B.Cu" "B.Mask" "B.Paste")
			(roundrect_rratio 0.2)
			(net 1 "GND")
			(pintype "passive")
		)
	)
	(footprint "antmicro-footprints:R_0402_1005Metric"
		(layer "B.Cu")
		(at 114.800502 182.6 180)
		(descr "Resistor SMD 0402")
		(tags "resistor SMD 0402")
		(property "Reference" "R4"
			(at -1.122484 0.772697 0)
			(layer "B.SilkS")
			(hide yes)
			(effects
				(font
					(size 0.7 0.7)
					(thickness 0.15)
				)
				(justify left bottom mirror)
			)
		)
		(property "Value" "R_4k7_0402"
			(at -1.011843 -1.772047 0)
			(layer "B.Fab")
			(effects
				(font
					(size 0.7 0.7)
					(thickness 0.15)
				)
				(justify left bottom mirror)
			)
		)
		(property "Datasheet" "https://www.bourns.com/docs/product-datasheets/cr.pdf"
			(at 0 0 180)
			(layer "F.Fab")
			(hide yes)
			(effects
				(font
					(size 1.27 1.27)
					(thickness 0.15)
				)
			)
		)
		(property "Author" "Antmicro"
			(at 229.601004 365.2 0)
			(layer "B.Fab")
			(hide yes)
			(effects
				(font
					(size 1 1)
					(thickness 0.15)
				)
				(justify mirror)
			)
		)
		(property "License" "Apache-2.0"
			(at 229.601004 365.2 0)
			(layer "B.Fab")
			(hide yes)
			(effects
				(font
					(size 1 1)
					(thickness 0.15)
				)
				(justify mirror)
			)
		)
		(property "MPN" "CR0402-FX-4701GLF"
			(at 229.601004 365.2 0)
			(layer "B.Fab")
			(hide yes)
			(effects
				(font
					(size 1 1)
					(thickness 0.15)
				)
				(justify mirror)
			)
		)
		(property "Manufacturer" "Bourns"
			(at 229.601004 365.2 0)
			(layer "B.Fab")
			(hide yes)
			(effects
				(font
					(size 1 1)
					(thickness 0.15)
				)
				(justify mirror)
			)
		)
		(property "Tolerance" "1%"
			(at 229.601004 365.2 0)
			(layer "B.Fab")
			(hide yes)
			(effects
				(font
					(size 1 1)
					(thickness 0.15)
				)
				(justify mirror)
			)
		)
		(property "Val" "4k7"
			(at 229.601004 365.2 0)
			(layer "B.Fab")
			(hide yes)
			(effects
				(font
					(size 1 1)
					(thickness 0.15)
				)
				(justify mirror)
			)
		)
		(sheetname "/HyperRAM + QSPI Flash/")
		(sheetfile "hyperram-flash.kicad_sch")
		(attr smd)
		(fp_rect
			(start -0.93 0.47)
			(end 0.93 -0.47)
			(stroke
				(width 0.05)
				(type solid)
			)
			(fill no)
			(layer "B.CrtYd")
		)
		(fp_rect
			(start -0.5 0.25)
			(end 0.5 -0.25)
			(stroke
				(width 0.15)
				(type solid)
			)
			(fill no)
			(layer "B.Fab")
		)
		(pad "1" smd roundrect
			(at -0.485 0 180)
			(size 0.59 0.64)
			(layers "B.Cu" "B.Mask" "B.Paste")
			(roundrect_rratio 0.25)
			(net 200 "+3V3")
			(pintype "passive")
		)
		(pad "2" smd roundrect
			(at 0.485 0 180)
			(size 0.59 0.64)
			(layers "B.Cu" "B.Mask" "B.Paste")
			(roundrect_rratio 0.25)
			(net 360 "/HyperRAM + QSPI Flash/IO3")
			(pintype "passive")
		)
	)
	(footprint "antmicro-footprints:TP_SMD_1mm"
		(layer "B.Cu")
		(at 186.4 164.5845 180)
		(property "Reference" "TP31"
			(at 0 0.731898 0)
			(layer "B.SilkS")
			(hide yes)
			(effects
				(font
					(size 0.7 0.7)
					(thickness 0.15)
				)
				(justify left bottom mirror)
			)
		)
		(property "Value" "TP_1mm_SMD"
			(at 0 -1.4 0)
			(layer "B.Fab")
			(effects
				(font
					(size 0.7 0.7)
					(thickness 0.15)
				)
				(justify left bottom mirror)
			)
		)
		(property "MPN" ""
			(at 0 0 0)
			(unlocked yes)
			(layer "B.Fab")
			(hide yes)
			(effects
				(font
					(size 1 1)
					(thickness 0.15)
				)
				(justify mirror)
			)
		)
		(property "Manufacturer" ""
			(at 0 0 0)
			(unlocked yes)
			(layer "B.Fab")
			(hide yes)
			(effects
				(font
					(size 1 1)
					(thickness 0.15)
				)
				(justify mirror)
			)
		)
		(property "Author" "Antmicro"
			(at 0 0 0)
			(unlocked yes)
			(layer "B.Fab")
			(hide yes)
			(effects
				(font
					(size 1 1)
					(thickness 0.15)
				)
				(justify mirror)
			)
		)
		(property "License" "Apache-2.0"
			(at 0 0 0)
			(unlocked yes)
			(layer "B.Fab")
			(hide yes)
			(effects
				(font
					(size 1 1)
					(thickness 0.15)
				)
				(justify mirror)
			)
		)
		(sheetname "/Supply/")
		(sheetfile "supply.kicad_sch")
		(attr exclude_from_pos_files)
		(fp_circle
			(center 0 0)
			(end 0.6 0)
			(stroke
				(width 0.05)
				(type default)
			)
			(fill no)
			(layer "B.CrtYd")
		)
		(fp_text user "License: Apache-2.0"
			(at -0.5 -5.2 0)
			(layer "B.Fab")
			(effects
				(font
					(size 0.7 0.7)
					(thickness 0.15)
				)
				(justify left bottom mirror)
			)
		)
		(fp_text user "Author: Antmicro"
			(at -0.5 -4 0)
			(layer "B.Fab")
			(effects
				(font
					(size 0.7 0.7)
					(thickness 0.15)
				)
				(justify left bottom mirror)
			)
		)
		(fp_text user "${REFERENCE}"
			(at -0.5 -2.8 0)
			(layer "B.Fab")
			(effects
				(font
					(size 0.7 0.7)
					(thickness 0.15)
				)
				(justify left bottom mirror)
			)
		)
		(pad "1" smd circle
			(at 0 0 180)
			(size 1 1)
			(layers "B.Cu" "B.Mask")
			(net 201 "+5V")
			(pinfunction "1")
			(pintype "passive")
		)
	)
	(footprint "antmicro-footprints:C_0402_1005Metric"
		(layer "B.Cu")
		(at 105.96 176.204 90)
		(descr "Capacitor SMD 0402")
		(tags "capacitor SMD 0402")
		(property "Reference" "C238"
			(at 0 0.699001 90)
			(layer "B.SilkS")
			(hide yes)
			(effects
				(font
					(size 0.7 0.7)
					(thickness 0.15)
				)
				(justify right bottom mirror)
			)
		)
		(property "Value" "C_100n_0402"
			(at -1.022927 -2.155213 90)
			(layer "B.Fab")
			(effects
				(font
					(size 0.7 0.7)
					(thickness 0.15)
				)
				(justify right bottom mirror)
			)
		)
		(property "Datasheet" "https://www.murata.com/products/productdetail?partno=GRM155R61H104KE14%23"
			(at 0 0 90)
			(layer "F.Fab")
			(hide yes)
			(effects
				(font
					(size 1.27 1.27)
					(thickness 0.15)
				)
			)
		)
		(property "Author" "Antmicro"
			(at 282.164 70.244 0)
			(layer "B.Fab")
			(hide yes)
			(effects
				(font
					(size 1 1)
					(thickness 0.15)
				)
				(justify mirror)
			)
		)
		(property "Dielectric" "X5R"
			(at 282.164 70.244 0)
			(layer "B.Fab")
			(hide yes)
			(effects
				(font
					(size 1 1)
					(thickness 0.15)
				)
				(justify mirror)
			)
		)
		(property "License" "Apache-2.0"
			(at 282.164 70.244 0)
			(layer "B.Fab")
			(hide yes)
			(effects
				(font
					(size 1 1)
					(thickness 0.15)
				)
				(justify mirror)
			)
		)
		(property "MPN" "GRM155R61H104KE14D"
			(at 282.164 70.244 0)
			(layer "B.Fab")
			(hide yes)
			(effects
				(font
					(size 1 1)
					(thickness 0.15)
				)
				(justify mirror)
			)
		)
		(property "Manufacturer" "Murata"
			(at 282.164 70.244 0)
			(layer "B.Fab")
			(hide yes)
			(effects
				(font
					(size 1 1)
					(thickness 0.15)
				)
				(justify mirror)
			)
		)
		(property "Val" "100n"
			(at 282.164 70.244 0)
			(layer "B.Fab")
			(hide yes)
			(effects
				(font
					(size 1 1)
					(thickness 0.15)
				)
				(justify mirror)
			)
		)
		(property "Voltage" "50V"
			(at 282.164 70.244 0)
			(layer "B.Fab")
			(hide yes)
			(effects
				(font
					(size 1 1)
					(thickness 0.15)
				)
				(justify mirror)
			)
		)
		(sheetname "/Debug FTDI/")
		(sheetfile "debug-ftdi.kicad_sch")
		(attr smd)
		(fp_rect
			(start -0.925 0.47)
			(end 0.925 -0.47)
			(stroke
				(width 0.05)
				(type default)
			)
			(fill no)
			(layer "B.CrtYd")
		)
		(fp_line
			(start 0.504 -0.248)
			(end -0.494 -0.248)
			(stroke
				(width 0.15)
				(type solid)
			)
			(layer "B.Fab")
		)
		(fp_line
			(start -0.494 -0.248)
			(end -0.494 0.25)
			(stroke
				(width 0.15)
				(type solid)
			)
			(layer "B.Fab")
		)
		(fp_line
			(start 0.504 0.25)
			(end 0.504 -0.248)
			(stroke
				(width 0.15)
				(type solid)
			)
			(layer "B.Fab")
		)
		(fp_line
			(start -0.494 0.25)
			(end 0.504 0.25)
			(stroke
				(width 0.15)
				(type solid)
			)
			(layer "B.Fab")
		)
		(pad "1" smd roundrect
			(at -0.48 0 90)
			(size 0.59 0.64)
			(layers "B.Cu" "B.Mask" "B.Paste")
			(roundrect_rratio 0.25)
			(net 1 "GND")
			(pintype "passive")
		)
		(pad "2" smd roundrect
			(at 0.48 0 90)
			(size 0.59 0.64)
			(layers "B.Cu" "B.Mask" "B.Paste")
			(roundrect_rratio 0.25)
			(net 200 "+3V3")
			(pintype "passive")
		)
	)
	(footprint "antmicro-footprints:C_0402_1005Metric"
		(layer "B.Cu")
		(at 100.280501 143.546 90)
		(descr "Capacitor SMD 0402")
		(tags "capacitor SMD 0402")
		(property "Reference" "C165"
			(at 0 0.699 270)
			(layer "B.SilkS")
			(hide yes)
			(effects
				(font
					(size 0.7 0.7)
					(thickness 0.15)
				)
				(justify left bottom mirror)
			)
		)
		(property "Value" "C_100n_0402"
			(at -1.022927 -2.155213 270)
			(layer "B.Fab")
			(effects
				(font
					(size 0.7 0.7)
					(thickness 0.15)
				)
				(justify left bottom mirror)
			)
		)
		(property "Datasheet" "https://www.murata.com/products/productdetail?partno=GRM155R61H104KE14%23"
			(at 0 0 90)
			(layer "F.Fab")
			(hide yes)
			(effects
				(font
					(size 1.27 1.27)
					(thickness 0.15)
				)
			)
		)
		(property "Author" "Antmicro"
			(at 243.826501 43.265499 0)
			(layer "B.Fab")
			(hide yes)
			(effects
				(font
					(size 1 1)
					(thickness 0.15)
				)
				(justify mirror)
			)
		)
		(property "Dielectric" "X5R"
			(at 243.826501 43.265499 0)
			(layer "B.Fab")
			(hide yes)
			(effects
				(font
					(size 1 1)
					(thickness 0.15)
				)
				(justify mirror)
			)
		)
		(property "License" "Apache-2.0"
			(at 243.826501 43.265499 0)
			(layer "B.Fab")
			(hide yes)
			(effects
				(font
					(size 1 1)
					(thickness 0.15)
				)
				(justify mirror)
			)
		)
		(property "MPN" "GRM155R61H104KE14D"
			(at 243.826501 43.265499 0)
			(layer "B.Fab")
			(hide yes)
			(effects
				(font
					(size 1 1)
					(thickness 0.15)
				)
				(justify mirror)
			)
		)
		(property "Manufacturer" "Murata"
			(at 243.826501 43.265499 0)
			(layer "B.Fab")
			(hide yes)
			(effects
				(font
					(size 1 1)
					(thickness 0.15)
				)
				(justify mirror)
			)
		)
		(property "Val" "100n"
			(at 243.826501 43.265499 0)
			(layer "B.Fab")
			(hide yes)
			(effects
				(font
					(size 1 1)
					(thickness 0.15)
				)
				(justify mirror)
			)
		)
		(property "Voltage" "50V"
			(at 243.826501 43.265499 0)
			(layer "B.Fab")
			(hide yes)
			(effects
				(font
					(size 1 1)
					(thickness 0.15)
				)
				(justify mirror)
			)
		)
		(sheetname "/I^{2}C/")
		(sheetfile "i2c.kicad_sch")
		(attr smd)
		(fp_rect
			(start -0.9659 0.481258)
			(end 0.9649 -0.458742)
			(stroke
				(width 0.05)
				(type solid)
			)
			(fill no)
			(layer "B.CrtYd")
		)
		(fp_line
			(start 0.499 -0.248)
			(end -0.499 -0.248)
			(stroke
				(width 0.15)
				(type solid)
			)
			(layer "B.Fab")
		)
		(fp_line
			(start -0.499 -0.248)
			(end -0.499 0.25)
			(stroke
				(width 0.15)
				(type solid)
			)
			(layer "B.Fab")
		)
		(fp_line
			(start 0.499 0.25)
			(end 0.499 -0.248)
			(stroke
				(width 0.15)
				(type solid)
			)
			(layer "B.Fab")
		)
		(fp_line
			(start -0.499 0.25)
			(end 0.499 0.25)
			(stroke
				(width 0.15)
				(type solid)
			)
			(layer "B.Fab")
		)
		(pad "1" smd roundrect
			(at -0.484 0 90)
			(size 0.59 0.64)
			(layers "B.Cu" "B.Mask" "B.Paste")
			(roundrect_rratio 0.25)
			(net 200 "+3V3")
			(pintype "passive")
		)
		(pad "2" smd roundrect
			(at 0.484 0 90)
			(size 0.59 0.64)
			(layers "B.Cu" "B.Mask" "B.Paste")
			(roundrect_rratio 0.25)
			(net 1 "GND")
			(pintype "passive")
		)
	)
	(footprint "antmicro-footprints:C_0402_1005Metric"
		(layer "B.Cu")
		(at 115.580501 176.926 -90)
		(descr "Capacitor SMD 0402")
		(tags "capacitor SMD 0402")
		(property "Reference" "C2"
			(at 0 0.699 90)
			(layer "B.SilkS")
			(hide yes)
			(effects
				(font
					(size 0.7 0.7)
					(thickness 0.15)
				)
				(justify left bottom mirror)
			)
		)
		(property "Value" "C_100n_0402"
			(at -1.022927 -2.155213 90)
			(layer "B.Fab")
			(effects
				(font
					(size 0.7 0.7)
					(thickness 0.15)
				)
				(justify left bottom mirror)
			)
		)
		(property "Datasheet" "https://www.murata.com/products/productdetail?partno=GRM155R61H104KE14%23"
			(at 0 0 270)
			(layer "F.Fab")
			(hide yes)
			(effects
				(font
					(size 1.27 1.27)
					(thickness 0.15)
				)
			)
		)
		(property "Author" "Antmicro"
			(at -61.345499 292.506501 0)
			(layer "B.Fab")
			(hide yes)
			(effects
				(font
					(size 1 1)
					(thickness 0.15)
				)
				(justify mirror)
			)
		)
		(property "Dielectric" "X5R"
			(at -61.345499 292.506501 0)
			(layer "B.Fab")
			(hide yes)
			(effects
				(font
					(size 1 1)
					(thickness 0.15)
				)
				(justify mirror)
			)
		)
		(property "License" "Apache-2.0"
			(at -61.345499 292.506501 0)
			(layer "B.Fab")
			(hide yes)
			(effects
				(font
					(size 1 1)
					(thickness 0.15)
				)
				(justify mirror)
			)
		)
		(property "MPN" "GRM155R61H104KE14D"
			(at -61.345499 292.506501 0)
			(layer "B.Fab")
			(hide yes)
			(effects
				(font
					(size 1 1)
					(thickness 0.15)
				)
				(justify mirror)
			)
		)
		(property "Manufacturer" "Murata"
			(at -61.345499 292.506501 0)
			(layer "B.Fab")
			(hide yes)
			(effects
				(font
					(size 1 1)
					(thickness 0.15)
				)
				(justify mirror)
			)
		)
		(property "Val" "100n"
			(at -61.345499 292.506501 0)
			(layer "B.Fab")
			(hide yes)
			(effects
				(font
					(size 1 1)
					(thickness 0.15)
				)
				(justify mirror)
			)
		)
		(property "Voltage" "50V"
			(at -61.345499 292.506501 0)
			(layer "B.Fab")
			(hide yes)
			(effects
				(font
					(size 1 1)
					(thickness 0.15)
				)
				(justify mirror)
			)
		)
		(sheetname "/HyperRAM + QSPI Flash/")
		(sheetfile "hyperram-flash.kicad_sch")
		(attr smd)
		(fp_rect
			(start -0.9659 0.481258)
			(end 0.9649 -0.458742)
			(stroke
				(width 0.05)
				(type solid)
			)
			(fill no)
			(layer "B.CrtYd")
		)
		(fp_line
			(start -0.499 0.25)
			(end 0.499 0.25)
			(stroke
				(width 0.15)
				(type solid)
			)
			(layer "B.Fab")
		)
		(fp_line
			(start 0.499 0.25)
			(end 0.499 -0.248)
			(stroke
				(width 0.15)
				(type solid)
			)
			(layer "B.Fab")
		)
		(fp_line
			(start -0.499 -0.248)
			(end -0.499 0.25)
			(stroke
				(width 0.15)
				(type solid)
			)
			(layer "B.Fab")
		)
		(fp_line
			(start 0.499 -0.248)
			(end -0.499 -0.248)
			(stroke
				(width 0.15)
				(type solid)
			)
			(layer "B.Fab")
		)
		(pad "1" smd roundrect
			(at -0.484 0 270)
			(size 0.59 0.64)
			(layers "B.Cu" "B.Mask" "B.Paste")
			(roundrect_rratio 0.25)
			(net 200 "+3V3")
			(pintype "passive")
		)
		(pad "2" smd roundrect
			(at 0.484 0 270)
			(size 0.59 0.64)
			(layers "B.Cu" "B.Mask" "B.Paste")
			(roundrect_rratio 0.25)
			(net 1 "GND")
			(pintype "passive")
		)
	)
	(footprint "antmicro-footprints:C_0402_1005Metric"
		(layer "B.Cu")
		(at 149.875001 176.3)
		(descr "Capacitor SMD 0402 (1005 Metric), square (rectangular) end terminal, IPC_7351 nominal, (Body size source: IPC-SM-782 page 76, https://www.pcb-3d.com/wordpress/wp-content/uploads/ipc-sm-782a_amendment_1_and_2.pdf)")
		(tags "capacitor 0402")
		(property "Reference" "C104"
			(at 0 1.17 180)
			(layer "B.SilkS")
			(hide yes)
			(effects
				(font
					(size 0.7 0.7)
					(thickness 0.15)
				)
				(justify left bottom mirror)
			)
		)
		(property "Value" "C_100n_0402"
			(at 0 -1.169 180)
			(layer "B.Fab")
			(effects
				(font
					(size 0.7 0.7)
					(thickness 0.15)
				)
				(justify left bottom mirror)
			)
		)
		(property "Datasheet" "https://www.murata.com/products/productdetail?partno=GRM155R61H104KE14%23"
			(at 0 0 0)
			(layer "F.Fab")
			(hide yes)
			(effects
				(font
					(size 1.27 1.27)
					(thickness 0.15)
				)
			)
		)
		(property "Author" "Antmicro"
			(at 0 0 0)
			(layer "B.Fab")
			(hide yes)
			(effects
				(font
					(size 1 1)
					(thickness 0.15)
				)
				(justify mirror)
			)
		)
		(property "Dielectric" "X5R"
			(at 0 0 0)
			(layer "B.Fab")
			(hide yes)
			(effects
				(font
					(size 1 1)
					(thickness 0.15)
				)
				(justify mirror)
			)
		)
		(property "License" "Apache-2.0"
			(at 0 0 0)
			(layer "B.Fab")
			(hide yes)
			(effects
				(font
					(size 1 1)
					(thickness 0.15)
				)
				(justify mirror)
			)
		)
		(property "MPN" "GRM155R61H104KE14D"
			(at 0 0 0)
			(layer "B.Fab")
			(hide yes)
			(effects
				(font
					(size 1 1)
					(thickness 0.15)
				)
				(justify mirror)
			)
		)
		(property "Manufacturer" "Murata"
			(at 0 0 0)
			(layer "B.Fab")
			(hide yes)
			(effects
				(font
					(size 1 1)
					(thickness 0.15)
				)
				(justify mirror)
			)
		)
		(property "Val" "100n"
			(at 0 0 0)
			(layer "B.Fab")
			(hide yes)
			(effects
				(font
					(size 1 1)
					(thickness 0.15)
				)
				(justify mirror)
			)
		)
		(property "Voltage" "50V"
			(at 0 0 0)
			(layer "B.Fab")
			(hide yes)
			(effects
				(font
					(size 1 1)
					(thickness 0.15)
				)
				(justify mirror)
			)
		)
		(sheetname "/FPGA power/")
		(sheetfile "fpga-power.kicad_sch")
		(attr smd)
		(fp_rect
			(start -0.9656 0.4572)
			(end 0.9652 -0.4828)
			(stroke
				(width 0.05)
				(type solid)
			)
			(fill no)
			(layer "B.CrtYd")
		)
		(fp_line
			(start -0.5 -0.248)
			(end -0.5 0.25)
			(stroke
				(width 0.15)
				(type solid)
			)
			(layer "B.Fab")
		)
		(fp_line
			(start -0.5 0.25)
			(end 0.498 0.25)
			(stroke
				(width 0.15)
				(type solid)
			)
			(layer "B.Fab")
		)
		(fp_line
			(start 0.498 -0.248)
			(end -0.5 -0.248)
			(stroke
				(width 0.15)
				(type solid)
			)
			(layer "B.Fab")
		)
		(fp_line
			(start 0.498 0.25)
			(end 0.498 -0.248)
			(stroke
				(width 0.15)
				(type solid)
			)
			(layer "B.Fab")
		)
		(pad "1" smd roundrect
			(at -0.5 0 270)
			(size 0.6 0.6)
			(layers "B.Cu" "B.Mask" "B.Paste")
			(roundrect_rratio 0.25)
			(net 1 "GND")
			(pintype "passive")
		)
		(pad "2" smd roundrect
			(at 0.498 0)
			(size 0.6 0.6)
			(layers "B.Cu" "B.Mask" "B.Paste")
			(roundrect_rratio 0.25)
			(net 226 "+1V2_MGTAVTT")
			(pintype "passive")
		)
	)
	(footprint "antmicro-footprints:TP_SMD_1mm"
		(layer "B.Cu")
		(at 186.4 184.85 180)
		(property "Reference" "TP28"
			(at 0 0.731898 0)
			(layer "B.SilkS")
			(hide yes)
			(effects
				(font
					(size 0.7 0.7)
					(thickness 0.15)
				)
				(justify left bottom mirror)
			)
		)
		(property "Value" "TP_1mm_SMD"
			(at 0 -1.4 0)
			(layer "B.Fab")
			(effects
				(font
					(size 0.7 0.7)
					(thickness 0.15)
				)
				(justify left bottom mirror)
			)
		)
		(property "MPN" ""
			(at 0 0 0)
			(unlocked yes)
			(layer "B.Fab")
			(hide yes)
			(effects
				(font
					(size 1 1)
					(thickness 0.15)
				)
				(justify mirror)
			)
		)
		(property "Manufacturer" ""
			(at 0 0 0)
			(unlocked yes)
			(layer "B.Fab")
			(hide yes)
			(effects
				(font
					(size 1 1)
					(thickness 0.15)
				)
				(justify mirror)
			)
		)
		(property "Author" "Antmicro"
			(at 0 0 0)
			(unlocked yes)
			(layer "B.Fab")
			(hide yes)
			(effects
				(font
					(size 1 1)
					(thickness 0.15)
				)
				(justify mirror)
			)
		)
		(property "License" "Apache-2.0"
			(at 0 0 0)
			(unlocked yes)
			(layer "B.Fab")
			(hide yes)
			(effects
				(font
					(size 1 1)
					(thickness 0.15)
				)
				(justify mirror)
			)
		)
		(sheetname "/Supply/")
		(sheetfile "supply.kicad_sch")
		(attr exclude_from_pos_files)
		(fp_circle
			(center 0 0)
			(end 0.6 0)
			(stroke
				(width 0.05)
				(type default)
			)
			(fill no)
			(layer "B.CrtYd")
		)
		(fp_text user "Author: Antmicro"
			(at -0.5 -4 0)
			(layer "B.Fab")
			(effects
				(font
					(size 0.7 0.7)
					(thickness 0.15)
				)
				(justify left bottom mirror)
			)
		)
		(fp_text user "${REFERENCE}"
			(at -0.5 -2.8 0)
			(layer "B.Fab")
			(effects
				(font
					(size 0.7 0.7)
					(thickness 0.15)
				)
				(justify left bottom mirror)
			)
		)
		(fp_text user "License: Apache-2.0"
			(at -0.5 -5.2 0)
			(layer "B.Fab")
			(effects
				(font
					(size 0.7 0.7)
					(thickness 0.15)
				)
				(justify left bottom mirror)
			)
		)
		(pad "1" smd circle
			(at 0 0 180)
			(size 1 1)
			(layers "B.Cu" "B.Mask")
			(net 187 "+1V0_MGTAVCC")
			(pinfunction "1")
			(pintype "passive")
		)
	)
	(footprint "antmicro-footprints:C_0603_1608Metric"
		(layer "B.Cu")
		(at 147.375501 174.801 180)
		(descr "Capacitor SMD 0603")
		(tags "capacitor 0603")
		(property "Reference" "C73"
			(at 0 0.9 0)
			(layer "B.SilkS")
			(hide yes)
			(effects
				(font
					(size 0.7 0.7)
					(thickness 0.15)
				)
				(justify left bottom mirror)
			)
		)
		(property "Value" "C_47u_0603"
			(at 0 -1.6 0)
			(layer "B.Fab")
			(effects
				(font
					(size 0.7 0.7)
					(thickness 0.15)
				)
				(justify left bottom mirror)
			)
		)
		(property "Datasheet" "https://www.murata.com/products/productdetail?partno=GRM188R60J476ME15%23"
			(at 0 0 180)
			(layer "F.Fab")
			(hide yes)
			(effects
				(font
					(size 1.27 1.27)
					(thickness 0.15)
				)
			)
		)
		(property "Author" "Antmicro"
			(at 294.751002 349.602 0)
			(layer "B.Fab")
			(hide yes)
			(effects
				(font
					(size 1 1)
					(thickness 0.15)
				)
				(justify mirror)
			)
		)
		(property "Dielectric" ""
			(at 294.751002 349.602 0)
			(layer "B.Fab")
			(hide yes)
			(effects
				(font
					(size 1 1)
					(thickness 0.15)
				)
				(justify mirror)
			)
		)
		(property "License" "Apache-2.0"
			(at 294.751002 349.602 0)
			(layer "B.Fab")
			(hide yes)
			(effects
				(font
					(size 1 1)
					(thickness 0.15)
				)
				(justify mirror)
			)
		)
		(property "MPN" "GRM188R60J476ME15D"
			(at 294.751002 349.602 0)
			(layer "B.Fab")
			(hide yes)
			(effects
				(font
					(size 1 1)
					(thickness 0.15)
				)
				(justify mirror)
			)
		)
		(property "Manufacturer" "Murata"
			(at 294.751002 349.602 0)
			(layer "B.Fab")
			(hide yes)
			(effects
				(font
					(size 1 1)
					(thickness 0.15)
				)
				(justify mirror)
			)
		)
		(property "Val" "47u"
			(at 294.751002 349.602 0)
			(layer "B.Fab")
			(hide yes)
			(effects
				(font
					(size 1 1)
					(thickness 0.15)
				)
				(justify mirror)
			)
		)
		(property "Voltage" ""
			(at 294.751002 349.602 0)
			(layer "B.Fab")
			(hide yes)
			(effects
				(font
					(size 1 1)
					(thickness 0.15)
				)
				(justify mirror)
			)
		)
		(sheetname "/FPGA power/")
		(sheetfile "fpga-power.kicad_sch")
		(attr smd)
		(fp_line
			(start -0.3 0.3)
			(end 0.3 0.3)
			(stroke
				(width 0.15)
				(type solid)
			)
			(layer "B.SilkS")
		)
		(fp_line
			(start -0.3 -0.3)
			(end 0.3 -0.3)
			(stroke
				(width 0.15)
				(type solid)
			)
			(layer "B.SilkS")
		)
		(fp_rect
			(start -1.24 0.7)
			(end 1.24 -0.7)
			(stroke
				(width 0.05)
				(type solid)
			)
			(fill no)
			(layer "B.CrtYd")
		)
		(fp_rect
			(start -0.8 0.4)
			(end 0.8 -0.4)
			(stroke
				(width 0.15)
				(type solid)
			)
			(fill no)
			(layer "B.Fab")
		)
		(pad "1" smd roundrect
			(at -0.7 0 180)
			(size 0.6 0.8)
			(layers "B.Cu" "B.Mask" "B.Paste")
			(roundrect_rratio 0.2)
			(net 200 "+3V3")
			(pintype "passive")
		)
		(pad "2" smd roundrect
			(at 0.7 0 180)
			(size 0.6 0.8)
			(layers "B.Cu" "B.Mask" "B.Paste")
			(roundrect_rratio 0.2)
			(net 1 "GND")
			(pintype "passive")
		)
	)
	(footprint "antmicro-footprints:C_0402_1005Metric"
		(layer "B.Cu")
		(at 133.375501 166.801 90)
		(descr "Capacitor SMD 0402 (1005 Metric), square (rectangular) end terminal, IPC_7351 nominal, (Body size source: IPC-SM-782 page 76, https://www.pcb-3d.com/wordpress/wp-content/uploads/ipc-sm-782a_amendment_1_and_2.pdf)")
		(tags "capacitor 0402")
		(property "Reference" "C31"
			(at 0 1.17 270)
			(layer "B.SilkS")
			(hide yes)
			(effects
				(font
					(size 0.7 0.7)
					(thickness 0.15)
				)
				(justify left bottom mirror)
			)
		)
		(property "Value" "C_100n_0402"
			(at 0 -1.169 270)
			(layer "B.Fab")
			(effects
				(font
					(size 0.7 0.7)
					(thickness 0.15)
				)
				(justify left bottom mirror)
			)
		)
		(property "Datasheet" "https://www.murata.com/products/productdetail?partno=GRM155R61H104KE14%23"
			(at 0 0 90)
			(layer "F.Fab")
			(hide yes)
			(effects
				(font
					(size 1.27 1.27)
					(thickness 0.15)
				)
			)
		)
		(property "Author" "Antmicro"
			(at 300.176501 33.425499 0)
			(layer "B.Fab")
			(hide yes)
			(effects
				(font
					(size 1 1)
					(thickness 0.15)
				)
				(justify mirror)
			)
		)
		(property "Dielectric" "X5R"
			(at 300.176501 33.425499 0)
			(layer "B.Fab")
			(hide yes)
			(effects
				(font
					(size 1 1)
					(thickness 0.15)
				)
				(justify mirror)
			)
		)
		(property "License" "Apache-2.0"
			(at 300.176501 33.425499 0)
			(layer "B.Fab")
			(hide yes)
			(effects
				(font
					(size 1 1)
					(thickness 0.15)
				)
				(justify mirror)
			)
		)
		(property "MPN" "GRM155R61H104KE14D"
			(at 300.176501 33.425499 0)
			(layer "B.Fab")
			(hide yes)
			(effects
				(font
					(size 1 1)
					(thickness 0.15)
				)
				(justify mirror)
			)
		)
		(property "Manufacturer" "Murata"
			(at 300.176501 33.425499 0)
			(layer "B.Fab")
			(hide yes)
			(effects
				(font
					(size 1 1)
					(thickness 0.15)
				)
				(justify mirror)
			)
		)
		(property "Val" "100n"
			(at 300.176501 33.425499 0)
			(layer "B.Fab")
			(hide yes)
			(effects
				(font
					(size 1 1)
					(thickness 0.15)
				)
				(justify mirror)
			)
		)
		(property "Voltage" "50V"
			(at 300.176501 33.425499 0)
			(layer "B.Fab")
			(hide yes)
			(effects
				(font
					(size 1 1)
					(thickness 0.15)
				)
				(justify mirror)
			)
		)
		(sheetname "/FPGA power/")
		(sheetfile "fpga-power.kicad_sch")
		(attr smd)
		(fp_rect
			(start -0.9656 0.4572)
			(end 0.9652 -0.4828)
			(stroke
				(width 0.05)
				(type solid)
			)
			(fill no)
			(layer "B.CrtYd")
		)
		(fp_line
			(start 0.498 -0.248)
			(end -0.5 -0.248)
			(stroke
				(width 0.15)
				(type solid)
			)
			(layer "B.Fab")
		)
		(fp_line
			(start -0.5 -0.248)
			(end -0.5 0.25)
			(stroke
				(width 0.15)
				(type solid)
			)
			(layer "B.Fab")
		)
		(fp_line
			(start 0.498 0.25)
			(end 0.498 -0.248)
			(stroke
				(width 0.15)
				(type solid)
			)
			(layer "B.Fab")
		)
		(fp_line
			(start -0.5 0.25)
			(end 0.498 0.25)
			(stroke
				(width 0.15)
				(type solid)
			)
			(layer "B.Fab")
		)
		(pad "1" smd roundrect
			(at -0.5 0)
			(size 0.6 0.6)
			(layers "B.Cu" "B.Mask" "B.Paste")
			(roundrect_rratio 0.25)
			(net 1 "GND")
			(pintype "passive")
		)
		(pad "2" smd roundrect
			(at 0.498 0 90)
			(size 0.6 0.6)
			(layers "B.Cu" "B.Mask" "B.Paste")
			(roundrect_rratio 0.25)
			(net 206 "+1V1")
			(pintype "passive")
		)
	)
	(footprint "antmicro-footprints:C_0402_1005Metric"
		(layer "B.Cu")
		(at 151.375501 162.801 -90)
		(descr "Capacitor SMD 0402 (1005 Metric), square (rectangular) end terminal, IPC_7351 nominal, (Body size source: IPC-SM-782 page 76, https://www.pcb-3d.com/wordpress/wp-content/uploads/ipc-sm-782a_amendment_1_and_2.pdf)")
		(tags "capacitor 0402")
		(property "Reference" "C89"
			(at 0 1.17 90)
			(layer "B.SilkS")
			(hide yes)
			(effects
				(font
					(size 0.7 0.7)
					(thickness 0.15)
				)
				(justify left bottom mirror)
			)
		)
		(property "Value" "C_100n_0402"
			(at 0 -1.169 90)
			(layer "B.Fab")
			(effects
				(font
					(size 0.7 0.7)
					(thickness 0.15)
				)
				(justify left bottom mirror)
			)
		)
		(property "Datasheet" "https://www.murata.com/products/productdetail?partno=GRM155R61H104KE14%23"
			(at 0 0 270)
			(layer "F.Fab")
			(hide yes)
			(effects
				(font
					(size 1.27 1.27)
					(thickness 0.15)
				)
			)
		)
		(property "Author" "Antmicro"
			(at -11.425499 314.176501 0)
			(layer "B.Fab")
			(hide yes)
			(effects
				(font
					(size 1 1)
					(thickness 0.15)
				)
				(justify mirror)
			)
		)
		(property "Dielectric" "X5R"
			(at -11.425499 314.176501 0)
			(layer "B.Fab")
			(hide yes)
			(effects
				(font
					(size 1 1)
					(thickness 0.15)
				)
				(justify mirror)
			)
		)
		(property "License" "Apache-2.0"
			(at -11.425499 314.176501 0)
			(layer "B.Fab")
			(hide yes)
			(effects
				(font
					(size 1 1)
					(thickness 0.15)
				)
				(justify mirror)
			)
		)
		(property "MPN" "GRM155R61H104KE14D"
			(at -11.425499 314.176501 0)
			(layer "B.Fab")
			(hide yes)
			(effects
				(font
					(size 1 1)
					(thickness 0.15)
				)
				(justify mirror)
			)
		)
		(property "Manufacturer" "Murata"
			(at -11.425499 314.176501 0)
			(layer "B.Fab")
			(hide yes)
			(effects
				(font
					(size 1 1)
					(thickness 0.15)
				)
				(justify mirror)
			)
		)
		(property "Val" "100n"
			(at -11.425499 314.176501 0)
			(layer "B.Fab")
			(hide yes)
			(effects
				(font
					(size 1 1)
					(thickness 0.15)
				)
				(justify mirror)
			)
		)
		(property "Voltage" "50V"
			(at -11.425499 314.176501 0)
			(layer "B.Fab")
			(hide yes)
			(effects
				(font
					(size 1 1)
					(thickness 0.15)
				)
				(justify mirror)
			)
		)
		(sheetname "/FPGA power/")
		(sheetfile "fpga-power.kicad_sch")
		(attr smd)
		(fp_rect
			(start -0.9656 0.4572)
			(end 0.9652 -0.4828)
			(stroke
				(width 0.05)
				(type solid)
			)
			(fill no)
			(layer "B.CrtYd")
		)
		(fp_line
			(start -0.5 0.25)
			(end 0.498 0.25)
			(stroke
				(width 0.15)
				(type solid)
			)
			(layer "B.Fab")
		)
		(fp_line
			(start 0.498 0.25)
			(end 0.498 -0.248)
			(stroke
				(width 0.15)
				(type solid)
			)
			(layer "B.Fab")
		)
		(fp_line
			(start -0.5 -0.248)
			(end -0.5 0.25)
			(stroke
				(width 0.15)
				(type solid)
			)
			(layer "B.Fab")
		)
		(fp_line
			(start 0.498 -0.248)
			(end -0.5 -0.248)
			(stroke
				(width 0.15)
				(type solid)
			)
			(layer "B.Fab")
		)
		(pad "1" smd roundrect
			(at -0.5 0 180)
			(size 0.6 0.6)
			(layers "B.Cu" "B.Mask" "B.Paste")
			(roundrect_rratio 0.25)
			(net 1 "GND")
			(pintype "passive")
		)
		(pad "2" smd roundrect
			(at 0.498 0 270)
			(size 0.6 0.6)
			(layers "B.Cu" "B.Mask" "B.Paste")
			(roundrect_rratio 0.25)
			(net 206 "+1V1")
			(pintype "passive")
		)
	)
	(footprint "antmicro-footprints:C_0402_1005Metric"
		(layer "B.Cu")
		(at 102.1 159.55)
		(descr "Capacitor SMD 0402")
		(tags "capacitor SMD 0402")
		(property "Reference" "C160"
			(at 0 0.699 180)
			(layer "B.SilkS")
			(hide yes)
			(effects
				(font
					(size 0.7 0.7)
					(thickness 0.15)
				)
				(justify left bottom mirror)
			)
		)
		(property "Value" "C_100n_0402"
			(at -1.022927 -2.155213 180)
			(layer "B.Fab")
			(effects
				(font
					(size 0.7 0.7)
					(thickness 0.15)
				)
				(justify left bottom mirror)
			)
		)
		(property "Datasheet" "https://www.murata.com/products/productdetail?partno=GRM155R61H104KE14%23"
			(at 0 0 0)
			(layer "F.Fab")
			(hide yes)
			(effects
				(font
					(size 1.27 1.27)
					(thickness 0.15)
				)
			)
		)
		(property "Author" "Antmicro"
			(at 0 0 0)
			(layer "B.Fab")
			(hide yes)
			(effects
				(font
					(size 1 1)
					(thickness 0.15)
				)
				(justify mirror)
			)
		)
		(property "Dielectric" "X5R"
			(at 0 0 0)
			(layer "B.Fab")
			(hide yes)
			(effects
				(font
					(size 1 1)
					(thickness 0.15)
				)
				(justify mirror)
			)
		)
		(property "License" "Apache-2.0"
			(at 0 0 0)
			(layer "B.Fab")
			(hide yes)
			(effects
				(font
					(size 1 1)
					(thickness 0.15)
				)
				(justify mirror)
			)
		)
		(property "MPN" "GRM155R61H104KE14D"
			(at 0 0 0)
			(layer "B.Fab")
			(hide yes)
			(effects
				(font
					(size 1 1)
					(thickness 0.15)
				)
				(justify mirror)
			)
		)
		(property "Manufacturer" "Murata"
			(at 0 0 0)
			(layer "B.Fab")
			(hide yes)
			(effects
				(font
					(size 1 1)
					(thickness 0.15)
				)
				(justify mirror)
			)
		)
		(property "Val" "100n"
			(at 0 0 0)
			(layer "B.Fab")
			(hide yes)
			(effects
				(font
					(size 1 1)
					(thickness 0.15)
				)
				(justify mirror)
			)
		)
		(property "Voltage" "50V"
			(at 0 0 0)
			(layer "B.Fab")
			(hide yes)
			(effects
				(font
					(size 1 1)
					(thickness 0.15)
				)
				(justify mirror)
			)
		)
		(sheetname "/Ethernet/")
		(sheetfile "ethernet.kicad_sch")
		(attr smd)
		(fp_rect
			(start -0.9659 0.481258)
			(end 0.9649 -0.458742)
			(stroke
				(width 0.05)
				(type solid)
			)
			(fill no)
			(layer "B.CrtYd")
		)
		(fp_line
			(start -0.499 -0.248)
			(end -0.499 0.25)
			(stroke
				(width 0.15)
				(type solid)
			)
			(layer "B.Fab")
		)
		(fp_line
			(start -0.499 0.25)
			(end 0.499 0.25)
			(stroke
				(width 0.15)
				(type solid)
			)
			(layer "B.Fab")
		)
		(fp_line
			(start 0.499 -0.248)
			(end -0.499 -0.248)
			(stroke
				(width 0.15)
				(type solid)
			)
			(layer "B.Fab")
		)
		(fp_line
			(start 0.499 0.25)
			(end 0.499 -0.248)
			(stroke
				(width 0.15)
				(type solid)
			)
			(layer "B.Fab")
		)
		(pad "1" smd roundrect
			(at -0.484 0)
			(size 0.59 0.64)
			(layers "B.Cu" "B.Mask" "B.Paste")
			(roundrect_rratio 0.25)
			(net 1 "GND")
			(pintype "passive")
		)
		(pad "2" smd roundrect
			(at 0.484 0)
			(size 0.59 0.64)
			(layers "B.Cu" "B.Mask" "B.Paste")
			(roundrect_rratio 0.25)
			(net 200 "+3V3")
			(pintype "passive")
		)
	)
	(footprint "antmicro-footprints:R_0402_1005Metric"
		(layer "B.Cu")
		(at 159.700501 179.676)
		(descr "Resistor SMD 0402")
		(tags "resistor SMD 0402")
		(property "Reference" "R17"
			(at -1.122484 0.772697 180)
			(layer "B.SilkS")
			(hide yes)
			(effects
				(font
					(size 0.7 0.7)
					(thickness 0.15)
				)
				(justify left bottom mirror)
			)
		)
		(property "Value" "R_10k_0402"
			(at -1.011843 -1.772047 180)
			(layer "B.Fab")
			(effects
				(font
					(size 0.7 0.7)
					(thickness 0.15)
				)
				(justify left bottom mirror)
			)
		)
		(property "Datasheet" "https://www.bourns.com/docs/product-datasheets/cr.pdf"
			(at 0 0 0)
			(layer "F.Fab")
			(hide yes)
			(effects
				(font
					(size 1.27 1.27)
					(thickness 0.15)
				)
			)
		)
		(property "Author" "Antmicro"
			(at 0 0 0)
			(layer "B.Fab")
			(hide yes)
			(effects
				(font
					(size 1 1)
					(thickness 0.15)
				)
				(justify mirror)
			)
		)
		(property "License" "Apache-2.0"
			(at 0 0 0)
			(layer "B.Fab")
			(hide yes)
			(effects
				(font
					(size 1 1)
					(thickness 0.15)
				)
				(justify mirror)
			)
		)
		(property "MPN" "CR0402-FX-1002GLF"
			(at 0 0 0)
			(layer "B.Fab")
			(hide yes)
			(effects
				(font
					(size 1 1)
					(thickness 0.15)
				)
				(justify mirror)
			)
		)
		(property "Manufacturer" "Bourns"
			(at 0 0 0)
			(layer "B.Fab")
			(hide yes)
			(effects
				(font
					(size 1 1)
					(thickness 0.15)
				)
				(justify mirror)
			)
		)
		(property "Tolerance" "1%"
			(at 0 0 0)
			(layer "B.Fab")
			(hide yes)
			(effects
				(font
					(size 1 1)
					(thickness 0.15)
				)
				(justify mirror)
			)
		)
		(property "Val" "10k"
			(at 0 0 0)
			(layer "B.Fab")
			(hide yes)
			(effects
				(font
					(size 1 1)
					(thickness 0.15)
				)
				(justify mirror)
			)
		)
		(sheetname "/FPGA Config/")
		(sheetfile "fpga-config.kicad_sch")
		(attr smd)
		(fp_rect
			(start -0.93 0.47)
			(end 0.93 -0.47)
			(stroke
				(width 0.05)
				(type solid)
			)
			(fill no)
			(layer "B.CrtYd")
		)
		(fp_rect
			(start -0.5 0.25)
			(end 0.5 -0.25)
			(stroke
				(width 0.15)
				(type solid)
			)
			(fill no)
			(layer "B.Fab")
		)
		(pad "1" smd roundrect
			(at -0.485 0)
			(size 0.59 0.64)
			(layers "B.Cu" "B.Mask" "B.Paste")
			(roundrect_rratio 0.25)
			(net 633 "/FPGA Config/MODE0")
			(pintype "passive")
		)
		(pad "2" smd roundrect
			(at 0.485 0)
			(size 0.59 0.64)
			(layers "B.Cu" "B.Mask" "B.Paste")
			(roundrect_rratio 0.25)
			(net 200 "+3V3")
			(pintype "passive")
		)
	)
	(footprint "antmicro-footprints:C_0402_1005Metric"
		(layer "B.Cu")
		(at 141.875001 179.3025)
		(descr "Capacitor SMD 0402 (1005 Metric), square (rectangular) end terminal, IPC_7351 nominal, (Body size source: IPC-SM-782 page 76, https://www.pcb-3d.com/wordpress/wp-content/uploads/ipc-sm-782a_amendment_1_and_2.pdf)")
		(tags "capacitor 0402")
		(property "Reference" "C13"
			(at 0 1.17 180)
			(layer "B.SilkS")
			(hide yes)
			(effects
				(font
					(size 0.7 0.7)
					(thickness 0.15)
				)
				(justify left bottom mirror)
			)
		)
		(property "Value" "C_100n_0402"
			(at 0 -1.169 180)
			(layer "B.Fab")
			(effects
				(font
					(size 0.7 0.7)
					(thickness 0.15)
				)
				(justify left bottom mirror)
			)
		)
		(property "Datasheet" "https://www.murata.com/products/productdetail?partno=GRM155R61H104KE14%23"
			(at 0 0 0)
			(layer "F.Fab")
			(hide yes)
			(effects
				(font
					(size 1.27 1.27)
					(thickness 0.15)
				)
			)
		)
		(property "Author" "Antmicro"
			(at 0 0 0)
			(layer "B.Fab")
			(hide yes)
			(effects
				(font
					(size 1 1)
					(thickness 0.15)
				)
				(justify mirror)
			)
		)
		(property "Dielectric" "X5R"
			(at 0 0 0)
			(layer "B.Fab")
			(hide yes)
			(effects
				(font
					(size 1 1)
					(thickness 0.15)
				)
				(justify mirror)
			)
		)
		(property "License" "Apache-2.0"
			(at 0 0 0)
			(layer "B.Fab")
			(hide yes)
			(effects
				(font
					(size 1 1)
					(thickness 0.15)
				)
				(justify mirror)
			)
		)
		(property "MPN" "GRM155R61H104KE14D"
			(at 0 0 0)
			(layer "B.Fab")
			(hide yes)
			(effects
				(font
					(size 1 1)
					(thickness 0.15)
				)
				(justify mirror)
			)
		)
		(property "Manufacturer" "Murata"
			(at 0 0 0)
			(layer "B.Fab")
			(hide yes)
			(effects
				(font
					(size 1 1)
					(thickness 0.15)
				)
				(justify mirror)
			)
		)
		(property "Val" "100n"
			(at 0 0 0)
			(layer "B.Fab")
			(hide yes)
			(effects
				(font
					(size 1 1)
					(thickness 0.15)
				)
				(justify mirror)
			)
		)
		(property "Voltage" "50V"
			(at 0 0 0)
			(layer "B.Fab")
			(hide yes)
			(effects
				(font
					(size 1 1)
					(thickness 0.15)
				)
				(justify mirror)
			)
		)
		(sheetname "/FPGA power/")
		(sheetfile "fpga-power.kicad_sch")
		(attr smd)
		(fp_rect
			(start -0.9656 0.4572)
			(end 0.9652 -0.4828)
			(stroke
				(width 0.05)
				(type solid)
			)
			(fill no)
			(layer "B.CrtYd")
		)
		(fp_line
			(start -0.5 -0.248)
			(end -0.5 0.25)
			(stroke
				(width 0.15)
				(type solid)
			)
			(layer "B.Fab")
		)
		(fp_line
			(start -0.5 0.25)
			(end 0.498 0.25)
			(stroke
				(width 0.15)
				(type solid)
			)
			(layer "B.Fab")
		)
		(fp_line
			(start 0.498 -0.248)
			(end -0.5 -0.248)
			(stroke
				(width 0.15)
				(type solid)
			)
			(layer "B.Fab")
		)
		(fp_line
			(start 0.498 0.25)
			(end 0.498 -0.248)
			(stroke
				(width 0.15)
				(type solid)
			)
			(layer "B.Fab")
		)
		(pad "1" smd roundrect
			(at -0.5 0 270)
			(size 0.6 0.6)
			(layers "B.Cu" "B.Mask" "B.Paste")
			(roundrect_rratio 0.25)
			(net 1 "GND")
			(pintype "passive")
		)
		(pad "2" smd roundrect
			(at 0.498 0)
			(size 0.6 0.6)
			(layers "B.Cu" "B.Mask" "B.Paste")
			(roundrect_rratio 0.25)
			(net 227 "+1V0")
			(pintype "passive")
		)
	)
	(footprint "antmicro-footprints:C_0402_1005Metric"
		(layer "B.Cu")
		(at 137.375501 168.801 90)
		(descr "Capacitor SMD 0402 (1005 Metric), square (rectangular) end terminal, IPC_7351 nominal, (Body size source: IPC-SM-782 page 76, https://www.pcb-3d.com/wordpress/wp-content/uploads/ipc-sm-782a_amendment_1_and_2.pdf)")
		(tags "capacitor 0402")
		(property "Reference" "C49"
			(at 0 1.17 270)
			(layer "B.SilkS")
			(hide yes)
			(effects
				(font
					(size 0.7 0.7)
					(thickness 0.15)
				)
				(justify left bottom mirror)
			)
		)
		(property "Value" "C_100n_0402"
			(at 0 -1.169 270)
			(layer "B.Fab")
			(effects
				(font
					(size 0.7 0.7)
					(thickness 0.15)
				)
				(justify left bottom mirror)
			)
		)
		(property "Datasheet" "https://www.murata.com/products/productdetail?partno=GRM155R61H104KE14%23"
			(at 0 0 90)
			(layer "F.Fab")
			(hide yes)
			(effects
				(font
					(size 1.27 1.27)
					(thickness 0.15)
				)
			)
		)
		(property "Author" "Antmicro"
			(at 306.176501 31.425499 0)
			(layer "B.Fab")
			(hide yes)
			(effects
				(font
					(size 1 1)
					(thickness 0.15)
				)
				(justify mirror)
			)
		)
		(property "Dielectric" "X5R"
			(at 306.176501 31.425499 0)
			(layer "B.Fab")
			(hide yes)
			(effects
				(font
					(size 1 1)
					(thickness 0.15)
				)
				(justify mirror)
			)
		)
		(property "License" "Apache-2.0"
			(at 306.176501 31.425499 0)
			(layer "B.Fab")
			(hide yes)
			(effects
				(font
					(size 1 1)
					(thickness 0.15)
				)
				(justify mirror)
			)
		)
		(property "MPN" "GRM155R61H104KE14D"
			(at 306.176501 31.425499 0)
			(layer "B.Fab")
			(hide yes)
			(effects
				(font
					(size 1 1)
					(thickness 0.15)
				)
				(justify mirror)
			)
		)
		(property "Manufacturer" "Murata"
			(at 306.176501 31.425499 0)
			(layer "B.Fab")
			(hide yes)
			(effects
				(font
					(size 1 1)
					(thickness 0.15)
				)
				(justify mirror)
			)
		)
		(property "Val" "100n"
			(at 306.176501 31.425499 0)
			(layer "B.Fab")
			(hide yes)
			(effects
				(font
					(size 1 1)
					(thickness 0.15)
				)
				(justify mirror)
			)
		)
		(property "Voltage" "50V"
			(at 306.176501 31.425499 0)
			(layer "B.Fab")
			(hide yes)
			(effects
				(font
					(size 1 1)
					(thickness 0.15)
				)
				(justify mirror)
			)
		)
		(sheetname "/FPGA power/")
		(sheetfile "fpga-power.kicad_sch")
		(attr smd)
		(fp_rect
			(start -0.9656 0.4572)
			(end 0.9652 -0.4828)
			(stroke
				(width 0.05)
				(type solid)
			)
			(fill no)
			(layer "B.CrtYd")
		)
		(fp_line
			(start 0.498 -0.248)
			(end -0.5 -0.248)
			(stroke
				(width 0.15)
				(type solid)
			)
			(layer "B.Fab")
		)
		(fp_line
			(start -0.5 -0.248)
			(end -0.5 0.25)
			(stroke
				(width 0.15)
				(type solid)
			)
			(layer "B.Fab")
		)
		(fp_line
			(start 0.498 0.25)
			(end 0.498 -0.248)
			(stroke
				(width 0.15)
				(type solid)
			)
			(layer "B.Fab")
		)
		(fp_line
			(start -0.5 0.25)
			(end 0.498 0.25)
			(stroke
				(width 0.15)
				(type solid)
			)
			(layer "B.Fab")
		)
		(pad "1" smd roundrect
			(at -0.5 0)
			(size 0.6 0.6)
			(layers "B.Cu" "B.Mask" "B.Paste")
			(roundrect_rratio 0.25)
			(net 1 "GND")
			(pintype "passive")
		)
		(pad "2" smd roundrect
			(at 0.498 0 90)
			(size 0.6 0.6)
			(layers "B.Cu" "B.Mask" "B.Paste")
			(roundrect_rratio 0.25)
			(net 206 "+1V1")
			(pintype "passive")
		)
	)
	(footprint "antmicro-footprints:C_0402_1005Metric"
		(layer "B.Cu")
		(at 146.375001 181.8025 90)
		(descr "Capacitor SMD 0402 (1005 Metric), square (rectangular) end terminal, IPC_7351 nominal, (Body size source: IPC-SM-782 page 76, https://www.pcb-3d.com/wordpress/wp-content/uploads/ipc-sm-782a_amendment_1_and_2.pdf)")
		(tags "capacitor 0402")
		(property "Reference" "C100"
			(at 0 1.17 270)
			(layer "B.SilkS")
			(hide yes)
			(effects
				(font
					(size 0.7 0.7)
					(thickness 0.15)
				)
				(justify left bottom mirror)
			)
		)
		(property "Value" "C_100n_0402"
			(at 0 -1.169 270)
			(layer "B.Fab")
			(effects
				(font
					(size 0.7 0.7)
					(thickness 0.15)
				)
				(justify left bottom mirror)
			)
		)
		(property "Datasheet" "https://www.murata.com/products/productdetail?partno=GRM155R61H104KE14%23"
			(at 0 0 90)
			(layer "F.Fab")
			(hide yes)
			(effects
				(font
					(size 1.27 1.27)
					(thickness 0.15)
				)
			)
		)
		(property "Author" "Antmicro"
			(at 328.177501 35.427499 0)
			(layer "B.Fab")
			(hide yes)
			(effects
				(font
					(size 1 1)
					(thickness 0.15)
				)
				(justify mirror)
			)
		)
		(property "Dielectric" "X5R"
			(at 328.177501 35.427499 0)
			(layer "B.Fab")
			(hide yes)
			(effects
				(font
					(size 1 1)
					(thickness 0.15)
				)
				(justify mirror)
			)
		)
		(property "License" "Apache-2.0"
			(at 328.177501 35.427499 0)
			(layer "B.Fab")
			(hide yes)
			(effects
				(font
					(size 1 1)
					(thickness 0.15)
				)
				(justify mirror)
			)
		)
		(property "MPN" "GRM155R61H104KE14D"
			(at 328.177501 35.427499 0)
			(layer "B.Fab")
			(hide yes)
			(effects
				(font
					(size 1 1)
					(thickness 0.15)
				)
				(justify mirror)
			)
		)
		(property "Manufacturer" "Murata"
			(at 328.177501 35.427499 0)
			(layer "B.Fab")
			(hide yes)
			(effects
				(font
					(size 1 1)
					(thickness 0.15)
				)
				(justify mirror)
			)
		)
		(property "Val" "100n"
			(at 328.177501 35.427499 0)
			(layer "B.Fab")
			(hide yes)
			(effects
				(font
					(size 1 1)
					(thickness 0.15)
				)
				(justify mirror)
			)
		)
		(property "Voltage" "50V"
			(at 328.177501 35.427499 0)
			(layer "B.Fab")
			(hide yes)
			(effects
				(font
					(size 1 1)
					(thickness 0.15)
				)
				(justify mirror)
			)
		)
		(sheetname "/FPGA power/")
		(sheetfile "fpga-power.kicad_sch")
		(attr smd)
		(fp_rect
			(start -0.9656 0.4572)
			(end 0.9652 -0.4828)
			(stroke
				(width 0.05)
				(type solid)
			)
			(fill no)
			(layer "B.CrtYd")
		)
		(fp_line
			(start 0.498 -0.248)
			(end -0.5 -0.248)
			(stroke
				(width 0.15)
				(type solid)
			)
			(layer "B.Fab")
		)
		(fp_line
			(start -0.5 -0.248)
			(end -0.5 0.25)
			(stroke
				(width 0.15)
				(type solid)
			)
			(layer "B.Fab")
		)
		(fp_line
			(start 0.498 0.25)
			(end 0.498 -0.248)
			(stroke
				(width 0.15)
				(type solid)
			)
			(layer "B.Fab")
		)
		(fp_line
			(start -0.5 0.25)
			(end 0.498 0.25)
			(stroke
				(width 0.15)
				(type solid)
			)
			(layer "B.Fab")
		)
		(pad "1" smd roundrect
			(at -0.5 0)
			(size 0.6 0.6)
			(layers "B.Cu" "B.Mask" "B.Paste")
			(roundrect_rratio 0.25)
			(net 1 "GND")
			(pintype "passive")
		)
		(pad "2" smd roundrect
			(at 0.498 0 90)
			(size 0.6 0.6)
			(layers "B.Cu" "B.Mask" "B.Paste")
			(roundrect_rratio 0.25)
			(net 187 "+1V0_MGTAVCC")
			(pintype "passive")
		)
	)
	(footprint "antmicro-footprints:R_0402_1005Metric"
		(layer "B.Cu")
		(at 180.8 191 180)
		(descr "Resistor SMD 0402")
		(tags "resistor SMD 0402")
		(property "Reference" "R177"
			(at 1.25 -0.4 0)
			(layer "B.SilkS")
			(effects
				(font
					(size 0.7 0.7)
					(thickness 0.15)
				)
				(justify left bottom mirror)
			)
		)
		(property "Value" "R_0R_0402"
			(at -1.011843 -1.772047 0)
			(layer "B.Fab")
			(effects
				(font
					(size 0.7 0.7)
					(thickness 0.15)
				)
				(justify left bottom mirror)
			)
		)
		(property "Datasheet" "https://industrial.panasonic.com/cdbs/www-data/pdf/RDA0000/AOA0000C301.pdf"
			(at 0 0 180)
			(layer "F.Fab")
			(hide yes)
			(effects
				(font
					(size 1.27 1.27)
					(thickness 0.15)
				)
			)
		)
		(property "Author" "Antmicro"
			(at 361.6 382 0)
			(layer "B.Fab")
			(hide yes)
			(effects
				(font
					(size 1 1)
					(thickness 0.15)
				)
				(justify mirror)
			)
		)
		(property "Current" "1A"
			(at 361.6 382 0)
			(layer "B.Fab")
			(hide yes)
			(effects
				(font
					(size 1 1)
					(thickness 0.15)
				)
				(justify mirror)
			)
		)
		(property "License" "Apache-2.0"
			(at 361.6 382 0)
			(layer "B.Fab")
			(hide yes)
			(effects
				(font
					(size 1 1)
					(thickness 0.15)
				)
				(justify mirror)
			)
		)
		(property "MPN" "ERJ2GE0R00X"
			(at 361.6 382 0)
			(layer "B.Fab")
			(hide yes)
			(effects
				(font
					(size 1 1)
					(thickness 0.15)
				)
				(justify mirror)
			)
		)
		(property "Manufacturer" "Panasonic"
			(at 361.6 382 0)
			(layer "B.Fab")
			(hide yes)
			(effects
				(font
					(size 1 1)
					(thickness 0.15)
				)
				(justify mirror)
			)
		)
		(property "Tolerance" ""
			(at 361.6 382 0)
			(layer "B.Fab")
			(hide yes)
			(effects
				(font
					(size 1 1)
					(thickness 0.15)
				)
				(justify mirror)
			)
		)
		(property "Val" "0R"
			(at 361.6 382 0)
			(layer "B.Fab")
			(hide yes)
			(effects
				(font
					(size 1 1)
					(thickness 0.15)
				)
				(justify mirror)
			)
		)
		(sheetname "/I^{2}C/")
		(sheetfile "i2c.kicad_sch")
		(attr exclude_from_pos_files exclude_from_bom dnp)
		(fp_rect
			(start -0.93 0.47)
			(end 0.93 -0.47)
			(stroke
				(width 0.05)
				(type solid)
			)
			(fill no)
			(layer "B.CrtYd")
		)
		(fp_rect
			(start -0.5 0.25)
			(end 0.5 -0.25)
			(stroke
				(width 0.15)
				(type solid)
			)
			(fill no)
			(layer "B.Fab")
		)
		(pad "1" smd roundrect
			(at -0.485 0 180)
			(size 0.59 0.64)
			(layers "B.Cu" "B.Mask" "B.Paste")
			(roundrect_rratio 0.25)
			(net 691 "/I^{2}C/PWR.SCL")
			(pintype "passive")
		)
		(pad "2" smd roundrect
			(at 0.485 0 180)
			(size 0.59 0.64)
			(layers "B.Cu" "B.Mask" "B.Paste")
			(roundrect_rratio 0.25)
			(net 682 "/FPGA bank 14/FPGA_DDR.SCL")
			(pintype "passive")
		)
	)
	(footprint "antmicro-footprints:R_0402_1005Metric"
		(layer "B.Cu")
		(at 107.4 142.4 90)
		(descr "Resistor SMD 0402")
		(tags "resistor SMD 0402")
		(property "Reference" "R33"
			(at 3.044968 0.254606 270)
			(layer "B.SilkS")
			(effects
				(font
					(size 0.7 0.7)
					(thickness 0.15)
				)
				(justify left bottom mirror)
			)
		)
		(property "Value" "R_0R_0402"
			(at -1.011843 -1.772047 270)
			(layer "B.Fab")
			(effects
				(font
					(size 0.7 0.7)
					(thickness 0.15)
				)
				(justify left bottom mirror)
			)
		)
		(property "Datasheet" "https://industrial.panasonic.com/cdbs/www-data/pdf/RDA0000/AOA0000C301.pdf"
			(at 0 0 90)
			(layer "F.Fab")
			(hide yes)
			(effects
				(font
					(size 1.27 1.27)
					(thickness 0.15)
				)
			)
		)
		(property "Author" "Antmicro"
			(at 249.8 35 0)
			(layer "B.Fab")
			(hide yes)
			(effects
				(font
					(size 1 1)
					(thickness 0.15)
				)
				(justify mirror)
			)
		)
		(property "Current" "1A"
			(at 249.8 35 0)
			(layer "B.Fab")
			(hide yes)
			(effects
				(font
					(size 1 1)
					(thickness 0.15)
				)
				(justify mirror)
			)
		)
		(property "License" "Apache-2.0"
			(at 249.8 35 0)
			(layer "B.Fab")
			(hide yes)
			(effects
				(font
					(size 1 1)
					(thickness 0.15)
				)
				(justify mirror)
			)
		)
		(property "MPN" "ERJ2GE0R00X"
			(at 249.8 35 0)
			(layer "B.Fab")
			(hide yes)
			(effects
				(font
					(size 1 1)
					(thickness 0.15)
				)
				(justify mirror)
			)
		)
		(property "Manufacturer" "Panasonic"
			(at 249.8 35 0)
			(layer "B.Fab")
			(hide yes)
			(effects
				(font
					(size 1 1)
					(thickness 0.15)
				)
				(justify mirror)
			)
		)
		(property "Tolerance" ""
			(at 249.8 35 0)
			(layer "B.Fab")
			(hide yes)
			(effects
				(font
					(size 1 1)
					(thickness 0.15)
				)
				(justify mirror)
			)
		)
		(property "Val" "0R"
			(at 249.8 35 0)
			(layer "B.Fab")
			(hide yes)
			(effects
				(font
					(size 1 1)
					(thickness 0.15)
				)
				(justify mirror)
			)
		)
		(sheetname "/DDR5 SODIMM/")
		(sheetfile "ddr5-sodimm.kicad_sch")
		(attr exclude_from_pos_files exclude_from_bom dnp)
		(fp_rect
			(start -0.93 0.47)
			(end 0.93 -0.47)
			(stroke
				(width 0.05)
				(type solid)
			)
			(fill no)
			(layer "B.CrtYd")
		)
		(fp_rect
			(start -0.5 0.25)
			(end 0.5 -0.25)
			(stroke
				(width 0.15)
				(type solid)
			)
			(fill no)
			(layer "B.Fab")
		)
		(pad "1" smd roundrect
			(at -0.485 0 90)
			(size 0.59 0.64)
			(layers "B.Cu" "B.Mask" "B.Paste")
			(roundrect_rratio 0.25)
			(net 137 "/DDR5 SODIMM/RFU1")
			(pintype "passive")
		)
		(pad "2" smd roundrect
			(at 0.485 0 90)
			(size 0.59 0.64)
			(layers "B.Cu" "B.Mask" "B.Paste")
			(roundrect_rratio 0.25)
			(net 273 "RFU_1")
			(pintype "passive")
		)
	)
	(footprint "antmicro-footprints:TP_SMD_1mm"
		(layer "B.Cu")
		(at 203.1 154.3 90)
		(property "Reference" "TP37"
			(at -3.4 -0.3 90)
			(layer "B.SilkS")
			(effects
				(font
					(size 0.7 0.7)
					(thickness 0.15)
				)
				(justify right top mirror)
			)
		)
		(property "Value" "TP_1mm_SMD"
			(at 0 -1.4 90)
			(layer "B.Fab")
			(effects
				(font
					(size 0.7 0.7)
					(thickness 0.15)
				)
				(justify right top mirror)
			)
		)
		(property "MPN" ""
			(at 0 0 270)
			(unlocked yes)
			(layer "B.Fab")
			(hide yes)
			(effects
				(font
					(size 1 1)
					(thickness 0.15)
				)
				(justify mirror)
			)
		)
		(property "Manufacturer" ""
			(at 0 0 270)
			(unlocked yes)
			(layer "B.Fab")
			(hide yes)
			(effects
				(font
					(size 1 1)
					(thickness 0.15)
				)
				(justify mirror)
			)
		)
		(property "Author" "Antmicro"
			(at 0 0 270)
			(unlocked yes)
			(layer "B.Fab")
			(hide yes)
			(effects
				(font
					(size 1 1)
					(thickness 0.15)
				)
				(justify mirror)
			)
		)
		(property "License" "Apache-2.0"
			(at 0 0 270)
			(unlocked yes)
			(layer "B.Fab")
			(hide yes)
			(effects
				(font
					(size 1 1)
					(thickness 0.15)
				)
				(justify mirror)
			)
		)
		(sheetname "/I^{2}C/")
		(sheetfile "i2c.kicad_sch")
		(attr exclude_from_pos_files)
		(fp_circle
			(center 0 0)
			(end 0.6 0)
			(stroke
				(width 0.05)
				(type default)
			)
			(fill no)
			(layer "B.CrtYd")
		)
		(fp_text user "Author: Antmicro"
			(at -0.5 -4 90)
			(layer "B.Fab")
			(effects
				(font
					(size 0.7 0.7)
					(thickness 0.15)
				)
				(justify right top mirror)
			)
		)
		(fp_text user "License: Apache-2.0"
			(at -0.5 -5.2 90)
			(layer "B.Fab")
			(effects
				(font
					(size 0.7 0.7)
					(thickness 0.15)
				)
				(justify right top mirror)
			)
		)
		(fp_text user "${REFERENCE}"
			(at -0.5 -2.8 90)
			(layer "B.Fab")
			(effects
				(font
					(size 0.7 0.7)
					(thickness 0.15)
				)
				(justify right top mirror)
			)
		)
		(pad "1" smd circle
			(at 0 0 90)
			(size 1 1)
			(layers "B.Cu" "B.Mask")
			(net 691 "/I^{2}C/PWR.SCL")
			(pinfunction "1")
			(pintype "passive")
		)
	)
	(footprint "antmicro-footprints:C_0603_1608Metric"
		(layer "B.Cu")
		(at 136.075001 160.2025 90)
		(descr "Capacitor SMD 0603")
		(tags "capacitor 0603")
		(property "Reference" "C85"
			(at 0 0.9 90)
			(layer "B.SilkS")
			(hide yes)
			(effects
				(font
					(size 0.7 0.7)
					(thickness 0.15)
				)
				(justify right bottom mirror)
			)
		)
		(property "Value" "C_47u_0603"
			(at 0 -1.6 90)
			(layer "B.Fab")
			(effects
				(font
					(size 0.7 0.7)
					(thickness 0.15)
				)
				(justify right bottom mirror)
			)
		)
		(property "Datasheet" "https://www.murata.com/products/productdetail?partno=GRM188R60J476ME15%23"
			(at 0 0 90)
			(layer "F.Fab")
			(hide yes)
			(effects
				(font
					(size 1.27 1.27)
					(thickness 0.15)
				)
			)
		)
		(property "Author" "Antmicro"
			(at 296.277501 24.127499 0)
			(layer "B.Fab")
			(hide yes)
			(effects
				(font
					(size 1 1)
					(thickness 0.15)
				)
				(justify mirror)
			)
		)
		(property "Dielectric" ""
			(at 296.277501 24.127499 0)
			(layer "B.Fab")
			(hide yes)
			(effects
				(font
					(size 1 1)
					(thickness 0.15)
				)
				(justify mirror)
			)
		)
		(property "License" "Apache-2.0"
			(at 296.277501 24.127499 0)
			(layer "B.Fab")
			(hide yes)
			(effects
				(font
					(size 1 1)
					(thickness 0.15)
				)
				(justify mirror)
			)
		)
		(property "MPN" "GRM188R60J476ME15D"
			(at 296.277501 24.127499 0)
			(layer "B.Fab")
			(hide yes)
			(effects
				(font
					(size 1 1)
					(thickness 0.15)
				)
				(justify mirror)
			)
		)
		(property "Manufacturer" "Murata"
			(at 296.277501 24.127499 0)
			(layer "B.Fab")
			(hide yes)
			(effects
				(font
					(size 1 1)
					(thickness 0.15)
				)
				(justify mirror)
			)
		)
		(property "Val" "47u"
			(at 296.277501 24.127499 0)
			(layer "B.Fab")
			(hide yes)
			(effects
				(font
					(size 1 1)
					(thickness 0.15)
				)
				(justify mirror)
			)
		)
		(property "Voltage" ""
			(at 296.277501 24.127499 0)
			(layer "B.Fab")
			(hide yes)
			(effects
				(font
					(size 1 1)
					(thickness 0.15)
				)
				(justify mirror)
			)
		)
		(sheetname "/FPGA power/")
		(sheetfile "fpga-power.kicad_sch")
		(attr smd)
		(fp_line
			(start -0.3 -0.3)
			(end 0.3 -0.3)
			(stroke
				(width 0.15)
				(type solid)
			)
			(layer "B.SilkS")
		)
		(fp_line
			(start -0.3 0.3)
			(end 0.3 0.3)
			(stroke
				(width 0.15)
				(type solid)
			)
			(layer "B.SilkS")
		)
		(fp_rect
			(start -1.24 0.7)
			(end 1.24 -0.7)
			(stroke
				(width 0.05)
				(type solid)
			)
			(fill no)
			(layer "B.CrtYd")
		)
		(fp_rect
			(start -0.8 0.4)
			(end 0.8 -0.4)
			(stroke
				(width 0.15)
				(type solid)
			)
			(fill no)
			(layer "B.Fab")
		)
		(pad "1" smd roundrect
			(at -0.7 0 90)
			(size 0.6 0.8)
			(layers "B.Cu" "B.Mask" "B.Paste")
			(roundrect_rratio 0.2)
			(net 206 "+1V1")
			(pintype "passive")
		)
		(pad "2" smd roundrect
			(at 0.7 0 90)
			(size 0.6 0.8)
			(layers "B.Cu" "B.Mask" "B.Paste")
			(roundrect_rratio 0.2)
			(net 1 "GND")
			(pintype "passive")
		)
	)
	(footprint "antmicro-footprints:R_0402_1005Metric"
		(layer "B.Cu")
		(at 123.15 183.099999)
		(descr "Resistor SMD 0402")
		(tags "resistor SMD 0402")
		(property "Reference" "R3"
			(at -1.122484 0.772697 180)
			(layer "B.SilkS")
			(hide yes)
			(effects
				(font
					(size 0.7 0.7)
					(thickness 0.15)
				)
				(justify left bottom mirror)
			)
		)
		(property "Value" "R_2k2_0402"
			(at -1.011843 -1.772047 180)
			(layer "B.Fab")
			(effects
				(font
					(size 0.7 0.7)
					(thickness 0.15)
				)
				(justify left bottom mirror)
			)
		)
		(property "Datasheet" "https://www.bourns.com/docs/product-datasheets/cr.pdf"
			(at 0 0 0)
			(layer "F.Fab")
			(hide yes)
			(effects
				(font
					(size 1.27 1.27)
					(thickness 0.15)
				)
			)
		)
		(property "Author" "Antmicro"
			(at 0 0 0)
			(layer "B.Fab")
			(hide yes)
			(effects
				(font
					(size 1 1)
					(thickness 0.15)
				)
				(justify mirror)
			)
		)
		(property "License" "Apache-2.0"
			(at 0 0 0)
			(layer "B.Fab")
			(hide yes)
			(effects
				(font
					(size 1 1)
					(thickness 0.15)
				)
				(justify mirror)
			)
		)
		(property "MPN" "CR0402-FX-2201GLF"
			(at 0 0 0)
			(layer "B.Fab")
			(hide yes)
			(effects
				(font
					(size 1 1)
					(thickness 0.15)
				)
				(justify mirror)
			)
		)
		(property "Manufacturer" "Bourns"
			(at 0 0 0)
			(layer "B.Fab")
			(hide yes)
			(effects
				(font
					(size 1 1)
					(thickness 0.15)
				)
				(justify mirror)
			)
		)
		(property "Tolerance" "1%"
			(at 0 0 0)
			(layer "B.Fab")
			(hide yes)
			(effects
				(font
					(size 1 1)
					(thickness 0.15)
				)
				(justify mirror)
			)
		)
		(property "Val" "2k2"
			(at 0 0 0)
			(layer "B.Fab")
			(hide yes)
			(effects
				(font
					(size 1 1)
					(thickness 0.15)
				)
				(justify mirror)
			)
		)
		(sheetname "/HyperRAM + QSPI Flash/")
		(sheetfile "hyperram-flash.kicad_sch")
		(attr smd)
		(fp_rect
			(start -0.93 0.47)
			(end 0.93 -0.47)
			(stroke
				(width 0.05)
				(type solid)
			)
			(fill no)
			(layer "B.CrtYd")
		)
		(fp_rect
			(start -0.5 0.25)
			(end 0.5 -0.25)
			(stroke
				(width 0.15)
				(type solid)
			)
			(fill no)
			(layer "B.Fab")
		)
		(pad "1" smd roundrect
			(at -0.485 0)
			(size 0.59 0.64)
			(layers "B.Cu" "B.Mask" "B.Paste")
			(roundrect_rratio 0.25)
			(net 200 "+3V3")
			(pintype "passive")
		)
		(pad "2" smd roundrect
			(at 0.485 0)
			(size 0.59 0.64)
			(layers "B.Cu" "B.Mask" "B.Paste")
			(roundrect_rratio 0.25)
			(net 625 "/FPGA Config/FLASH.~{CS}")
			(pintype "passive")
		)
	)
	(footprint "antmicro-footprints:R_0402_1005Metric"
		(layer "B.Cu")
		(at 180.8 192 180)
		(descr "Resistor SMD 0402")
		(tags "resistor SMD 0402")
		(property "Reference" "R179"
			(at 1.25 -0.4 0)
			(layer "B.SilkS")
			(effects
				(font
					(size 0.7 0.7)
					(thickness 0.15)
				)
				(justify left bottom mirror)
			)
		)
		(property "Value" "R_0R_0402"
			(at -1.011843 -1.772047 0)
			(layer "B.Fab")
			(effects
				(font
					(size 0.7 0.7)
					(thickness 0.15)
				)
				(justify left bottom mirror)
			)
		)
		(property "Datasheet" "https://industrial.panasonic.com/cdbs/www-data/pdf/RDA0000/AOA0000C301.pdf"
			(at 0 0 180)
			(layer "F.Fab")
			(hide yes)
			(effects
				(font
					(size 1.27 1.27)
					(thickness 0.15)
				)
			)
		)
		(property "Author" "Antmicro"
			(at 361.6 384 0)
			(layer "B.Fab")
			(hide yes)
			(effects
				(font
					(size 1 1)
					(thickness 0.15)
				)
				(justify mirror)
			)
		)
		(property "Current" "1A"
			(at 361.6 384 0)
			(layer "B.Fab")
			(hide yes)
			(effects
				(font
					(size 1 1)
					(thickness 0.15)
				)
				(justify mirror)
			)
		)
		(property "License" "Apache-2.0"
			(at 361.6 384 0)
			(layer "B.Fab")
			(hide yes)
			(effects
				(font
					(size 1 1)
					(thickness 0.15)
				)
				(justify mirror)
			)
		)
		(property "MPN" "ERJ2GE0R00X"
			(at 361.6 384 0)
			(layer "B.Fab")
			(hide yes)
			(effects
				(font
					(size 1 1)
					(thickness 0.15)
				)
				(justify mirror)
			)
		)
		(property "Manufacturer" "Panasonic"
			(at 361.6 384 0)
			(layer "B.Fab")
			(hide yes)
			(effects
				(font
					(size 1 1)
					(thickness 0.15)
				)
				(justify mirror)
			)
		)
		(property "Tolerance" ""
			(at 361.6 384 0)
			(layer "B.Fab")
			(hide yes)
			(effects
				(font
					(size 1 1)
					(thickness 0.15)
				)
				(justify mirror)
			)
		)
		(property "Val" "0R"
			(at 361.6 384 0)
			(layer "B.Fab")
			(hide yes)
			(effects
				(font
					(size 1 1)
					(thickness 0.15)
				)
				(justify mirror)
			)
		)
		(sheetname "/I^{2}C/")
		(sheetfile "i2c.kicad_sch")
		(attr exclude_from_pos_files exclude_from_bom dnp)
		(fp_rect
			(start -0.93 0.47)
			(end 0.93 -0.47)
			(stroke
				(width 0.05)
				(type solid)
			)
			(fill no)
			(layer "B.CrtYd")
		)
		(fp_rect
			(start -0.5 0.25)
			(end 0.5 -0.25)
			(stroke
				(width 0.15)
				(type solid)
			)
			(fill no)
			(layer "B.Fab")
		)
		(pad "1" smd roundrect
			(at -0.485 0 180)
			(size 0.59 0.64)
			(layers "B.Cu" "B.Mask" "B.Paste")
			(roundrect_rratio 0.25)
			(net 691 "/I^{2}C/PWR.SCL")
			(pintype "passive")
		)
		(pad "2" smd roundrect
			(at 0.485 0 180)
			(size 0.59 0.64)
			(layers "B.Cu" "B.Mask" "B.Paste")
			(roundrect_rratio 0.25)
			(net 671 "/Debug FTDI/FTDI.SCL")
			(pintype "passive")
		)
	)
	(footprint "antmicro-footprints:C_0402_1005Metric"
		(layer "B.Cu")
		(at 202.9 167.9 -90)
		(descr "Capacitor SMD 0402")
		(tags "capacitor SMD 0402")
		(property "Reference" "C174"
			(at 0 0.699 90)
			(layer "B.SilkS")
			(hide yes)
			(effects
				(font
					(size 0.7 0.7)
					(thickness 0.15)
				)
				(justify left bottom mirror)
			)
		)
		(property "Value" "C_1u_0402"
			(at -1.022927 -2.155213 90)
			(layer "B.Fab")
			(effects
				(font
					(size 0.7 0.7)
					(thickness 0.15)
				)
				(justify left bottom mirror)
			)
		)
		(property "Datasheet" "https://product.tdk.com/en/search/capacitor/ceramic/mlcc/info?part_no=C1005X6S1A105K050BC"
			(at 0 0 270)
			(layer "F.Fab")
			(hide yes)
			(effects
				(font
					(size 1.27 1.27)
					(thickness 0.15)
				)
			)
		)
		(property "Author" "Antmicro"
			(at 35 370.8 0)
			(layer "B.Fab")
			(hide yes)
			(effects
				(font
					(size 1 1)
					(thickness 0.15)
				)
				(justify mirror)
			)
		)
		(property "Dielectric" ""
			(at 35 370.8 0)
			(layer "B.Fab")
			(hide yes)
			(effects
				(font
					(size 1 1)
					(thickness 0.15)
				)
				(justify mirror)
			)
		)
		(property "License" "Apache-2.0"
			(at 35 370.8 0)
			(layer "B.Fab")
			(hide yes)
			(effects
				(font
					(size 1 1)
					(thickness 0.15)
				)
				(justify mirror)
			)
		)
		(property "MPN" "C1005X6S1A105K050BC"
			(at 35 370.8 0)
			(layer "B.Fab")
			(hide yes)
			(effects
				(font
					(size 1 1)
					(thickness 0.15)
				)
				(justify mirror)
			)
		)
		(property "Manufacturer" "TDK"
			(at 35 370.8 0)
			(layer "B.Fab")
			(hide yes)
			(effects
				(font
					(size 1 1)
					(thickness 0.15)
				)
				(justify mirror)
			)
		)
		(property "Val" "1u"
			(at 35 370.8 0)
			(layer "B.Fab")
			(hide yes)
			(effects
				(font
					(size 1 1)
					(thickness 0.15)
				)
				(justify mirror)
			)
		)
		(property "Voltage" ""
			(at 35 370.8 0)
			(layer "B.Fab")
			(hide yes)
			(effects
				(font
					(size 1 1)
					(thickness 0.15)
				)
				(justify mirror)
			)
		)
		(sheetname "/Supply/")
		(sheetfile "supply.kicad_sch")
		(attr smd)
		(fp_rect
			(start -0.9659 0.481258)
			(end 0.9649 -0.458742)
			(stroke
				(width 0.05)
				(type solid)
			)
			(fill no)
			(layer "B.CrtYd")
		)
		(fp_line
			(start -0.499 0.25)
			(end 0.499 0.25)
			(stroke
				(width 0.15)
				(type solid)
			)
			(layer "B.Fab")
		)
		(fp_line
			(start 0.499 0.25)
			(end 0.499 -0.248)
			(stroke
				(width 0.15)
				(type solid)
			)
			(layer "B.Fab")
		)
		(fp_line
			(start -0.499 -0.248)
			(end -0.499 0.25)
			(stroke
				(width 0.15)
				(type solid)
			)
			(layer "B.Fab")
		)
		(fp_line
			(start 0.499 -0.248)
			(end -0.499 -0.248)
			(stroke
				(width 0.15)
				(type solid)
			)
			(layer "B.Fab")
		)
		(pad "1" smd roundrect
			(at -0.484 0 270)
			(size 0.59 0.64)
			(layers "B.Cu" "B.Mask" "B.Paste")
			(roundrect_rratio 0.25)
			(net 1 "GND")
			(pintype "passive")
		)
		(pad "2" smd roundrect
			(at 0.484 0 270)
			(size 0.59 0.64)
			(layers "B.Cu" "B.Mask" "B.Paste")
			(roundrect_rratio 0.25)
			(net 40 "/Supply/QDCDC2_VCC")
			(pintype "passive")
		)
	)
	(footprint "antmicro-footprints:TP_SMD_1mm"
		(layer "B.Cu")
		(at 105.937096 187.9 90)
		(property "Reference" "TP53"
			(at -3.68 -0.272904 90)
			(layer "B.SilkS")
			(effects
				(font
					(size 0.7 0.7)
					(thickness 0.15)
				)
				(justify right top mirror)
			)
		)
		(property "Value" "TP_1mm_SMD"
			(at 0 -1.4 90)
			(layer "B.Fab")
			(effects
				(font
					(size 0.7 0.7)
					(thickness 0.15)
				)
				(justify right top mirror)
			)
		)
		(property "MPN" ""
			(at 0 0 270)
			(unlocked yes)
			(layer "B.Fab")
			(hide yes)
			(effects
				(font
					(size 1 1)
					(thickness 0.15)
				)
				(justify mirror)
			)
		)
		(property "Manufacturer" ""
			(at 0 0 270)
			(unlocked yes)
			(layer "B.Fab")
			(hide yes)
			(effects
				(font
					(size 1 1)
					(thickness 0.15)
				)
				(justify mirror)
			)
		)
		(property "Author" "Antmicro"
			(at 0 0 270)
			(unlocked yes)
			(layer "B.Fab")
			(hide yes)
			(effects
				(font
					(size 1 1)
					(thickness 0.15)
				)
				(justify mirror)
			)
		)
		(property "License" "Apache-2.0"
			(at 0 0 270)
			(unlocked yes)
			(layer "B.Fab")
			(hide yes)
			(effects
				(font
					(size 1 1)
					(thickness 0.15)
				)
				(justify mirror)
			)
		)
		(sheetname "/Debug FTDI/")
		(sheetfile "debug-ftdi.kicad_sch")
		(attr exclude_from_pos_files)
		(fp_circle
			(center 0 0)
			(end 0.6 0)
			(stroke
				(width 0.05)
				(type default)
			)
			(fill no)
			(layer "B.CrtYd")
		)
		(fp_text user "Author: Antmicro"
			(at -0.5 -4 90)
			(layer "B.Fab")
			(effects
				(font
					(size 0.7 0.7)
					(thickness 0.15)
				)
				(justify right top mirror)
			)
		)
		(fp_text user "License: Apache-2.0"
			(at -0.5 -5.2 90)
			(layer "B.Fab")
			(effects
				(font
					(size 0.7 0.7)
					(thickness 0.15)
				)
				(justify right top mirror)
			)
		)
		(fp_text user "${REFERENCE}"
			(at -0.5 -2.8 90)
			(layer "B.Fab")
			(effects
				(font
					(size 0.7 0.7)
					(thickness 0.15)
				)
				(justify right top mirror)
			)
		)
		(pad "1" smd circle
			(at 0 0 90)
			(size 1 1)
			(layers "B.Cu" "B.Mask")
			(net 671 "/Debug FTDI/FTDI.SCL")
			(pinfunction "1")
			(pintype "passive")
		)
	)
	(footprint "antmicro-footprints:C_0402_1005Metric"
		(layer "B.Cu")
		(at 132.525501 204.850501 90)
		(descr "Capacitor SMD 0402")
		(tags "capacitor SMD 0402")
		(property "Reference" "C232"
			(at 0 0.699 270)
			(layer "B.SilkS")
			(hide yes)
			(effects
				(font
					(size 0.7 0.7)
					(thickness 0.15)
				)
				(justify left bottom mirror)
			)
		)
		(property "Value" "C_100n_0402"
			(at -1.022927 -2.155213 270)
			(layer "B.Fab")
			(effects
				(font
					(size 0.7 0.7)
					(thickness 0.15)
				)
				(justify left bottom mirror)
			)
		)
		(property "Datasheet" "https://www.murata.com/products/productdetail?partno=GRM155R61H104KE14%23"
			(at 0 0 90)
			(layer "F.Fab")
			(hide yes)
			(effects
				(font
					(size 1.27 1.27)
					(thickness 0.15)
				)
			)
		)
		(property "Author" "Antmicro"
			(at 337.376002 72.325 0)
			(layer "B.Fab")
			(hide yes)
			(effects
				(font
					(size 1 1)
					(thickness 0.15)
				)
				(justify mirror)
			)
		)
		(property "Dielectric" "X5R"
			(at 337.376002 72.325 0)
			(layer "B.Fab")
			(hide yes)
			(effects
				(font
					(size 1 1)
					(thickness 0.15)
				)
				(justify mirror)
			)
		)
		(property "License" "Apache-2.0"
			(at 337.376002 72.325 0)
			(layer "B.Fab")
			(hide yes)
			(effects
				(font
					(size 1 1)
					(thickness 0.15)
				)
				(justify mirror)
			)
		)
		(property "MPN" "GRM155R61H104KE14D"
			(at 337.376002 72.325 0)
			(layer "B.Fab")
			(hide yes)
			(effects
				(font
					(size 1 1)
					(thickness 0.15)
				)
				(justify mirror)
			)
		)
		(property "Manufacturer" "Murata"
			(at 337.376002 72.325 0)
			(layer "B.Fab")
			(hide yes)
			(effects
				(font
					(size 1 1)
					(thickness 0.15)
				)
				(justify mirror)
			)
		)
		(property "Val" "100n"
			(at 337.376002 72.325 0)
			(layer "B.Fab")
			(hide yes)
			(effects
				(font
					(size 1 1)
					(thickness 0.15)
				)
				(justify mirror)
			)
		)
		(property "Voltage" "50V"
			(at 337.376002 72.325 0)
			(layer "B.Fab")
			(hide yes)
			(effects
				(font
					(size 1 1)
					(thickness 0.15)
				)
				(justify mirror)
			)
		)
		(sheetname "/FPGA MGT Interface/")
		(sheetfile "fpga-mgt.kicad_sch")
		(attr smd)
		(fp_rect
			(start -0.9659 0.481258)
			(end 0.9649 -0.458742)
			(stroke
				(width 0.05)
				(type solid)
			)
			(fill no)
			(layer "B.CrtYd")
		)
		(fp_line
			(start 0.499 -0.248)
			(end -0.499 -0.248)
			(stroke
				(width 0.15)
				(type solid)
			)
			(layer "B.Fab")
		)
		(fp_line
			(start -0.499 -0.248)
			(end -0.499 0.25)
			(stroke
				(width 0.15)
				(type solid)
			)
			(layer "B.Fab")
		)
		(fp_line
			(start 0.499 0.25)
			(end 0.499 -0.248)
			(stroke
				(width 0.15)
				(type solid)
			)
			(layer "B.Fab")
		)
		(fp_line
			(start -0.499 0.25)
			(end 0.499 0.25)
			(stroke
				(width 0.15)
				(type solid)
			)
			(layer "B.Fab")
		)
		(pad "1" smd roundrect
			(at -0.484 0 90)
			(size 0.59 0.64)
			(layers "B.Cu" "B.Mask" "B.Paste")
			(roundrect_rratio 0.25)
			(net 28 "/FPGA MGT Interface/PCIE.TXD0_N")
			(pintype "passive")
		)
		(pad "2" smd roundrect
			(at 0.484 0 90)
			(size 0.59 0.64)
			(layers "B.Cu" "B.Mask" "B.Paste")
			(roundrect_rratio 0.25)
			(net 29 "/FPGA MGT Interface/GTX_TX3_N")
			(pintype "passive")
		)
	)
	(footprint "antmicro-footprints:TP_SMD_1mm"
		(layer "B.Cu")
		(at 172.3 181.9 180)
		(property "Reference" "TP68"
			(at 0.9 -0.3 0)
			(layer "B.SilkS")
			(effects
				(font
					(size 0.7 0.7)
					(thickness 0.15)
				)
				(justify left bottom mirror)
			)
		)
		(property "Value" "TP_1mm_SMD"
			(at 0 -1.4 0)
			(layer "B.Fab")
			(effects
				(font
					(size 0.7 0.7)
					(thickness 0.15)
				)
				(justify left bottom mirror)
			)
		)
		(property "MPN" ""
			(at 0 0 0)
			(unlocked yes)
			(layer "B.Fab")
			(hide yes)
			(effects
				(font
					(size 1 1)
					(thickness 0.15)
				)
				(justify mirror)
			)
		)
		(property "Manufacturer" ""
			(at 0 0 0)
			(unlocked yes)
			(layer "B.Fab")
			(hide yes)
			(effects
				(font
					(size 1 1)
					(thickness 0.15)
				)
				(justify mirror)
			)
		)
		(property "Author" "Antmicro"
			(at 0 0 0)
			(unlocked yes)
			(layer "B.Fab")
			(hide yes)
			(effects
				(font
					(size 1 1)
					(thickness 0.15)
				)
				(justify mirror)
			)
		)
		(property "License" "Apache-2.0"
			(at 0 0 0)
			(unlocked yes)
			(layer "B.Fab")
			(hide yes)
			(effects
				(font
					(size 1 1)
					(thickness 0.15)
				)
				(justify mirror)
			)
		)
		(sheetname "/I^{2}C/")
		(sheetfile "i2c.kicad_sch")
		(attr exclude_from_pos_files)
		(fp_circle
			(center 0 0)
			(end 0.6 0)
			(stroke
				(width 0.05)
				(type default)
			)
			(fill no)
			(layer "B.CrtYd")
		)
		(fp_text user "License: Apache-2.0"
			(at -0.5 -5.2 0)
			(layer "B.Fab")
			(effects
				(font
					(size 0.7 0.7)
					(thickness 0.15)
				)
				(justify left bottom mirror)
			)
		)
		(fp_text user "Author: Antmicro"
			(at -0.5 -4 0)
			(layer "B.Fab")
			(effects
				(font
					(size 0.7 0.7)
					(thickness 0.15)
				)
				(justify left bottom mirror)
			)
		)
		(fp_text user "${REFERENCE}"
			(at -0.5 -2.8 0)
			(layer "B.Fab")
			(effects
				(font
					(size 0.7 0.7)
					(thickness 0.15)
				)
				(justify left bottom mirror)
			)
		)
		(pad "1" smd circle
			(at 0 0 180)
			(size 1 1)
			(layers "B.Cu" "B.Mask")
			(net 1 "GND")
			(pinfunction "1")
			(pintype "passive")
		)
	)
	(footprint "antmicro-footprints:R_0402_1005Metric"
		(layer "B.Cu")
		(at 180.8 199.4 180)
		(descr "Resistor SMD 0402")
		(tags "resistor SMD 0402")
		(property "Reference" "R176"
			(at -3.95 -0.5 0)
			(layer "B.SilkS")
			(effects
				(font
					(size 0.7 0.7)
					(thickness 0.15)
				)
				(justify left bottom mirror)
			)
		)
		(property "Value" "R_0R_0402"
			(at -1.011843 -1.772047 0)
			(layer "B.Fab")
			(effects
				(font
					(size 0.7 0.7)
					(thickness 0.15)
				)
				(justify left bottom mirror)
			)
		)
		(property "Datasheet" "https://industrial.panasonic.com/cdbs/www-data/pdf/RDA0000/AOA0000C301.pdf"
			(at 0 0 180)
			(layer "F.Fab")
			(hide yes)
			(effects
				(font
					(size 1.27 1.27)
					(thickness 0.15)
				)
			)
		)
		(property "Author" "Antmicro"
			(at 361.6 398.8 0)
			(layer "B.Fab")
			(hide yes)
			(effects
				(font
					(size 1 1)
					(thickness 0.15)
				)
				(justify mirror)
			)
		)
		(property "Current" "1A"
			(at 361.6 398.8 0)
			(layer "B.Fab")
			(hide yes)
			(effects
				(font
					(size 1 1)
					(thickness 0.15)
				)
				(justify mirror)
			)
		)
		(property "License" "Apache-2.0"
			(at 361.6 398.8 0)
			(layer "B.Fab")
			(hide yes)
			(effects
				(font
					(size 1 1)
					(thickness 0.15)
				)
				(justify mirror)
			)
		)
		(property "MPN" "ERJ2GE0R00X"
			(at 361.6 398.8 0)
			(layer "B.Fab")
			(hide yes)
			(effects
				(font
					(size 1 1)
					(thickness 0.15)
				)
				(justify mirror)
			)
		)
		(property "Manufacturer" "Panasonic"
			(at 361.6 398.8 0)
			(layer "B.Fab")
			(hide yes)
			(effects
				(font
					(size 1 1)
					(thickness 0.15)
				)
				(justify mirror)
			)
		)
		(property "Tolerance" ""
			(at 361.6 398.8 0)
			(layer "B.Fab")
			(hide yes)
			(effects
				(font
					(size 1 1)
					(thickness 0.15)
				)
				(justify mirror)
			)
		)
		(property "Val" "0R"
			(at 361.6 398.8 0)
			(layer "B.Fab")
			(hide yes)
			(effects
				(font
					(size 1 1)
					(thickness 0.15)
				)
				(justify mirror)
			)
		)
		(sheetname "/I^{2}C/")
		(sheetfile "i2c.kicad_sch")
		(attr exclude_from_pos_files exclude_from_bom dnp)
		(fp_rect
			(start -0.93 0.47)
			(end 0.93 -0.47)
			(stroke
				(width 0.05)
				(type solid)
			)
			(fill no)
			(layer "B.CrtYd")
		)
		(fp_rect
			(start -0.5 0.25)
			(end 0.5 -0.25)
			(stroke
				(width 0.15)
				(type solid)
			)
			(fill no)
			(layer "B.Fab")
		)
		(pad "1" smd roundrect
			(at -0.485 0 180)
			(size 0.59 0.64)
			(layers "B.Cu" "B.Mask" "B.Paste")
			(roundrect_rratio 0.25)
			(net 690 "/I^{2}C/PWR.SDA")
			(pintype "passive")
		)
		(pad "2" smd roundrect
			(at 0.485 0 180)
			(size 0.59 0.64)
			(layers "B.Cu" "B.Mask" "B.Paste")
			(roundrect_rratio 0.25)
			(net 672 "/Debug FTDI/FTDI.SDA")
			(pintype "passive")
		)
	)
	(footprint "antmicro-footprints:TP_SMD_1mm"
		(layer "B.Cu")
		(at 110 179.13 180)
		(property "Reference" "TP49"
			(at -3.4 -0.45 0)
			(layer "B.SilkS")
			(effects
				(font
					(size 0.7 0.7)
					(thickness 0.15)
				)
				(justify left bottom mirror)
			)
		)
		(property "Value" "TP_1mm_SMD"
			(at 0 -1.4 0)
			(layer "B.Fab")
			(effects
				(font
					(size 0.7 0.7)
					(thickness 0.15)
				)
				(justify left bottom mirror)
			)
		)
		(property "MPN" ""
			(at 0 0 0)
			(unlocked yes)
			(layer "B.Fab")
			(hide yes)
			(effects
				(font
					(size 1 1)
					(thickness 0.15)
				)
				(justify mirror)
			)
		)
		(property "Manufacturer" ""
			(at 0 0 0)
			(unlocked yes)
			(layer "B.Fab")
			(hide yes)
			(effects
				(font
					(size 1 1)
					(thickness 0.15)
				)
				(justify mirror)
			)
		)
		(property "Author" "Antmicro"
			(at 0 0 0)
			(unlocked yes)
			(layer "B.Fab")
			(hide yes)
			(effects
				(font
					(size 1 1)
					(thickness 0.15)
				)
				(justify mirror)
			)
		)
		(property "License" "Apache-2.0"
			(at 0 0 0)
			(unlocked yes)
			(layer "B.Fab")
			(hide yes)
			(effects
				(font
					(size 1 1)
					(thickness 0.15)
				)
				(justify mirror)
			)
		)
		(sheetname "/Debug FTDI/")
		(sheetfile "debug-ftdi.kicad_sch")
		(attr exclude_from_pos_files)
		(fp_circle
			(center 0 0)
			(end 0.6 0)
			(stroke
				(width 0.05)
				(type default)
			)
			(fill no)
			(layer "B.CrtYd")
		)
		(fp_text user "License: Apache-2.0"
			(at -0.5 -5.2 0)
			(layer "B.Fab")
			(effects
				(font
					(size 0.7 0.7)
					(thickness 0.15)
				)
				(justify left bottom mirror)
			)
		)
		(fp_text user "Author: Antmicro"
			(at -0.5 -4 0)
			(layer "B.Fab")
			(effects
				(font
					(size 0.7 0.7)
					(thickness 0.15)
				)
				(justify left bottom mirror)
			)
		)
		(fp_text user "${REFERENCE}"
			(at -0.5 -2.8 0)
			(layer "B.Fab")
			(effects
				(font
					(size 0.7 0.7)
					(thickness 0.15)
				)
				(justify left bottom mirror)
			)
		)
		(pad "1" smd circle
			(at 0 0 180)
			(size 1 1)
			(layers "B.Cu" "B.Mask")
			(net 639 "/Debug FTDI/UART0.RX")
			(pinfunction "1")
			(pintype "passive")
		)
	)
	(footprint "antmicro-footprints:C_0402_1005Metric"
		(layer "B.Cu")
		(at 142.375501 177.801 90)
		(descr "Capacitor SMD 0402 (1005 Metric), square (rectangular) end terminal, IPC_7351 nominal, (Body size source: IPC-SM-782 page 76, https://www.pcb-3d.com/wordpress/wp-content/uploads/ipc-sm-782a_amendment_1_and_2.pdf)")
		(tags "capacitor 0402")
		(property "Reference" "C68"
			(at 0 1.17 270)
			(layer "B.SilkS")
			(hide yes)
			(effects
				(font
					(size 0.7 0.7)
					(thickness 0.15)
				)
				(justify left bottom mirror)
			)
		)
		(property "Value" "C_100n_0402"
			(at 0 -1.169 270)
			(layer "B.Fab")
			(effects
				(font
					(size 0.7 0.7)
					(thickness 0.15)
				)
				(justify left bottom mirror)
			)
		)
		(property "Datasheet" "https://www.murata.com/products/productdetail?partno=GRM155R61H104KE14%23"
			(at 0 0 90)
			(layer "F.Fab")
			(hide yes)
			(effects
				(font
					(size 1.27 1.27)
					(thickness 0.15)
				)
			)
		)
		(property "Author" "Antmicro"
			(at 320.176501 35.425499 0)
			(layer "B.Fab")
			(hide yes)
			(effects
				(font
					(size 1 1)
					(thickness 0.15)
				)
				(justify mirror)
			)
		)
		(property "Dielectric" "X5R"
			(at 320.176501 35.425499 0)
			(layer "B.Fab")
			(hide yes)
			(effects
				(font
					(size 1 1)
					(thickness 0.15)
				)
				(justify mirror)
			)
		)
		(property "License" "Apache-2.0"
			(at 320.176501 35.425499 0)
			(layer "B.Fab")
			(hide yes)
			(effects
				(font
					(size 1 1)
					(thickness 0.15)
				)
				(justify mirror)
			)
		)
		(property "MPN" "GRM155R61H104KE14D"
			(at 320.176501 35.425499 0)
			(layer "B.Fab")
			(hide yes)
			(effects
				(font
					(size 1 1)
					(thickness 0.15)
				)
				(justify mirror)
			)
		)
		(property "Manufacturer" "Murata"
			(at 320.176501 35.425499 0)
			(layer "B.Fab")
			(hide yes)
			(effects
				(font
					(size 1 1)
					(thickness 0.15)
				)
				(justify mirror)
			)
		)
		(property "Val" "100n"
			(at 320.176501 35.425499 0)
			(layer "B.Fab")
			(hide yes)
			(effects
				(font
					(size 1 1)
					(thickness 0.15)
				)
				(justify mirror)
			)
		)
		(property "Voltage" "50V"
			(at 320.176501 35.425499 0)
			(layer "B.Fab")
			(hide yes)
			(effects
				(font
					(size 1 1)
					(thickness 0.15)
				)
				(justify mirror)
			)
		)
		(sheetname "/FPGA power/")
		(sheetfile "fpga-power.kicad_sch")
		(attr smd)
		(fp_rect
			(start -0.9656 0.4572)
			(end 0.9652 -0.4828)
			(stroke
				(width 0.05)
				(type solid)
			)
			(fill no)
			(layer "B.CrtYd")
		)
		(fp_line
			(start 0.498 -0.248)
			(end -0.5 -0.248)
			(stroke
				(width 0.15)
				(type solid)
			)
			(layer "B.Fab")
		)
		(fp_line
			(start -0.5 -0.248)
			(end -0.5 0.25)
			(stroke
				(width 0.15)
				(type solid)
			)
			(layer "B.Fab")
		)
		(fp_line
			(start 0.498 0.25)
			(end 0.498 -0.248)
			(stroke
				(width 0.15)
				(type solid)
			)
			(layer "B.Fab")
		)
		(fp_line
			(start -0.5 0.25)
			(end 0.498 0.25)
			(stroke
				(width 0.15)
				(type solid)
			)
			(layer "B.Fab")
		)
		(pad "1" smd roundrect
			(at -0.5 0)
			(size 0.6 0.6)
			(layers "B.Cu" "B.Mask" "B.Paste")
			(roundrect_rratio 0.25)
			(net 1 "GND")
			(pintype "passive")
		)
		(pad "2" smd roundrect
			(at 0.498 0 90)
			(size 0.6 0.6)
			(layers "B.Cu" "B.Mask" "B.Paste")
			(roundrect_rratio 0.25)
			(net 188 "+1V8")
			(pintype "passive")
		)
	)
	(footprint "antmicro-footprints:C_0402_1005Metric"
		(layer "B.Cu")
		(at 82.856897 137.670037 -90)
		(descr "Capacitor SMD 0402")
		(tags "capacitor SMD 0402")
		(property "Reference" "C135"
			(at 0 0.699 90)
			(layer "B.SilkS")
			(hide yes)
			(effects
				(font
					(size 0.7 0.7)
					(thickness 0.15)
				)
				(justify left bottom mirror)
			)
		)
		(property "Value" "C_100n_0402"
			(at -1.022927 -2.155213 90)
			(layer "B.Fab")
			(effects
				(font
					(size 0.7 0.7)
					(thickness 0.15)
				)
				(justify left bottom mirror)
			)
		)
		(property "Datasheet" "https://www.murata.com/products/productdetail?partno=GRM155R61H104KE14%23"
			(at 0 0 270)
			(layer "F.Fab")
			(hide yes)
			(effects
				(font
					(size 1.27 1.27)
					(thickness 0.15)
				)
			)
		)
		(property "Author" "Antmicro"
			(at -52.25659 217.970384 0)
			(layer "B.Fab")
			(hide yes)
			(effects
				(font
					(size 1 1)
					(thickness 0.15)
				)
				(justify mirror)
			)
		)
		(property "Dielectric" "X5R"
			(at -52.25659 217.970384 0)
			(layer "B.Fab")
			(hide yes)
			(effects
				(font
					(size 1 1)
					(thickness 0.15)
				)
				(justify mirror)
			)
		)
		(property "License" "Apache-2.0"
			(at -52.25659 217.970384 0)
			(layer "B.Fab")
			(hide yes)
			(effects
				(font
					(size 1 1)
					(thickness 0.15)
				)
				(justify mirror)
			)
		)
		(property "MPN" "GRM155R61H104KE14D"
			(at -52.25659 217.970384 0)
			(layer "B.Fab")
			(hide yes)
			(effects
				(font
					(size 1 1)
					(thickness 0.15)
				)
				(justify mirror)
			)
		)
		(property "Manufacturer" "Murata"
			(at -52.25659 217.970384 0)
			(layer "B.Fab")
			(hide yes)
			(effects
				(font
					(size 1 1)
					(thickness 0.15)
				)
				(justify mirror)
			)
		)
		(property "Val" "100n"
			(at -52.25659 217.970384 0)
			(layer "B.Fab")
			(hide yes)
			(effects
				(font
					(size 1 1)
					(thickness 0.15)
				)
				(justify mirror)
			)
		)
		(property "Voltage" "50V"
			(at -52.25659 217.970384 0)
			(layer "B.Fab")
			(hide yes)
			(effects
				(font
					(size 1 1)
					(thickness 0.15)
				)
				(justify mirror)
			)
		)
		(sheetname "/Ethernet/")
		(sheetfile "ethernet.kicad_sch")
		(attr smd)
		(fp_rect
			(start -0.9659 0.481258)
			(end 0.9649 -0.458742)
			(stroke
				(width 0.05)
				(type solid)
			)
			(fill no)
			(layer "B.CrtYd")
		)
		(fp_line
			(start -0.499 0.25)
			(end 0.499 0.25)
			(stroke
				(width 0.15)
				(type solid)
			)
			(layer "B.Fab")
		)
		(fp_line
			(start 0.499 0.25)
			(end 0.499 -0.248)
			(stroke
				(width 0.15)
				(type solid)
			)
			(layer "B.Fab")
		)
		(fp_line
			(start -0.499 -0.248)
			(end -0.499 0.25)
			(stroke
				(width 0.15)
				(type solid)
			)
			(layer "B.Fab")
		)
		(fp_line
			(start 0.499 -0.248)
			(end -0.499 -0.248)
			(stroke
				(width 0.15)
				(type solid)
			)
			(layer "B.Fab")
		)
		(pad "1" smd roundrect
			(at -0.484 0 270)
			(size 0.59 0.64)
			(layers "B.Cu" "B.Mask" "B.Paste")
			(roundrect_rratio 0.25)
			(net 1 "GND")
			(pintype "passive")
		)
		(pad "2" smd roundrect
			(at 0.484 0 270)
			(size 0.59 0.64)
			(layers "B.Cu" "B.Mask" "B.Paste")
			(roundrect_rratio 0.25)
			(net 214 "Net-(C135-Pad2)")
			(pintype "passive")
		)
	)
	(footprint "antmicro-footprints:TP_SMD_1mm"
		(layer "B.Cu")
		(at 110 176.63 180)
		(property "Reference" "TP48"
			(at -3.3 -0.47 0)
			(layer "B.SilkS")
			(effects
				(font
					(size 0.7 0.7)
					(thickness 0.15)
				)
				(justify left bottom mirror)
			)
		)
		(property "Value" "TP_1mm_SMD"
			(at 0 -1.4 0)
			(layer "B.Fab")
			(effects
				(font
					(size 0.7 0.7)
					(thickness 0.15)
				)
				(justify left bottom mirror)
			)
		)
		(property "MPN" ""
			(at 0 0 0)
			(unlocked yes)
			(layer "B.Fab")
			(hide yes)
			(effects
				(font
					(size 1 1)
					(thickness 0.15)
				)
				(justify mirror)
			)
		)
		(property "Manufacturer" ""
			(at 0 0 0)
			(unlocked yes)
			(layer "B.Fab")
			(hide yes)
			(effects
				(font
					(size 1 1)
					(thickness 0.15)
				)
				(justify mirror)
			)
		)
		(property "Author" "Antmicro"
			(at 0 0 0)
			(unlocked yes)
			(layer "B.Fab")
			(hide yes)
			(effects
				(font
					(size 1 1)
					(thickness 0.15)
				)
				(justify mirror)
			)
		)
		(property "License" "Apache-2.0"
			(at 0 0 0)
			(unlocked yes)
			(layer "B.Fab")
			(hide yes)
			(effects
				(font
					(size 1 1)
					(thickness 0.15)
				)
				(justify mirror)
			)
		)
		(sheetname "/Debug FTDI/")
		(sheetfile "debug-ftdi.kicad_sch")
		(attr exclude_from_pos_files)
		(fp_circle
			(center 0 0)
			(end 0.6 0)
			(stroke
				(width 0.05)
				(type default)
			)
			(fill no)
			(layer "B.CrtYd")
		)
		(fp_text user "Author: Antmicro"
			(at -0.5 -4 0)
			(layer "B.Fab")
			(effects
				(font
					(size 0.7 0.7)
					(thickness 0.15)
				)
				(justify left bottom mirror)
			)
		)
		(fp_text user "${REFERENCE}"
			(at -0.5 -2.8 0)
			(layer "B.Fab")
			(effects
				(font
					(size 0.7 0.7)
					(thickness 0.15)
				)
				(justify left bottom mirror)
			)
		)
		(fp_text user "License: Apache-2.0"
			(at -0.5 -5.2 0)
			(layer "B.Fab")
			(effects
				(font
					(size 0.7 0.7)
					(thickness 0.15)
				)
				(justify left bottom mirror)
			)
		)
		(pad "1" smd circle
			(at 0 0 180)
			(size 1 1)
			(layers "B.Cu" "B.Mask")
			(net 641 "/Debug FTDI/UART0.TX")
			(pinfunction "1")
			(pintype "passive")
		)
	)
	(footprint "antmicro-footprints:TP_SMD_1mm"
		(layer "B.Cu")
		(at 95 188.275 180)
		(property "Reference" "TP44"
			(at -1.3 0.775 0)
			(layer "B.SilkS")
			(effects
				(font
					(size 0.7 0.7)
					(thickness 0.15)
				)
				(justify left bottom mirror)
			)
		)
		(property "Value" "TP_1mm_SMD"
			(at 0 -1.4 0)
			(layer "B.Fab")
			(effects
				(font
					(size 0.7 0.7)
					(thickness 0.15)
				)
				(justify left bottom mirror)
			)
		)
		(property "MPN" ""
			(at 0 0 0)
			(unlocked yes)
			(layer "B.Fab")
			(hide yes)
			(effects
				(font
					(size 1 1)
					(thickness 0.15)
				)
				(justify mirror)
			)
		)
		(property "Manufacturer" ""
			(at 0 0 0)
			(unlocked yes)
			(layer "B.Fab")
			(hide yes)
			(effects
				(font
					(size 1 1)
					(thickness 0.15)
				)
				(justify mirror)
			)
		)
		(property "Author" "Antmicro"
			(at 0 0 0)
			(unlocked yes)
			(layer "B.Fab")
			(hide yes)
			(effects
				(font
					(size 1 1)
					(thickness 0.15)
				)
				(justify mirror)
			)
		)
		(property "License" "Apache-2.0"
			(at 0 0 0)
			(unlocked yes)
			(layer "B.Fab")
			(hide yes)
			(effects
				(font
					(size 1 1)
					(thickness 0.15)
				)
				(justify mirror)
			)
		)
		(sheetname "/Debug FTDI/")
		(sheetfile "debug-ftdi.kicad_sch")
		(attr exclude_from_pos_files)
		(fp_circle
			(center 0 0)
			(end 0.6 0)
			(stroke
				(width 0.05)
				(type default)
			)
			(fill no)
			(layer "B.CrtYd")
		)
		(fp_text user "Author: Antmicro"
			(at -0.5 -4 0)
			(layer "B.Fab")
			(effects
				(font
					(size 0.7 0.7)
					(thickness 0.15)
				)
				(justify left bottom mirror)
			)
		)
		(fp_text user "${REFERENCE}"
			(at -0.5 -2.8 0)
			(layer "B.Fab")
			(effects
				(font
					(size 0.7 0.7)
					(thickness 0.15)
				)
				(justify left bottom mirror)
			)
		)
		(fp_text user "License: Apache-2.0"
			(at -0.5 -5.2 0)
			(layer "B.Fab")
			(effects
				(font
					(size 0.7 0.7)
					(thickness 0.15)
				)
				(justify left bottom mirror)
			)
		)
		(pad "1" smd circle
			(at 0 0 180)
			(size 1 1)
			(layers "B.Cu" "B.Mask")
			(net 48 "/Debug FTDI/JTAG.TDI")
			(pinfunction "1")
			(pintype "passive")
		)
	)
	(footprint "antmicro-footprints:C_0402_1005Metric"
		(layer "B.Cu")
		(at 141.875501 173.301 180)
		(descr "Capacitor SMD 0402 (1005 Metric), square (rectangular) end terminal, IPC_7351 nominal, (Body size source: IPC-SM-782 page 76, https://www.pcb-3d.com/wordpress/wp-content/uploads/ipc-sm-782a_amendment_1_and_2.pdf)")
		(tags "capacitor 0402")
		(property "Reference" "C43"
			(at 0 1.17 0)
			(layer "B.SilkS")
			(hide yes)
			(effects
				(font
					(size 0.7 0.7)
					(thickness 0.15)
				)
				(justify left bottom mirror)
			)
		)
		(property "Value" "C_4u7_0402"
			(at 0 -1.169 0)
			(layer "B.Fab")
			(effects
				(font
					(size 0.7 0.7)
					(thickness 0.15)
				)
				(justify left bottom mirror)
			)
		)
		(property "Datasheet" "https://www.murata.com/products/productdetail?partno=GRM155R61A475MEAA%23"
			(at 0 0 180)
			(layer "F.Fab")
			(hide yes)
			(effects
				(font
					(size 1.27 1.27)
					(thickness 0.15)
				)
			)
		)
		(property "Author" "Antmicro"
			(at 283.751002 346.602 0)
			(layer "B.Fab")
			(hide yes)
			(effects
				(font
					(size 1 1)
					(thickness 0.15)
				)
				(justify mirror)
			)
		)
		(property "Dielectric" ""
			(at 283.751002 346.602 0)
			(layer "B.Fab")
			(hide yes)
			(effects
				(font
					(size 1 1)
					(thickness 0.15)
				)
				(justify mirror)
			)
		)
		(property "License" "Apache-2.0"
			(at 283.751002 346.602 0)
			(layer "B.Fab")
			(hide yes)
			(effects
				(font
					(size 1 1)
					(thickness 0.15)
				)
				(justify mirror)
			)
		)
		(property "MPN" "GRM155R61A475MEAAD"
			(at 283.751002 346.602 0)
			(layer "B.Fab")
			(hide yes)
			(effects
				(font
					(size 1 1)
					(thickness 0.15)
				)
				(justify mirror)
			)
		)
		(property "Manufacturer" "Murata"
			(at 283.751002 346.602 0)
			(layer "B.Fab")
			(hide yes)
			(effects
				(font
					(size 1 1)
					(thickness 0.15)
				)
				(justify mirror)
			)
		)
		(property "Val" "4u7"
			(at 283.751002 346.602 0)
			(layer "B.Fab")
			(hide yes)
			(effects
				(font
					(size 1 1)
					(thickness 0.15)
				)
				(justify mirror)
			)
		)
		(property "Voltage" ""
			(at 283.751002 346.602 0)
			(layer "B.Fab")
			(hide yes)
			(effects
				(font
					(size 1 1)
					(thickness 0.15)
				)
				(justify mirror)
			)
		)
		(sheetname "/FPGA power/")
		(sheetfile "fpga-power.kicad_sch")
		(attr smd)
		(fp_rect
			(start -0.9656 0.4572)
			(end 0.9652 -0.4828)
			(stroke
				(width 0.05)
				(type solid)
			)
			(fill no)
			(layer "B.CrtYd")
		)
		(fp_line
			(start 0.498 0.25)
			(end 0.498 -0.248)
			(stroke
				(width 0.15)
				(type solid)
			)
			(layer "B.Fab")
		)
		(fp_line
			(start 0.498 -0.248)
			(end -0.5 -0.248)
			(stroke
				(width 0.15)
				(type solid)
			)
			(layer "B.Fab")
		)
		(fp_line
			(start -0.5 0.25)
			(end 0.498 0.25)
			(stroke
				(width 0.15)
				(type solid)
			)
			(layer "B.Fab")
		)
		(fp_line
			(start -0.5 -0.248)
			(end -0.5 0.25)
			(stroke
				(width 0.15)
				(type solid)
			)
			(layer "B.Fab")
		)
		(pad "1" smd roundrect
			(at -0.5 0 90)
			(size 0.6 0.6)
			(layers "B.Cu" "B.Mask" "B.Paste")
			(roundrect_rratio 0.25)
			(net 188 "+1V8")
			(pintype "passive")
		)
		(pad "2" smd roundrect
			(at 0.498 0 180)
			(size 0.6 0.6)
			(layers "B.Cu" "B.Mask" "B.Paste")
			(roundrect_rratio 0.25)
			(net 1 "GND")
			(pintype "passive")
		)
	)
	(footprint "antmicro-footprints:C_0402_1005Metric"
		(layer "B.Cu")
		(at 144.375001 177.8025 -90)
		(descr "Capacitor SMD 0402 (1005 Metric), square (rectangular) end terminal, IPC_7351 nominal, (Body size source: IPC-SM-782 page 76, https://www.pcb-3d.com/wordpress/wp-content/uploads/ipc-sm-782a_amendment_1_and_2.pdf)")
		(tags "capacitor 0402")
		(property "Reference" "C90"
			(at 0 1.17 90)
			(layer "B.SilkS")
			(hide yes)
			(effects
				(font
					(size 0.7 0.7)
					(thickness 0.15)
				)
				(justify left bottom mirror)
			)
		)
		(property "Value" "C_100n_0402"
			(at 0 -1.169 90)
			(layer "B.Fab")
			(effects
				(font
					(size 0.7 0.7)
					(thickness 0.15)
				)
				(justify left bottom mirror)
			)
		)
		(property "Datasheet" "https://www.murata.com/products/productdetail?partno=GRM155R61H104KE14%23"
			(at 0 0 270)
			(layer "F.Fab")
			(hide yes)
			(effects
				(font
					(size 1.27 1.27)
					(thickness 0.15)
				)
			)
		)
		(property "Author" "Antmicro"
			(at -33.427499 322.177501 0)
			(layer "B.Fab")
			(hide yes)
			(effects
				(font
					(size 1 1)
					(thickness 0.15)
				)
				(justify mirror)
			)
		)
		(property "Dielectric" "X5R"
			(at -33.427499 322.177501 0)
			(layer "B.Fab")
			(hide yes)
			(effects
				(font
					(size 1 1)
					(thickness 0.15)
				)
				(justify mirror)
			)
		)
		(property "License" "Apache-2.0"
			(at -33.427499 322.177501 0)
			(layer "B.Fab")
			(hide yes)
			(effects
				(font
					(size 1 1)
					(thickness 0.15)
				)
				(justify mirror)
			)
		)
		(property "MPN" "GRM155R61H104KE14D"
			(at -33.427499 322.177501 0)
			(layer "B.Fab")
			(hide yes)
			(effects
				(font
					(size 1 1)
					(thickness 0.15)
				)
				(justify mirror)
			)
		)
		(property "Manufacturer" "Murata"
			(at -33.427499 322.177501 0)
			(layer "B.Fab")
			(hide yes)
			(effects
				(font
					(size 1 1)
					(thickness 0.15)
				)
				(justify mirror)
			)
		)
		(property "Val" "100n"
			(at -33.427499 322.177501 0)
			(layer "B.Fab")
			(hide yes)
			(effects
				(font
					(size 1 1)
					(thickness 0.15)
				)
				(justify mirror)
			)
		)
		(property "Voltage" "50V"
			(at -33.427499 322.177501 0)
			(layer "B.Fab")
			(hide yes)
			(effects
				(font
					(size 1 1)
					(thickness 0.15)
				)
				(justify mirror)
			)
		)
		(sheetname "/FPGA power/")
		(sheetfile "fpga-power.kicad_sch")
		(attr smd)
		(fp_rect
			(start -0.9656 0.4572)
			(end 0.9652 -0.4828)
			(stroke
				(width 0.05)
				(type solid)
			)
			(fill no)
			(layer "B.CrtYd")
		)
		(fp_line
			(start -0.5 0.25)
			(end 0.498 0.25)
			(stroke
				(width 0.15)
				(type solid)
			)
			(layer "B.Fab")
		)
		(fp_line
			(start 0.498 0.25)
			(end 0.498 -0.248)
			(stroke
				(width 0.15)
				(type solid)
			)
			(layer "B.Fab")
		)
		(fp_line
			(start -0.5 -0.248)
			(end -0.5 0.25)
			(stroke
				(width 0.15)
				(type solid)
			)
			(layer "B.Fab")
		)
		(fp_line
			(start 0.498 -0.248)
			(end -0.5 -0.248)
			(stroke
				(width 0.15)
				(type solid)
			)
			(layer "B.Fab")
		)
		(pad "1" smd roundrect
			(at -0.5 0 180)
			(size 0.6 0.6)
			(layers "B.Cu" "B.Mask" "B.Paste")
			(roundrect_rratio 0.25)
			(net 1 "GND")
			(pintype "passive")
		)
		(pad "2" smd roundrect
			(at 0.498 0 270)
			(size 0.6 0.6)
			(layers "B.Cu" "B.Mask" "B.Paste")
			(roundrect_rratio 0.25)
			(net 227 "+1V0")
			(pintype "passive")
		)
	)
	(footprint "antmicro-footprints:TP_SMD_1mm"
		(layer "B.Cu")
		(at 168.7 190.5 180)
		(property "Reference" "TP57"
			(at -3.4 -0.9 0)
			(layer "B.SilkS")
			(effects
				(font
					(size 0.7 0.7)
					(thickness 0.15)
				)
				(justify left bottom mirror)
			)
		)
		(property "Value" "TP_1mm_SMD"
			(at 0 -1.4 0)
			(layer "B.Fab")
			(effects
				(font
					(size 0.7 0.7)
					(thickness 0.15)
				)
				(justify left bottom mirror)
			)
		)
		(property "MPN" ""
			(at 0 0 0)
			(unlocked yes)
			(layer "B.Fab")
			(hide yes)
			(effects
				(font
					(size 1 1)
					(thickness 0.15)
				)
				(justify mirror)
			)
		)
		(property "Manufacturer" ""
			(at 0 0 0)
			(unlocked yes)
			(layer "B.Fab")
			(hide yes)
			(effects
				(font
					(size 1 1)
					(thickness 0.15)
				)
				(justify mirror)
			)
		)
		(property "Author" "Antmicro"
			(at 0 0 0)
			(unlocked yes)
			(layer "B.Fab")
			(hide yes)
			(effects
				(font
					(size 1 1)
					(thickness 0.15)
				)
				(justify mirror)
			)
		)
		(property "License" "Apache-2.0"
			(at 0 0 0)
			(unlocked yes)
			(layer "B.Fab")
			(hide yes)
			(effects
				(font
					(size 1 1)
					(thickness 0.15)
				)
				(justify mirror)
			)
		)
		(sheetname "/Supply/")
		(sheetfile "supply.kicad_sch")
		(attr exclude_from_pos_files)
		(fp_circle
			(center 0 0)
			(end 0.6 0)
			(stroke
				(width 0.05)
				(type default)
			)
			(fill no)
			(layer "B.CrtYd")
		)
		(fp_text user "License: Apache-2.0"
			(at -0.5 -5.2 0)
			(layer "B.Fab")
			(effects
				(font
					(size 0.7 0.7)
					(thickness 0.15)
				)
				(justify left bottom mirror)
			)
		)
		(fp_text user "${REFERENCE}"
			(at -0.5 -2.8 0)
			(layer "B.Fab")
			(effects
				(font
					(size 0.7 0.7)
					(thickness 0.15)
				)
				(justify left bottom mirror)
			)
		)
		(fp_text user "Author: Antmicro"
			(at -0.5 -4 0)
			(layer "B.Fab")
			(effects
				(font
					(size 0.7 0.7)
					(thickness 0.15)
				)
				(justify left bottom mirror)
			)
		)
		(pad "1" smd circle
			(at 0 0 180)
			(size 1 1)
			(layers "B.Cu" "B.Mask")
			(net 78 "/Supply/1V0_REG")
			(pinfunction "1")
			(pintype "passive")
		)
	)
	(footprint "antmicro-footprints:C_0603_1608Metric"
		(layer "B.Cu")
		(at 144.775501 174.801 180)
		(descr "Capacitor SMD 0603")
		(tags "capacitor 0603")
		(property "Reference" "C27"
			(at 0 0.9 0)
			(layer "B.SilkS")
			(hide yes)
			(effects
				(font
					(size 0.7 0.7)
					(thickness 0.15)
				)
				(justify left bottom mirror)
			)
		)
		(property "Value" "C_47u_0603"
			(at 0 -1.6 0)
			(layer "B.Fab")
			(effects
				(font
					(size 0.7 0.7)
					(thickness 0.15)
				)
				(justify left bottom mirror)
			)
		)
		(property "Datasheet" "https://www.murata.com/products/productdetail?partno=GRM188R60J476ME15%23"
			(at 0 0 180)
			(layer "F.Fab")
			(hide yes)
			(effects
				(font
					(size 1.27 1.27)
					(thickness 0.15)
				)
			)
		)
		(property "Author" "Antmicro"
			(at 289.551002 349.602 0)
			(layer "B.Fab")
			(hide yes)
			(effects
				(font
					(size 1 1)
					(thickness 0.15)
				)
				(justify mirror)
			)
		)
		(property "Dielectric" ""
			(at 289.551002 349.602 0)
			(layer "B.Fab")
			(hide yes)
			(effects
				(font
					(size 1 1)
					(thickness 0.15)
				)
				(justify mirror)
			)
		)
		(property "License" "Apache-2.0"
			(at 289.551002 349.602 0)
			(layer "B.Fab")
			(hide yes)
			(effects
				(font
					(size 1 1)
					(thickness 0.15)
				)
				(justify mirror)
			)
		)
		(property "MPN" "GRM188R60J476ME15D"
			(at 289.551002 349.602 0)
			(layer "B.Fab")
			(hide yes)
			(effects
				(font
					(size 1 1)
					(thickness 0.15)
				)
				(justify mirror)
			)
		)
		(property "Manufacturer" "Murata"
			(at 289.551002 349.602 0)
			(layer "B.Fab")
			(hide yes)
			(effects
				(font
					(size 1 1)
					(thickness 0.15)
				)
				(justify mirror)
			)
		)
		(property "Val" "47u"
			(at 289.551002 349.602 0)
			(layer "B.Fab")
			(hide yes)
			(effects
				(font
					(size 1 1)
					(thickness 0.15)
				)
				(justify mirror)
			)
		)
		(property "Voltage" ""
			(at 289.551002 349.602 0)
			(layer "B.Fab")
			(hide yes)
			(effects
				(font
					(size 1 1)
					(thickness 0.15)
				)
				(justify mirror)
			)
		)
		(sheetname "/FPGA power/")
		(sheetfile "fpga-power.kicad_sch")
		(attr smd)
		(fp_line
			(start -0.3 0.3)
			(end 0.3 0.3)
			(stroke
				(width 0.15)
				(type solid)
			)
			(layer "B.SilkS")
		)
		(fp_line
			(start -0.3 -0.3)
			(end 0.3 -0.3)
			(stroke
				(width 0.15)
				(type solid)
			)
			(layer "B.SilkS")
		)
		(fp_rect
			(start -1.24 0.7)
			(end 1.24 -0.7)
			(stroke
				(width 0.05)
				(type solid)
			)
			(fill no)
			(layer "B.CrtYd")
		)
		(fp_rect
			(start -0.8 0.4)
			(end 0.8 -0.4)
			(stroke
				(width 0.15)
				(type solid)
			)
			(fill no)
			(layer "B.Fab")
		)
		(pad "1" smd roundrect
			(at -0.7 0 180)
			(size 0.6 0.8)
			(layers "B.Cu" "B.Mask" "B.Paste")
			(roundrect_rratio 0.2)
			(net 188 "+1V8")
			(pintype "passive")
		)
		(pad "2" smd roundrect
			(at 0.7 0 180)
			(size 0.6 0.8)
			(layers "B.Cu" "B.Mask" "B.Paste")
			(roundrect_rratio 0.2)
			(net 1 "GND")
			(pintype "passive")
		)
	)
	(footprint "antmicro-footprints:Fiducial_1mm_Mask2mm"
		(layer "B.Cu")
		(at 199 114)
		(descr "Circular Fiducial, 1mm bare copper, 3mm soldermask opening")
		(tags "fiducial")
		(property "Reference" "FID1003"
			(at 0 1.4 0)
			(layer "B.SilkS")
			(hide yes)
			(effects
				(font
					(size 0.7 0.7)
					(thickness 0.15)
				)
				(justify right bottom mirror)
			)
		)
		(property "Value" "Fiducial_1mm_Mask2mm"
			(at 0 -2.2 0)
			(layer "B.Fab")
			(effects
				(font
					(size 0.7 0.7)
					(thickness 0.15)
				)
				(justify right bottom mirror)
			)
		)
		(property "Author" "Antmicro"
			(at 0 0 0)
			(layer "B.Fab")
			(hide yes)
			(effects
				(font
					(size 1 1)
					(thickness 0.15)
				)
				(justify mirror)
			)
		)
		(property "License" "Apache-2.0"
			(at 0 0 0)
			(layer "B.Fab")
			(hide yes)
			(effects
				(font
					(size 1 1)
					(thickness 0.15)
				)
				(justify mirror)
			)
		)
		(property "MPN" ""
			(at 0 0 0)
			(layer "B.Fab")
			(hide yes)
			(effects
				(font
					(size 1 1)
					(thickness 0.15)
				)
				(justify mirror)
			)
		)
		(property "Manufacturer" ""
			(at 0 0 0)
			(layer "B.Fab")
			(hide yes)
			(effects
				(font
					(size 1 1)
					(thickness 0.15)
				)
				(justify mirror)
			)
		)
		(sheetfile "sodimm-ddr5-tester.kicad_sch")
		(attr board_only exclude_from_pos_files exclude_from_bom)
		(fp_circle
			(center 0 0)
			(end 1.24 0)
			(stroke
				(width 0.05)
				(type solid)
			)
			(fill no)
			(layer "B.CrtYd")
		)
		(fp_circle
			(center 0 0)
			(end 0.999 0)
			(stroke
				(width 0.15)
				(type solid)
			)
			(fill no)
			(layer "B.Fab")
		)
		(pad "" smd circle
			(at 0 0)
			(size 1 1)
			(layers "B.Cu" "B.Mask")
			(solder_mask_margin 0.5)
			(clearance 0.5)
		)
	)
	(footprint "antmicro-footprints:TP_SMD_1mm"
		(layer "B.Cu")
		(at 177.74 168.38 180)
		(property "Reference" "TP56"
			(at 0.47 -0.4 0)
			(layer "B.SilkS")
			(effects
				(font
					(size 0.7 0.7)
					(thickness 0.15)
				)
				(justify left bottom mirror)
			)
		)
		(property "Value" "TP_1mm_SMD"
			(at 0 -1.4 0)
			(layer "B.Fab")
			(effects
				(font
					(size 0.7 0.7)
					(thickness 0.15)
				)
				(justify left bottom mirror)
			)
		)
		(property "MPN" ""
			(at 0 0 0)
			(unlocked yes)
			(layer "B.Fab")
			(hide yes)
			(effects
				(font
					(size 1 1)
					(thickness 0.15)
				)
				(justify mirror)
			)
		)
		(property "Manufacturer" ""
			(at 0 0 0)
			(unlocked yes)
			(layer "B.Fab")
			(hide yes)
			(effects
				(font
					(size 1 1)
					(thickness 0.15)
				)
				(justify mirror)
			)
		)
		(property "Author" "Antmicro"
			(at 0 0 0)
			(unlocked yes)
			(layer "B.Fab")
			(hide yes)
			(effects
				(font
					(size 1 1)
					(thickness 0.15)
				)
				(justify mirror)
			)
		)
		(property "License" "Apache-2.0"
			(at 0 0 0)
			(unlocked yes)
			(layer "B.Fab")
			(hide yes)
			(effects
				(font
					(size 1 1)
					(thickness 0.15)
				)
				(justify mirror)
			)
		)
		(sheetname "/Supply/")
		(sheetfile "supply.kicad_sch")
		(attr exclude_from_pos_files)
		(fp_circle
			(center 0 0)
			(end 0.6 0)
			(stroke
				(width 0.05)
				(type default)
			)
			(fill no)
			(layer "B.CrtYd")
		)
		(fp_text user "${REFERENCE}"
			(at -0.5 -2.8 0)
			(layer "B.Fab")
			(effects
				(font
					(size 0.7 0.7)
					(thickness 0.15)
				)
				(justify left bottom mirror)
			)
		)
		(fp_text user "License: Apache-2.0"
			(at -0.5 -5.2 0)
			(layer "B.Fab")
			(effects
				(font
					(size 0.7 0.7)
					(thickness 0.15)
				)
				(justify left bottom mirror)
			)
		)
		(fp_text user "Author: Antmicro"
			(at -0.5 -4 0)
			(layer "B.Fab")
			(effects
				(font
					(size 0.7 0.7)
					(thickness 0.15)
				)
				(justify left bottom mirror)
			)
		)
		(pad "1" smd circle
			(at 0 0 180)
			(size 1 1)
			(layers "B.Cu" "B.Mask")
			(net 298 "/Supply/PWR_SDA_2")
			(pinfunction "1")
			(pintype "passive")
		)
	)
	(footprint "antmicro-footprints:TP_SMD_1mm"
		(layer "B.Cu")
		(at 110 171.63 180)
		(property "Reference" "TP50"
			(at -3.3 -0.3 0)
			(layer "B.SilkS")
			(effects
				(font
					(size 0.7 0.7)
					(thickness 0.15)
				)
				(justify left bottom mirror)
			)
		)
		(property "Value" "TP_1mm_SMD"
			(at 0 -1.4 0)
			(layer "B.Fab")
			(effects
				(font
					(size 0.7 0.7)
					(thickness 0.15)
				)
				(justify left bottom mirror)
			)
		)
		(property "MPN" ""
			(at 0 0 0)
			(unlocked yes)
			(layer "B.Fab")
			(hide yes)
			(effects
				(font
					(size 1 1)
					(thickness 0.15)
				)
				(justify mirror)
			)
		)
		(property "Manufacturer" ""
			(at 0 0 0)
			(unlocked yes)
			(layer "B.Fab")
			(hide yes)
			(effects
				(font
					(size 1 1)
					(thickness 0.15)
				)
				(justify mirror)
			)
		)
		(property "Author" "Antmicro"
			(at 0 0 0)
			(unlocked yes)
			(layer "B.Fab")
			(hide yes)
			(effects
				(font
					(size 1 1)
					(thickness 0.15)
				)
				(justify mirror)
			)
		)
		(property "License" "Apache-2.0"
			(at 0 0 0)
			(unlocked yes)
			(layer "B.Fab")
			(hide yes)
			(effects
				(font
					(size 1 1)
					(thickness 0.15)
				)
				(justify mirror)
			)
		)
		(sheetname "/Debug FTDI/")
		(sheetfile "debug-ftdi.kicad_sch")
		(attr exclude_from_pos_files)
		(fp_circle
			(center 0 0)
			(end 0.6 0)
			(stroke
				(width 0.05)
				(type default)
			)
			(fill no)
			(layer "B.CrtYd")
		)
		(fp_text user "${REFERENCE}"
			(at -0.5 -2.8 0)
			(layer "B.Fab")
			(effects
				(font
					(size 0.7 0.7)
					(thickness 0.15)
				)
				(justify left bottom mirror)
			)
		)
		(fp_text user "License: Apache-2.0"
			(at -0.5 -5.2 0)
			(layer "B.Fab")
			(effects
				(font
					(size 0.7 0.7)
					(thickness 0.15)
				)
				(justify left bottom mirror)
			)
		)
		(fp_text user "Author: Antmicro"
			(at -0.5 -4 0)
			(layer "B.Fab")
			(effects
				(font
					(size 0.7 0.7)
					(thickness 0.15)
				)
				(justify left bottom mirror)
			)
		)
		(pad "1" smd circle
			(at 0 0 180)
			(size 1 1)
			(layers "B.Cu" "B.Mask")
			(net 645 "/Debug FTDI/UART1.TX")
			(pinfunction "1")
			(pintype "passive")
		)
	)
	(footprint "antmicro-footprints:C_0402_1005Metric"
		(layer "B.Cu")
		(at 126.875501 162.301 180)
		(descr "Capacitor SMD 0402 (1005 Metric), square (rectangular) end terminal, IPC_7351 nominal, (Body size source: IPC-SM-782 page 76, https://www.pcb-3d.com/wordpress/wp-content/uploads/ipc-sm-782a_amendment_1_and_2.pdf)")
		(tags "capacitor 0402")
		(property "Reference" "C22"
			(at 0 1.17 0)
			(layer "B.SilkS")
			(hide yes)
			(effects
				(font
					(size 0.7 0.7)
					(thickness 0.15)
				)
				(justify left bottom mirror)
			)
		)
		(property "Value" "C_100n_0402"
			(at 0 -1.169 0)
			(layer "B.Fab")
			(effects
				(font
					(size 0.7 0.7)
					(thickness 0.15)
				)
				(justify left bottom mirror)
			)
		)
		(property "Datasheet" "https://www.murata.com/products/productdetail?partno=GRM155R61H104KE14%23"
			(at 0 0 180)
			(layer "F.Fab")
			(hide yes)
			(effects
				(font
					(size 1.27 1.27)
					(thickness 0.15)
				)
			)
		)
		(property "Author" "Antmicro"
			(at 253.751002 324.602 0)
			(layer "B.Fab")
			(hide yes)
			(effects
				(font
					(size 1 1)
					(thickness 0.15)
				)
				(justify mirror)
			)
		)
		(property "Dielectric" "X5R"
			(at 253.751002 324.602 0)
			(layer "B.Fab")
			(hide yes)
			(effects
				(font
					(size 1 1)
					(thickness 0.15)
				)
				(justify mirror)
			)
		)
		(property "License" "Apache-2.0"
			(at 253.751002 324.602 0)
			(layer "B.Fab")
			(hide yes)
			(effects
				(font
					(size 1 1)
					(thickness 0.15)
				)
				(justify mirror)
			)
		)
		(property "MPN" "GRM155R61H104KE14D"
			(at 253.751002 324.602 0)
			(layer "B.Fab")
			(hide yes)
			(effects
				(font
					(size 1 1)
					(thickness 0.15)
				)
				(justify mirror)
			)
		)
		(property "Manufacturer" "Murata"
			(at 253.751002 324.602 0)
			(layer "B.Fab")
			(hide yes)
			(effects
				(font
					(size 1 1)
					(thickness 0.15)
				)
				(justify mirror)
			)
		)
		(property "Val" "100n"
			(at 253.751002 324.602 0)
			(layer "B.Fab")
			(hide yes)
			(effects
				(font
					(size 1 1)
					(thickness 0.15)
				)
				(justify mirror)
			)
		)
		(property "Voltage" "50V"
			(at 253.751002 324.602 0)
			(layer "B.Fab")
			(hide yes)
			(effects
				(font
					(size 1 1)
					(thickness 0.15)
				)
				(justify mirror)
			)
		)
		(sheetname "/FPGA power/")
		(sheetfile "fpga-power.kicad_sch")
		(attr smd)
		(fp_rect
			(start -0.9656 0.4572)
			(end 0.9652 -0.4828)
			(stroke
				(width 0.05)
				(type solid)
			)
			(fill no)
			(layer "B.CrtYd")
		)
		(fp_line
			(start 0.498 0.25)
			(end 0.498 -0.248)
			(stroke
				(width 0.15)
				(type solid)
			)
			(layer "B.Fab")
		)
		(fp_line
			(start 0.498 -0.248)
			(end -0.5 -0.248)
			(stroke
				(width 0.15)
				(type solid)
			)
			(layer "B.Fab")
		)
		(fp_line
			(start -0.5 0.25)
			(end 0.498 0.25)
			(stroke
				(width 0.15)
				(type solid)
			)
			(layer "B.Fab")
		)
		(fp_line
			(start -0.5 -0.248)
			(end -0.5 0.25)
			(stroke
				(width 0.15)
				(type solid)
			)
			(layer "B.Fab")
		)
		(pad "1" smd roundrect
			(at -0.5 0 90)
			(size 0.6 0.6)
			(layers "B.Cu" "B.Mask" "B.Paste")
			(roundrect_rratio 0.25)
			(net 1 "GND")
			(pintype "passive")
		)
		(pad "2" smd roundrect
			(at 0.498 0 180)
			(size 0.6 0.6)
			(layers "B.Cu" "B.Mask" "B.Paste")
			(roundrect_rratio 0.25)
			(net 200 "+3V3")
			(pintype "passive")
		)
	)
	(footprint "antmicro-footprints:C_0402_1005Metric"
		(layer "B.Cu")
		(at 147.877001 178.3025 180)
		(descr "Capacitor SMD 0402 (1005 Metric), square (rectangular) end terminal, IPC_7351 nominal, (Body size source: IPC-SM-782 page 76, https://www.pcb-3d.com/wordpress/wp-content/uploads/ipc-sm-782a_amendment_1_and_2.pdf)")
		(tags "capacitor 0402")
		(property "Reference" "C98"
			(at 0 1.17 0)
			(layer "B.SilkS")
			(hide yes)
			(effects
				(font
					(size 0.7 0.7)
					(thickness 0.15)
				)
				(justify left bottom mirror)
			)
		)
		(property "Value" "C_100n_0402"
			(at 0 -1.169 0)
			(layer "B.Fab")
			(effects
				(font
					(size 0.7 0.7)
					(thickness 0.15)
				)
				(justify left bottom mirror)
			)
		)
		(property "Datasheet" "https://www.murata.com/products/productdetail?partno=GRM155R61H104KE14%23"
			(at 0 0 180)
			(layer "F.Fab")
			(hide yes)
			(effects
				(font
					(size 1.27 1.27)
					(thickness 0.15)
				)
			)
		)
		(property "Author" "Antmicro"
			(at 295.754002 356.605 0)
			(layer "B.Fab")
			(hide yes)
			(effects
				(font
					(size 1 1)
					(thickness 0.15)
				)
				(justify mirror)
			)
		)
		(property "Dielectric" "X5R"
			(at 295.754002 356.605 0)
			(layer "B.Fab")
			(hide yes)
			(effects
				(font
					(size 1 1)
					(thickness 0.15)
				)
				(justify mirror)
			)
		)
		(property "License" "Apache-2.0"
			(at 295.754002 356.605 0)
			(layer "B.Fab")
			(hide yes)
			(effects
				(font
					(size 1 1)
					(thickness 0.15)
				)
				(justify mirror)
			)
		)
		(property "MPN" "GRM155R61H104KE14D"
			(at 295.754002 356.605 0)
			(layer "B.Fab")
			(hide yes)
			(effects
				(font
					(size 1 1)
					(thickness 0.15)
				)
				(justify mirror)
			)
		)
		(property "Manufacturer" "Murata"
			(at 295.754002 356.605 0)
			(layer "B.Fab")
			(hide yes)
			(effects
				(font
					(size 1 1)
					(thickness 0.15)
				)
				(justify mirror)
			)
		)
		(property "Val" "100n"
			(at 295.754002 356.605 0)
			(layer "B.Fab")
			(hide yes)
			(effects
				(font
					(size 1 1)
					(thickness 0.15)
				)
				(justify mirror)
			)
		)
		(property "Voltage" "50V"
			(at 295.754002 356.605 0)
			(layer "B.Fab")
			(hide yes)
			(effects
				(font
					(size 1 1)
					(thickness 0.15)
				)
				(justify mirror)
			)
		)
		(sheetname "/FPGA power/")
		(sheetfile "fpga-power.kicad_sch")
		(attr smd)
		(fp_rect
			(start -0.9656 0.4572)
			(end 0.9652 -0.4828)
			(stroke
				(width 0.05)
				(type solid)
			)
			(fill no)
			(layer "B.CrtYd")
		)
		(fp_line
			(start 0.498 0.25)
			(end 0.498 -0.248)
			(stroke
				(width 0.15)
				(type solid)
			)
			(layer "B.Fab")
		)
		(fp_line
			(start 0.498 -0.248)
			(end -0.5 -0.248)
			(stroke
				(width 0.15)
				(type solid)
			)
			(layer "B.Fab")
		)
		(fp_line
			(start -0.5 0.25)
			(end 0.498 0.25)
			(stroke
				(width 0.15)
				(type solid)
			)
			(layer "B.Fab")
		)
		(fp_line
			(start -0.5 -0.248)
			(end -0.5 0.25)
			(stroke
				(width 0.15)
				(type solid)
			)
			(layer "B.Fab")
		)
		(pad "1" smd roundrect
			(at -0.5 0 90)
			(size 0.6 0.6)
			(layers "B.Cu" "B.Mask" "B.Paste")
			(roundrect_rratio 0.25)
			(net 1 "GND")
			(pintype "passive")
		)
		(pad "2" smd roundrect
			(at 0.498 0 180)
			(size 0.6 0.6)
			(layers "B.Cu" "B.Mask" "B.Paste")
			(roundrect_rratio 0.25)
			(net 187 "+1V0_MGTAVCC")
			(pintype "passive")
		)
	)
	(footprint "antmicro-footprints:C_0402_1005Metric"
		(layer "B.Cu")
		(at 141.875501 169.301)
		(descr "Capacitor SMD 0402 (1005 Metric), square (rectangular) end terminal, IPC_7351 nominal, (Body size source: IPC-SM-782 page 76, https://www.pcb-3d.com/wordpress/wp-content/uploads/ipc-sm-782a_amendment_1_and_2.pdf)")
		(tags "capacitor 0402")
		(property "Reference" "C78"
			(at 0 1.17 180)
			(layer "B.SilkS")
			(hide yes)
			(effects
				(font
					(size 0.7 0.7)
					(thickness 0.15)
				)
				(justify left bottom mirror)
			)
		)
		(property "Value" "C_100n_0402"
			(at 0 -1.169 180)
			(layer "B.Fab")
			(effects
				(font
					(size 0.7 0.7)
					(thickness 0.15)
				)
				(justify left bottom mirror)
			)
		)
		(property "Datasheet" "https://www.murata.com/products/productdetail?partno=GRM155R61H104KE14%23"
			(at 0 0 0)
			(layer "F.Fab")
			(hide yes)
			(effects
				(font
					(size 1.27 1.27)
					(thickness 0.15)
				)
			)
		)
		(property "Author" "Antmicro"
			(at 0 0 0)
			(layer "B.Fab")
			(hide yes)
			(effects
				(font
					(size 1 1)
					(thickness 0.15)
				)
				(justify mirror)
			)
		)
		(property "Dielectric" "X5R"
			(at 0 0 0)
			(layer "B.Fab")
			(hide yes)
			(effects
				(font
					(size 1 1)
					(thickness 0.15)
				)
				(justify mirror)
			)
		)
		(property "License" "Apache-2.0"
			(at 0 0 0)
			(layer "B.Fab")
			(hide yes)
			(effects
				(font
					(size 1 1)
					(thickness 0.15)
				)
				(justify mirror)
			)
		)
		(property "MPN" "GRM155R61H104KE14D"
			(at 0 0 0)
			(layer "B.Fab")
			(hide yes)
			(effects
				(font
					(size 1 1)
					(thickness 0.15)
				)
				(justify mirror)
			)
		)
		(property "Manufacturer" "Murata"
			(at 0 0 0)
			(layer "B.Fab")
			(hide yes)
			(effects
				(font
					(size 1 1)
					(thickness 0.15)
				)
				(justify mirror)
			)
		)
		(property "Val" "100n"
			(at 0 0 0)
			(layer "B.Fab")
			(hide yes)
			(effects
				(font
					(size 1 1)
					(thickness 0.15)
				)
				(justify mirror)
			)
		)
		(property "Voltage" "50V"
			(at 0 0 0)
			(layer "B.Fab")
			(hide yes)
			(effects
				(font
					(size 1 1)
					(thickness 0.15)
				)
				(justify mirror)
			)
		)
		(sheetname "/FPGA power/")
		(sheetfile "fpga-power.kicad_sch")
		(attr smd)
		(fp_rect
			(start -0.9656 0.4572)
			(end 0.9652 -0.4828)
			(stroke
				(width 0.05)
				(type solid)
			)
			(fill no)
			(layer "B.CrtYd")
		)
		(fp_line
			(start -0.5 -0.248)
			(end -0.5 0.25)
			(stroke
				(width 0.15)
				(type solid)
			)
			(layer "B.Fab")
		)
		(fp_line
			(start -0.5 0.25)
			(end 0.498 0.25)
			(stroke
				(width 0.15)
				(type solid)
			)
			(layer "B.Fab")
		)
		(fp_line
			(start 0.498 -0.248)
			(end -0.5 -0.248)
			(stroke
				(width 0.15)
				(type solid)
			)
			(layer "B.Fab")
		)
		(fp_line
			(start 0.498 0.25)
			(end 0.498 -0.248)
			(stroke
				(width 0.15)
				(type solid)
			)
			(layer "B.Fab")
		)
		(pad "1" smd roundrect
			(at -0.5 0 270)
			(size 0.6 0.6)
			(layers "B.Cu" "B.Mask" "B.Paste")
			(roundrect_rratio 0.25)
			(net 1 "GND")
			(pintype "passive")
		)
		(pad "2" smd roundrect
			(at 0.498 0)
			(size 0.6 0.6)
			(layers "B.Cu" "B.Mask" "B.Paste")
			(roundrect_rratio 0.25)
			(net 206 "+1V1")
			(pintype "passive")
		)
	)
	(footprint "antmicro-footprints:Fiducial_1mm_Mask2mm"
		(layer "B.Cu")
		(at 82.460501 197.866 180)
		(descr "Circular Fiducial, 1mm bare copper, 3mm soldermask opening")
		(tags "fiducial")
		(property "Reference" "FID1001"
			(at 0 1.4 0)
			(layer "B.SilkS")
			(hide yes)
			(effects
				(font
					(size 0.7 0.7)
					(thickness 0.15)
				)
				(justify left bottom mirror)
			)
		)
		(property "Value" "Fiducial_1mm_Mask2mm"
			(at 0 -2.2 0)
			(layer "B.Fab")
			(effects
				(font
					(size 0.7 0.7)
					(thickness 0.15)
				)
				(justify left bottom mirror)
			)
		)
		(property "Author" "Antmicro"
			(at 164.921002 395.732 0)
			(layer "B.Fab")
			(hide yes)
			(effects
				(font
					(size 1 1)
					(thickness 0.15)
				)
				(justify mirror)
			)
		)
		(property "License" "Apache-2.0"
			(at 164.921002 395.732 0)
			(layer "B.Fab")
			(hide yes)
			(effects
				(font
					(size 1 1)
					(thickness 0.15)
				)
				(justify mirror)
			)
		)
		(property "MPN" ""
			(at 164.921002 395.732 0)
			(layer "B.Fab")
			(hide yes)
			(effects
				(font
					(size 1 1)
					(thickness 0.15)
				)
				(justify mirror)
			)
		)
		(property "Manufacturer" ""
			(at 164.921002 395.732 0)
			(layer "B.Fab")
			(hide yes)
			(effects
				(font
					(size 1 1)
					(thickness 0.15)
				)
				(justify mirror)
			)
		)
		(sheetfile "sodimm-ddr5-tester.kicad_sch")
		(attr board_only exclude_from_pos_files exclude_from_bom)
		(fp_circle
			(center 0 0)
			(end 1.24 0)
			(stroke
				(width 0.05)
				(type solid)
			)
			(fill no)
			(layer "B.CrtYd")
		)
		(fp_circle
			(center 0 0)
			(end 0.999 0)
			(stroke
				(width 0.15)
				(type solid)
			)
			(fill no)
			(layer "B.Fab")
		)
		(pad "" smd circle
			(at 0 0 180)
			(size 1 1)
			(layers "B.Cu" "B.Mask")
			(solder_mask_margin 0.5)
			(clearance 0.5)
		)
	)
	(footprint "antmicro-footprints:R_0402_1005Metric"
		(layer "B.Cu")
		(at 180.8 193 180)
		(descr "Resistor SMD 0402")
		(tags "resistor SMD 0402")
		(property "Reference" "R178"
			(at 1.25 -0.4 0)
			(layer "B.SilkS")
			(effects
				(font
					(size 0.7 0.7)
					(thickness 0.15)
				)
				(justify left bottom mirror)
			)
		)
		(property "Value" "R_0R_0402"
			(at -1.011843 -1.772047 0)
			(layer "B.Fab")
			(effects
				(font
					(size 0.7 0.7)
					(thickness 0.15)
				)
				(justify left bottom mirror)
			)
		)
		(property "Datasheet" "https://industrial.panasonic.com/cdbs/www-data/pdf/RDA0000/AOA0000C301.pdf"
			(at 0 0 180)
			(layer "F.Fab")
			(hide yes)
			(effects
				(font
					(size 1.27 1.27)
					(thickness 0.15)
				)
			)
		)
		(property "Author" "Antmicro"
			(at 361.6 386 0)
			(layer "B.Fab")
			(hide yes)
			(effects
				(font
					(size 1 1)
					(thickness 0.15)
				)
				(justify mirror)
			)
		)
		(property "Current" "1A"
			(at 361.6 386 0)
			(layer "B.Fab")
			(hide yes)
			(effects
				(font
					(size 1 1)
					(thickness 0.15)
				)
				(justify mirror)
			)
		)
		(property "License" "Apache-2.0"
			(at 361.6 386 0)
			(layer "B.Fab")
			(hide yes)
			(effects
				(font
					(size 1 1)
					(thickness 0.15)
				)
				(justify mirror)
			)
		)
		(property "MPN" "ERJ2GE0R00X"
			(at 361.6 386 0)
			(layer "B.Fab")
			(hide yes)
			(effects
				(font
					(size 1 1)
					(thickness 0.15)
				)
				(justify mirror)
			)
		)
		(property "Manufacturer" "Panasonic"
			(at 361.6 386 0)
			(layer "B.Fab")
			(hide yes)
			(effects
				(font
					(size 1 1)
					(thickness 0.15)
				)
				(justify mirror)
			)
		)
		(property "Tolerance" ""
			(at 361.6 386 0)
			(layer "B.Fab")
			(hide yes)
			(effects
				(font
					(size 1 1)
					(thickness 0.15)
				)
				(justify mirror)
			)
		)
		(property "Val" "0R"
			(at 361.6 386 0)
			(layer "B.Fab")
			(hide yes)
			(effects
				(font
					(size 1 1)
					(thickness 0.15)
				)
				(justify mirror)
			)
		)
		(sheetname "/I^{2}C/")
		(sheetfile "i2c.kicad_sch")
		(attr exclude_from_pos_files exclude_from_bom dnp)
		(fp_rect
			(start -0.93 0.47)
			(end 0.93 -0.47)
			(stroke
				(width 0.05)
				(type solid)
			)
			(fill no)
			(layer "B.CrtYd")
		)
		(fp_rect
			(start -0.5 0.25)
			(end 0.5 -0.25)
			(stroke
				(width 0.15)
				(type solid)
			)
			(fill no)
			(layer "B.Fab")
		)
		(pad "1" smd roundrect
			(at -0.485 0 180)
			(size 0.59 0.64)
			(layers "B.Cu" "B.Mask" "B.Paste")
			(roundrect_rratio 0.25)
			(net 691 "/I^{2}C/PWR.SCL")
			(pintype "passive")
		)
		(pad "2" smd roundrect
			(at 0.485 0 180)
			(size 0.59 0.64)
			(layers "B.Cu" "B.Mask" "B.Paste")
			(roundrect_rratio 0.25)
			(net 689 "/FPGA bank 14/FPGA_PWR.SCL")
			(pintype "passive")
		)
	)
	(footprint "antmicro-footprints:R_0402_1005Metric"
		(layer "B.Cu")
		(at 196.7 189.175)
		(descr "Resistor SMD 0402")
		(tags "resistor SMD 0402")
		(property "Reference" "R152"
			(at 1.33 1.385 180)
			(layer "B.SilkS")
			(effects
				(font
					(size 0.7 0.7)
					(thickness 0.15)
				)
				(justify left bottom mirror)
			)
		)
		(property "Value" "R_0R_0402"
			(at -1.011843 -1.772047 180)
			(layer "B.Fab")
			(effects
				(font
					(size 0.7 0.7)
					(thickness 0.15)
				)
				(justify left bottom mirror)
			)
		)
		(property "Datasheet" "https://industrial.panasonic.com/cdbs/www-data/pdf/RDA0000/AOA0000C301.pdf"
			(at 0 0 0)
			(layer "F.Fab")
			(hide yes)
			(effects
				(font
					(size 1.27 1.27)
					(thickness 0.15)
				)
			)
		)
		(property "Author" "Antmicro"
			(at 0 0 0)
			(layer "B.Fab")
			(hide yes)
			(effects
				(font
					(size 1 1)
					(thickness 0.15)
				)
				(justify mirror)
			)
		)
		(property "Current" "1A"
			(at 0 0 0)
			(layer "B.Fab")
			(hide yes)
			(effects
				(font
					(size 1 1)
					(thickness 0.15)
				)
				(justify mirror)
			)
		)
		(property "License" "Apache-2.0"
			(at 0 0 0)
			(layer "B.Fab")
			(hide yes)
			(effects
				(font
					(size 1 1)
					(thickness 0.15)
				)
				(justify mirror)
			)
		)
		(property "MPN" "ERJ2GE0R00X"
			(at 0 0 0)
			(layer "B.Fab")
			(hide yes)
			(effects
				(font
					(size 1 1)
					(thickness 0.15)
				)
				(justify mirror)
			)
		)
		(property "Manufacturer" "Panasonic"
			(at 0 0 0)
			(layer "B.Fab")
			(hide yes)
			(effects
				(font
					(size 1 1)
					(thickness 0.15)
				)
				(justify mirror)
			)
		)
		(property "Tolerance" ""
			(at 0 0 0)
			(layer "B.Fab")
			(hide yes)
			(effects
				(font
					(size 1 1)
					(thickness 0.15)
				)
				(justify mirror)
			)
		)
		(property "Val" "0R"
			(at 0 0 0)
			(layer "B.Fab")
			(hide yes)
			(effects
				(font
					(size 1 1)
					(thickness 0.15)
				)
				(justify mirror)
			)
		)
		(sheetname "/Supply/")
		(sheetfile "supply.kicad_sch")
		(attr exclude_from_pos_files exclude_from_bom dnp)
		(fp_rect
			(start -0.93 0.47)
			(end 0.93 -0.47)
			(stroke
				(width 0.05)
				(type solid)
			)
			(fill no)
			(layer "B.CrtYd")
		)
		(fp_rect
			(start -0.5 0.25)
			(end 0.5 -0.25)
			(stroke
				(width 0.15)
				(type solid)
			)
			(fill no)
			(layer "B.Fab")
		)
		(pad "1" smd roundrect
			(at -0.485 0)
			(size 0.59 0.64)
			(layers "B.Cu" "B.Mask" "B.Paste")
			(roundrect_rratio 0.25)
			(net 1 "GND")
			(pintype "passive")
		)
		(pad "2" smd roundrect
			(at 0.485 0)
			(size 0.59 0.64)
			(layers "B.Cu" "B.Mask" "B.Paste")
			(roundrect_rratio 0.25)
			(net 210 "/Supply/FB1")
			(pintype "passive")
		)
	)
	(footprint "antmicro-footprints:R_0402_1005Metric"
		(layer "B.Cu")
		(at 137.777001 160.8005 180)
		(descr "Resistor SMD 0402")
		(tags "resistor SMD 0402")
		(property "Reference" "R129"
			(at -1.122484 0.772697 0)
			(layer "B.SilkS")
			(hide yes)
			(effects
				(font
					(size 0.7 0.7)
					(thickness 0.15)
				)
				(justify left bottom mirror)
			)
		)
		(property "Value" "R_1k_0402"
			(at -1.011843 -1.772047 0)
			(layer "B.Fab")
			(effects
				(font
					(size 0.7 0.7)
					(thickness 0.15)
				)
				(justify left bottom mirror)
			)
		)
		(property "Datasheet" "https://www.bourns.com/docs/product-datasheets/cr.pdf"
			(at 0 0 180)
			(layer "F.Fab")
			(hide yes)
			(effects
				(font
					(size 1.27 1.27)
					(thickness 0.15)
				)
			)
		)
		(property "Author" "Antmicro"
			(at 275.554002 321.601 0)
			(layer "B.Fab")
			(hide yes)
			(effects
				(font
					(size 1 1)
					(thickness 0.15)
				)
				(justify mirror)
			)
		)
		(property "License" "Apache-2.0"
			(at 275.554002 321.601 0)
			(layer "B.Fab")
			(hide yes)
			(effects
				(font
					(size 1 1)
					(thickness 0.15)
				)
				(justify mirror)
			)
		)
		(property "MPN" "CR0402-FX-1001GLF"
			(at 275.554002 321.601 0)
			(layer "B.Fab")
			(hide yes)
			(effects
				(font
					(size 1 1)
					(thickness 0.15)
				)
				(justify mirror)
			)
		)
		(property "Manufacturer" "Bourns"
			(at 275.554002 321.601 0)
			(layer "B.Fab")
			(hide yes)
			(effects
				(font
					(size 1 1)
					(thickness 0.15)
				)
				(justify mirror)
			)
		)
		(property "Tolerance" "1%"
			(at 275.554002 321.601 0)
			(layer "B.Fab")
			(hide yes)
			(effects
				(font
					(size 1 1)
					(thickness 0.15)
				)
				(justify mirror)
			)
		)
		(property "Val" "1k"
			(at 275.554002 321.601 0)
			(layer "B.Fab")
			(hide yes)
			(effects
				(font
					(size 1 1)
					(thickness 0.15)
				)
				(justify mirror)
			)
		)
		(sheetname "/FPGA banks HP/")
		(sheetfile "fpga-banks-32-34.kicad_sch")
		(attr smd)
		(fp_rect
			(start -0.93 0.47)
			(end 0.93 -0.47)
			(stroke
				(width 0.05)
				(type solid)
			)
			(fill no)
			(layer "B.CrtYd")
		)
		(fp_rect
			(start -0.5 0.25)
			(end 0.5 -0.25)
			(stroke
				(width 0.15)
				(type solid)
			)
			(fill no)
			(layer "B.Fab")
		)
		(pad "1" smd roundrect
			(at -0.485 0 180)
			(size 0.59 0.64)
			(layers "B.Cu" "B.Mask" "B.Paste")
			(roundrect_rratio 0.25)
			(net 379 "Net-(R129-Pad1)")
			(pintype "passive")
		)
		(pad "2" smd roundrect
			(at 0.485 0 180)
			(size 0.59 0.64)
			(layers "B.Cu" "B.Mask" "B.Paste")
			(roundrect_rratio 0.25)
			(net 206 "+1V1")
			(pintype "passive")
		)
	)
	(footprint "antmicro-footprints:R_0402_1005Metric"
		(layer "B.Cu")
		(at 122.350501 176.476 180)
		(descr "Resistor SMD 0402")
		(tags "resistor SMD 0402")
		(property "Reference" "R1"
			(at -1.122484 0.772697 0)
			(layer "B.SilkS")
			(hide yes)
			(effects
				(font
					(size 0.7 0.7)
					(thickness 0.15)
				)
				(justify left bottom mirror)
			)
		)
		(property "Value" "R_10k_0402"
			(at -1.011843 -1.772047 0)
			(layer "B.Fab")
			(effects
				(font
					(size 0.7 0.7)
					(thickness 0.15)
				)
				(justify left bottom mirror)
			)
		)
		(property "Datasheet" "https://www.bourns.com/docs/product-datasheets/cr.pdf"
			(at 0 0 180)
			(layer "F.Fab")
			(hide yes)
			(effects
				(font
					(size 1.27 1.27)
					(thickness 0.15)
				)
			)
		)
		(property "Author" "Antmicro"
			(at 244.701002 352.952 0)
			(layer "B.Fab")
			(hide yes)
			(effects
				(font
					(size 1 1)
					(thickness 0.15)
				)
				(justify mirror)
			)
		)
		(property "License" "Apache-2.0"
			(at 244.701002 352.952 0)
			(layer "B.Fab")
			(hide yes)
			(effects
				(font
					(size 1 1)
					(thickness 0.15)
				)
				(justify mirror)
			)
		)
		(property "MPN" "CR0402-FX-1002GLF"
			(at 244.701002 352.952 0)
			(layer "B.Fab")
			(hide yes)
			(effects
				(font
					(size 1 1)
					(thickness 0.15)
				)
				(justify mirror)
			)
		)
		(property "Manufacturer" "Bourns"
			(at 244.701002 352.952 0)
			(layer "B.Fab")
			(hide yes)
			(effects
				(font
					(size 1 1)
					(thickness 0.15)
				)
				(justify mirror)
			)
		)
		(property "Tolerance" "1%"
			(at 244.701002 352.952 0)
			(layer "B.Fab")
			(hide yes)
			(effects
				(font
					(size 1 1)
					(thickness 0.15)
				)
				(justify mirror)
			)
		)
		(property "Val" "10k"
			(at 244.701002 352.952 0)
			(layer "B.Fab")
			(hide yes)
			(effects
				(font
					(size 1 1)
					(thickness 0.15)
				)
				(justify mirror)
			)
		)
		(sheetname "/HyperRAM + QSPI Flash/")
		(sheetfile "hyperram-flash.kicad_sch")
		(attr smd)
		(fp_rect
			(start -0.93 0.47)
			(end 0.93 -0.47)
			(stroke
				(width 0.05)
				(type solid)
			)
			(fill no)
			(layer "B.CrtYd")
		)
		(fp_rect
			(start -0.5 0.25)
			(end 0.5 -0.25)
			(stroke
				(width 0.15)
				(type solid)
			)
			(fill no)
			(layer "B.Fab")
		)
		(pad "1" smd roundrect
			(at -0.485 0 180)
			(size 0.59 0.64)
			(layers "B.Cu" "B.Mask" "B.Paste")
			(roundrect_rratio 0.25)
			(net 200 "+3V3")
			(pintype "passive")
		)
		(pad "2" smd roundrect
			(at 0.485 0 180)
			(size 0.59 0.64)
			(layers "B.Cu" "B.Mask" "B.Paste")
			(roundrect_rratio 0.25)
			(net 623 "/FPGA bank 12/HyperRAM.~{RESET}")
			(pintype "passive")
		)
	)
	(footprint "antmicro-footprints:TP_SMD_1mm"
		(layer "B.Cu")
		(at 186.4 190.6 180)
		(property "Reference" "TP29"
			(at 0 0.731898 0)
			(layer "B.SilkS")
			(hide yes)
			(effects
				(font
					(size 0.7 0.7)
					(thickness 0.15)
				)
				(justify left bottom mirror)
			)
		)
		(property "Value" "TP_1mm_SMD"
			(at 0 -1.4 0)
			(layer "B.Fab")
			(effects
				(font
					(size 0.7 0.7)
					(thickness 0.15)
				)
				(justify left bottom mirror)
			)
		)
		(property "MPN" ""
			(at 0 0 0)
			(unlocked yes)
			(layer "B.Fab")
			(hide yes)
			(effects
				(font
					(size 1 1)
					(thickness 0.15)
				)
				(justify mirror)
			)
		)
		(property "Manufacturer" ""
			(at 0 0 0)
			(unlocked yes)
			(layer "B.Fab")
			(hide yes)
			(effects
				(font
					(size 1 1)
					(thickness 0.15)
				)
				(justify mirror)
			)
		)
		(property "Author" "Antmicro"
			(at 0 0 0)
			(unlocked yes)
			(layer "B.Fab")
			(hide yes)
			(effects
				(font
					(size 1 1)
					(thickness 0.15)
				)
				(justify mirror)
			)
		)
		(property "License" "Apache-2.0"
			(at 0 0 0)
			(unlocked yes)
			(layer "B.Fab")
			(hide yes)
			(effects
				(font
					(size 1 1)
					(thickness 0.15)
				)
				(justify mirror)
			)
		)
		(sheetname "/Supply/")
		(sheetfile "supply.kicad_sch")
		(attr exclude_from_pos_files)
		(fp_circle
			(center 0 0)
			(end 0.6 0)
			(stroke
				(width 0.05)
				(type default)
			)
			(fill no)
			(layer "B.CrtYd")
		)
		(fp_text user "Author: Antmicro"
			(at -0.5 -4 0)
			(layer "B.Fab")
			(effects
				(font
					(size 0.7 0.7)
					(thickness 0.15)
				)
				(justify left bottom mirror)
			)
		)
		(fp_text user "${REFERENCE}"
			(at -0.5 -2.8 0)
			(layer "B.Fab")
			(effects
				(font
					(size 0.7 0.7)
					(thickness 0.15)
				)
				(justify left bottom mirror)
			)
		)
		(fp_text user "License: Apache-2.0"
			(at -0.5 -5.2 0)
			(layer "B.Fab")
			(effects
				(font
					(size 0.7 0.7)
					(thickness 0.15)
				)
				(justify left bottom mirror)
			)
		)
		(pad "1" smd circle
			(at 0 0 180)
			(size 1 1)
			(layers "B.Cu" "B.Mask")
			(net 64 "/Supply/1V7")
			(pinfunction "1")
			(pintype "passive")
		)
	)
	(footprint "antmicro-footprints:R_0402_1005Metric"
		(layer "B.Cu")
		(at 180.8 200.4 180)
		(descr "Resistor SMD 0402")
		(tags "resistor SMD 0402")
		(property "Reference" "R174"
			(at -3.95 -0.5 0)
			(layer "B.SilkS")
			(effects
				(font
					(size 0.7 0.7)
					(thickness 0.15)
				)
				(justify left bottom mirror)
			)
		)
		(property "Value" "R_0R_0402"
			(at -1.011843 -1.772047 0)
			(layer "B.Fab")
			(effects
				(font
					(size 0.7 0.7)
					(thickness 0.15)
				)
				(justify left bottom mirror)
			)
		)
		(property "Datasheet" "https://industrial.panasonic.com/cdbs/www-data/pdf/RDA0000/AOA0000C301.pdf"
			(at 0 0 180)
			(layer "F.Fab")
			(hide yes)
			(effects
				(font
					(size 1.27 1.27)
					(thickness 0.15)
				)
			)
		)
		(property "Author" "Antmicro"
			(at 361.6 400.8 0)
			(layer "B.Fab")
			(hide yes)
			(effects
				(font
					(size 1 1)
					(thickness 0.15)
				)
				(justify mirror)
			)
		)
		(property "Current" "1A"
			(at 361.6 400.8 0)
			(layer "B.Fab")
			(hide yes)
			(effects
				(font
					(size 1 1)
					(thickness 0.15)
				)
				(justify mirror)
			)
		)
		(property "License" "Apache-2.0"
			(at 361.6 400.8 0)
			(layer "B.Fab")
			(hide yes)
			(effects
				(font
					(size 1 1)
					(thickness 0.15)
				)
				(justify mirror)
			)
		)
		(property "MPN" "ERJ2GE0R00X"
			(at 361.6 400.8 0)
			(layer "B.Fab")
			(hide yes)
			(effects
				(font
					(size 1 1)
					(thickness 0.15)
				)
				(justify mirror)
			)
		)
		(property "Manufacturer" "Panasonic"
			(at 361.6 400.8 0)
			(layer "B.Fab")
			(hide yes)
			(effects
				(font
					(size 1 1)
					(thickness 0.15)
				)
				(justify mirror)
			)
		)
		(property "Tolerance" ""
			(at 361.6 400.8 0)
			(layer "B.Fab")
			(hide yes)
			(effects
				(font
					(size 1 1)
					(thickness 0.15)
				)
				(justify mirror)
			)
		)
		(property "Val" "0R"
			(at 361.6 400.8 0)
			(layer "B.Fab")
			(hide yes)
			(effects
				(font
					(size 1 1)
					(thickness 0.15)
				)
				(justify mirror)
			)
		)
		(sheetname "/I^{2}C/")
		(sheetfile "i2c.kicad_sch")
		(attr exclude_from_pos_files exclude_from_bom dnp)
		(fp_rect
			(start -0.93 0.47)
			(end 0.93 -0.47)
			(stroke
				(width 0.05)
				(type solid)
			)
			(fill no)
			(layer "B.CrtYd")
		)
		(fp_rect
			(start -0.5 0.25)
			(end 0.5 -0.25)
			(stroke
				(width 0.15)
				(type solid)
			)
			(fill no)
			(layer "B.Fab")
		)
		(pad "1" smd roundrect
			(at -0.485 0 180)
			(size 0.59 0.64)
			(layers "B.Cu" "B.Mask" "B.Paste")
			(roundrect_rratio 0.25)
			(net 690 "/I^{2}C/PWR.SDA")
			(pintype "passive")
		)
		(pad "2" smd roundrect
			(at 0.485 0 180)
			(size 0.59 0.64)
			(layers "B.Cu" "B.Mask" "B.Paste")
			(roundrect_rratio 0.25)
			(net 683 "/FPGA bank 14/FPGA_DDR.SDA")
			(pintype "passive")
		)
	)
	(footprint "antmicro-footprints:C_0805_2012Metric"
		(layer "B.Cu")
		(at 136.000501 174.801)
		(descr "Capacitor SMD 0805")
		(tags "capacitor SMD 0805")
		(property "Reference" "C54"
			(at -2.10551 1.198678 0)
			(layer "B.SilkS")
			(hide yes)
			(effects
				(font
					(size 0.7 0.7)
					(thickness 0.15)
				)
				(justify right bottom mirror)
			)
		)
		(property "Value" "C_100u_0805"
			(at -2.055717 -1.963152 0)
			(layer "B.Fab")
			(effects
				(font
					(size 0.7 0.7)
					(thickness 0.15)
				)
				(justify right bottom mirror)
			)
		)
		(property "Datasheet" "https://www.murata.com/products/productdetail?partno=GRM21BR60J107ME15%23"
			(at 0 0 0)
			(layer "F.Fab")
			(hide yes)
			(effects
				(font
					(size 1.27 1.27)
					(thickness 0.15)
				)
			)
		)
		(property "Author" "Antmicro"
			(at 0 0 0)
			(layer "B.Fab")
			(hide yes)
			(effects
				(font
					(size 1 1)
					(thickness 0.15)
				)
				(justify mirror)
			)
		)
		(property "Dielectric" ""
			(at 0 0 0)
			(layer "B.Fab")
			(hide yes)
			(effects
				(font
					(size 1 1)
					(thickness 0.15)
				)
				(justify mirror)
			)
		)
		(property "License" "Apache-2.0"
			(at 0 0 0)
			(layer "B.Fab")
			(hide yes)
			(effects
				(font
					(size 1 1)
					(thickness 0.15)
				)
				(justify mirror)
			)
		)
		(property "MPN" "GRM21BR60J107ME15L"
			(at 0 0 0)
			(layer "B.Fab")
			(hide yes)
			(effects
				(font
					(size 1 1)
					(thickness 0.15)
				)
				(justify mirror)
			)
		)
		(property "Manufacturer" "Murata"
			(at 0 0 0)
			(layer "B.Fab")
			(hide yes)
			(effects
				(font
					(size 1 1)
					(thickness 0.15)
				)
				(justify mirror)
			)
		)
		(property "Val" "100u"
			(at 0 0 0)
			(layer "B.Fab")
			(hide yes)
			(effects
				(font
					(size 1 1)
					(thickness 0.15)
				)
				(justify mirror)
			)
		)
		(property "Voltage" ""
			(at 0 0 0)
			(layer "B.Fab")
			(hide yes)
			(effects
				(font
					(size 1 1)
					(thickness 0.15)
				)
				(justify mirror)
			)
		)
		(sheetname "/FPGA power/")
		(sheetfile "fpga-power.kicad_sch")
		(attr smd)
		(fp_line
			(start -0.3 -0.8)
			(end 0.3 -0.8)
			(stroke
				(width 0.15)
				(type solid)
			)
			(layer "B.SilkS")
		)
		(fp_line
			(start -0.3 0.8)
			(end 0.3 0.8)
			(stroke
				(width 0.15)
				(type solid)
			)
			(layer "B.SilkS")
		)
		(fp_rect
			(start -1.9 0.93)
			(end 1.9 -0.93)
			(stroke
				(width 0.05)
				(type solid)
			)
			(fill no)
			(layer "B.CrtYd")
		)
		(fp_rect
			(start -0.95 0.675)
			(end 0.95 -0.675)
			(stroke
				(width 0.15)
				(type solid)
			)
			(fill no)
			(layer "B.Fab")
		)
		(pad "1" smd rect
			(at -1.05 0)
			(size 1.2 1.2)
			(layers "B.Cu" "B.Mask" "B.Paste")
			(net 1 "GND")
			(pintype "passive")
		)
		(pad "2" smd rect
			(at 1.05 0)
			(size 1.2 1.2)
			(layers "B.Cu" "B.Mask" "B.Paste")
			(net 227 "+1V0")
			(pintype "passive")
		)
	)
	(footprint "antmicro-footprints:C_0402_1005Metric"
		(layer "B.Cu")
		(at 128.5 204.775 90)
		(descr "Capacitor SMD 0402")
		(tags "capacitor SMD 0402")
		(property "Reference" "C222"
			(at 0 0.699 270)
			(layer "B.SilkS")
			(hide yes)
			(effects
				(font
					(size 0.7 0.7)
					(thickness 0.15)
				)
				(justify left bottom mirror)
			)
		)
		(property "Value" "C_100n_0402"
			(at -1.022927 -2.155213 270)
			(layer "B.Fab")
			(effects
				(font
					(size 0.7 0.7)
					(thickness 0.15)
				)
				(justify left bottom mirror)
			)
		)
		(property "Datasheet" "https://www.murata.com/products/productdetail?partno=GRM155R61H104KE14%23"
			(at 0 0 90)
			(layer "F.Fab")
			(hide yes)
			(effects
				(font
					(size 1.27 1.27)
					(thickness 0.15)
				)
			)
		)
		(property "Author" "Antmicro"
			(at 333.275 76.275 0)
			(layer "B.Fab")
			(hide yes)
			(effects
				(font
					(size 1 1)
					(thickness 0.15)
				)
				(justify mirror)
			)
		)
		(property "Dielectric" "X5R"
			(at 333.275 76.275 0)
			(layer "B.Fab")
			(hide yes)
			(effects
				(font
					(size 1 1)
					(thickness 0.15)
				)
				(justify mirror)
			)
		)
		(property "License" "Apache-2.0"
			(at 333.275 76.275 0)
			(layer "B.Fab")
			(hide yes)
			(effects
				(font
					(size 1 1)
					(thickness 0.15)
				)
				(justify mirror)
			)
		)
		(property "MPN" "GRM155R61H104KE14D"
			(at 333.275 76.275 0)
			(layer "B.Fab")
			(hide yes)
			(effects
				(font
					(size 1 1)
					(thickness 0.15)
				)
				(justify mirror)
			)
		)
		(property "Manufacturer" "Murata"
			(at 333.275 76.275 0)
			(layer "B.Fab")
			(hide yes)
			(effects
				(font
					(size 1 1)
					(thickness 0.15)
				)
				(justify mirror)
			)
		)
		(property "Val" "100n"
			(at 333.275 76.275 0)
			(layer "B.Fab")
			(hide yes)
			(effects
				(font
					(size 1 1)
					(thickness 0.15)
				)
				(justify mirror)
			)
		)
		(property "Voltage" "50V"
			(at 333.275 76.275 0)
			(layer "B.Fab")
			(hide yes)
			(effects
				(font
					(size 1 1)
					(thickness 0.15)
				)
				(justify mirror)
			)
		)
		(sheetname "/FPGA MGT Interface/")
		(sheetfile "fpga-mgt.kicad_sch")
		(attr smd)
		(fp_rect
			(start -0.9659 0.481258)
			(end 0.9649 -0.458742)
			(stroke
				(width 0.05)
				(type solid)
			)
			(fill no)
			(layer "B.CrtYd")
		)
		(fp_line
			(start 0.499 -0.248)
			(end -0.499 -0.248)
			(stroke
				(width 0.15)
				(type solid)
			)
			(layer "B.Fab")
		)
		(fp_line
			(start -0.499 -0.248)
			(end -0.499 0.25)
			(stroke
				(width 0.15)
				(type solid)
			)
			(layer "B.Fab")
		)
		(fp_line
			(start 0.499 0.25)
			(end 0.499 -0.248)
			(stroke
				(width 0.15)
				(type solid)
			)
			(layer "B.Fab")
		)
		(fp_line
			(start -0.499 0.25)
			(end 0.499 0.25)
			(stroke
				(width 0.15)
				(type solid)
			)
			(layer "B.Fab")
		)
		(pad "1" smd roundrect
			(at -0.484 0 90)
			(size 0.59 0.64)
			(layers "B.Cu" "B.Mask" "B.Paste")
			(roundrect_rratio 0.25)
			(net 12 "/FPGA MGT Interface/PCIE.CLK_P")
			(pintype "passive")
		)
		(pad "2" smd roundrect
			(at 0.484 0 90)
			(size 0.59 0.64)
			(layers "B.Cu" "B.Mask" "B.Paste")
			(roundrect_rratio 0.25)
			(net 13 "/FPGA MGT Interface/GTR_REFCLK0_P")
			(pintype "passive")
		)
	)
	(footprint "antmicro-footprints:TP_SMD_1mm"
		(layer "B.Cu")
		(at 193.6 174.1 180)
		(property "Reference" "TP32"
			(at 0 0.731898 0)
			(layer "B.SilkS")
			(hide yes)
			(effects
				(font
					(size 0.7 0.7)
					(thickness 0.15)
				)
				(justify left bottom mirror)
			)
		)
		(property "Value" "TP_1mm_SMD"
			(at 0 -1.4 0)
			(layer "B.Fab")
			(effects
				(font
					(size 0.7 0.7)
					(thickness 0.15)
				)
				(justify left bottom mirror)
			)
		)
		(property "MPN" ""
			(at 0 0 0)
			(unlocked yes)
			(layer "B.Fab")
			(hide yes)
			(effects
				(font
					(size 1 1)
					(thickness 0.15)
				)
				(justify mirror)
			)
		)
		(property "Manufacturer" ""
			(at 0 0 0)
			(unlocked yes)
			(layer "B.Fab")
			(hide yes)
			(effects
				(font
					(size 1 1)
					(thickness 0.15)
				)
				(justify mirror)
			)
		)
		(property "Author" "Antmicro"
			(at 0 0 0)
			(unlocked yes)
			(layer "B.Fab")
			(hide yes)
			(effects
				(font
					(size 1 1)
					(thickness 0.15)
				)
				(justify mirror)
			)
		)
		(property "License" "Apache-2.0"
			(at 0 0 0)
			(unlocked yes)
			(layer "B.Fab")
			(hide yes)
			(effects
				(font
					(size 1 1)
					(thickness 0.15)
				)
				(justify mirror)
			)
		)
		(sheetname "/Supply/")
		(sheetfile "supply.kicad_sch")
		(attr exclude_from_pos_files)
		(fp_circle
			(center 0 0)
			(end 0.6 0)
			(stroke
				(width 0.05)
				(type default)
			)
			(fill no)
			(layer "B.CrtYd")
		)
		(fp_text user "License: Apache-2.0"
			(at -0.5 -5.2 0)
			(layer "B.Fab")
			(effects
				(font
					(size 0.7 0.7)
					(thickness 0.15)
				)
				(justify left bottom mirror)
			)
		)
		(fp_text user "${REFERENCE}"
			(at -0.5 -2.8 0)
			(layer "B.Fab")
			(effects
				(font
					(size 0.7 0.7)
					(thickness 0.15)
				)
				(justify left bottom mirror)
			)
		)
		(fp_text user "Author: Antmicro"
			(at -0.5 -4 0)
			(layer "B.Fab")
			(effects
				(font
					(size 0.7 0.7)
					(thickness 0.15)
				)
				(justify left bottom mirror)
			)
		)
		(pad "1" smd circle
			(at 0 0 180)
			(size 1 1)
			(layers "B.Cu" "B.Mask")
			(net 199 "+1V2")
			(pinfunction "1")
			(pintype "passive")
		)
	)
	(footprint "antmicro-footprints:R_0402_1005Metric"
		(layer "B.Cu")
		(at 140.302001 159.125 -90)
		(descr "Resistor SMD 0402")
		(tags "resistor SMD 0402")
		(property "Reference" "R131"
			(at -1.122484 0.772697 90)
			(layer "B.SilkS")
			(hide yes)
			(effects
				(font
					(size 0.7 0.7)
					(thickness 0.15)
				)
				(justify left bottom mirror)
			)
		)
		(property "Value" "R_0R_0402"
			(at -1.011843 -1.772047 90)
			(layer "B.Fab")
			(effects
				(font
					(size 0.7 0.7)
					(thickness 0.15)
				)
				(justify left bottom mirror)
			)
		)
		(property "Datasheet" "https://industrial.panasonic.com/cdbs/www-data/pdf/RDA0000/AOA0000C301.pdf"
			(at 0 0 270)
			(layer "F.Fab")
			(hide yes)
			(effects
				(font
					(size 1.27 1.27)
					(thickness 0.15)
				)
			)
		)
		(property "Author" "Antmicro"
			(at -18.822999 299.427001 0)
			(layer "B.Fab")
			(hide yes)
			(effects
				(font
					(size 1 1)
					(thickness 0.15)
				)
				(justify mirror)
			)
		)
		(property "Current" "1A"
			(at -18.822999 299.427001 0)
			(layer "B.Fab")
			(hide yes)
			(effects
				(font
					(size 1 1)
					(thickness 0.15)
				)
				(justify mirror)
			)
		)
		(property "License" "Apache-2.0"
			(at -18.822999 299.427001 0)
			(layer "B.Fab")
			(hide yes)
			(effects
				(font
					(size 1 1)
					(thickness 0.15)
				)
				(justify mirror)
			)
		)
		(property "MPN" "ERJ2GE0R00X"
			(at -18.822999 299.427001 0)
			(layer "B.Fab")
			(hide yes)
			(effects
				(font
					(size 1 1)
					(thickness 0.15)
				)
				(justify mirror)
			)
		)
		(property "Manufacturer" "Panasonic"
			(at -18.822999 299.427001 0)
			(layer "B.Fab")
			(hide yes)
			(effects
				(font
					(size 1 1)
					(thickness 0.15)
				)
				(justify mirror)
			)
		)
		(property "Tolerance" ""
			(at -18.822999 299.427001 0)
			(layer "B.Fab")
			(hide yes)
			(effects
				(font
					(size 1 1)
					(thickness 0.15)
				)
				(justify mirror)
			)
		)
		(property "Val" "0R"
			(at -18.822999 299.427001 0)
			(layer "B.Fab")
			(hide yes)
			(effects
				(font
					(size 1 1)
					(thickness 0.15)
				)
				(justify mirror)
			)
		)
		(sheetname "/FPGA banks HP/")
		(sheetfile "fpga-banks-32-34.kicad_sch")
		(attr exclude_from_bom)
		(fp_rect
			(start -0.93 0.47)
			(end 0.93 -0.47)
			(stroke
				(width 0.05)
				(type solid)
			)
			(fill no)
			(layer "B.CrtYd")
		)
		(fp_rect
			(start -0.5 0.25)
			(end 0.5 -0.25)
			(stroke
				(width 0.15)
				(type solid)
			)
			(fill no)
			(layer "B.Fab")
		)
		(pad "1" smd roundrect
			(at -0.485 0 270)
			(size 0.59 0.64)
			(layers "B.Cu" "B.Mask" "B.Paste")
			(roundrect_rratio 0.25)
			(net 36 "DAC_VREF")
			(pintype "passive")
		)
		(pad "2" smd roundrect
			(at 0.485 0 270)
			(size 0.59 0.64)
			(layers "B.Cu" "B.Mask" "B.Paste")
			(roundrect_rratio 0.25)
			(net 10 "/FPGA banks HP/VREF")
			(pintype "passive")
		)
	)
	(footprint "antmicro-footprints:C_0402_1005Metric"
		(layer "B.Cu")
		(at 88.806897 137.413487 90)
		(descr "Capacitor SMD 0402")
		(tags "capacitor SMD 0402")
		(property "Reference" "C137"
			(at 0 0.699 270)
			(layer "B.SilkS")
			(hide yes)
			(effects
				(font
					(size 0.7 0.7)
					(thickness 0.15)
				)
				(justify left bottom mirror)
			)
		)
		(property "Value" "C_100n_0402"
			(at -1.022927 -2.155213 270)
			(layer "B.Fab")
			(effects
				(font
					(size 0.7 0.7)
					(thickness 0.15)
				)
				(justify left bottom mirror)
			)
		)
		(property "Datasheet" "https://www.murata.com/products/productdetail?partno=GRM155R61H104KE14%23"
			(at 0 0 90)
			(layer "F.Fab")
			(hide yes)
			(effects
				(font
					(size 1.27 1.27)
					(thickness 0.15)
				)
			)
		)
		(property "Author" "Antmicro"
			(at 226.220384 48.60659 0)
			(layer "B.Fab")
			(hide yes)
			(effects
				(font
					(size 1 1)
					(thickness 0.15)
				)
				(justify mirror)
			)
		)
		(property "Dielectric" "X5R"
			(at 226.220384 48.60659 0)
			(layer "B.Fab")
			(hide yes)
			(effects
				(font
					(size 1 1)
					(thickness 0.15)
				)
				(justify mirror)
			)
		)
		(property "License" "Apache-2.0"
			(at 226.220384 48.60659 0)
			(layer "B.Fab")
			(hide yes)
			(effects
				(font
					(size 1 1)
					(thickness 0.15)
				)
				(justify mirror)
			)
		)
		(property "MPN" "GRM155R61H104KE14D"
			(at 226.220384 48.60659 0)
			(layer "B.Fab")
			(hide yes)
			(effects
				(font
					(size 1 1)
					(thickness 0.15)
				)
				(justify mirror)
			)
		)
		(property "Manufacturer" "Murata"
			(at 226.220384 48.60659 0)
			(layer "B.Fab")
			(hide yes)
			(effects
				(font
					(size 1 1)
					(thickness 0.15)
				)
				(justify mirror)
			)
		)
		(property "Val" "100n"
			(at 226.220384 48.60659 0)
			(layer "B.Fab")
			(hide yes)
			(effects
				(font
					(size 1 1)
					(thickness 0.15)
				)
				(justify mirror)
			)
		)
		(property "Voltage" "50V"
			(at 226.220384 48.60659 0)
			(layer "B.Fab")
			(hide yes)
			(effects
				(font
					(size 1 1)
					(thickness 0.15)
				)
				(justify mirror)
			)
		)
		(sheetname "/Ethernet/")
		(sheetfile "ethernet.kicad_sch")
		(attr smd)
		(fp_rect
			(start -0.9659 0.481258)
			(end 0.9649 -0.458742)
			(stroke
				(width 0.05)
				(type solid)
			)
			(fill no)
			(layer "B.CrtYd")
		)
		(fp_line
			(start 0.499 -0.248)
			(end -0.499 -0.248)
			(stroke
				(width 0.15)
				(type solid)
			)
			(layer "B.Fab")
		)
		(fp_line
			(start -0.499 -0.248)
			(end -0.499 0.25)
			(stroke
				(width 0.15)
				(type solid)
			)
			(layer "B.Fab")
		)
		(fp_line
			(start 0.499 0.25)
			(end 0.499 -0.248)
			(stroke
				(width 0.15)
				(type solid)
			)
			(layer "B.Fab")
		)
		(fp_line
			(start -0.499 0.25)
			(end 0.499 0.25)
			(stroke
				(width 0.15)
				(type solid)
			)
			(layer "B.Fab")
		)
		(pad "1" smd roundrect
			(at -0.484 0 90)
			(size 0.59 0.64)
			(layers "B.Cu" "B.Mask" "B.Paste")
			(roundrect_rratio 0.25)
			(net 1 "GND")
			(pintype "passive")
		)
		(pad "2" smd roundrect
			(at 0.484 0 90)
			(size 0.59 0.64)
			(layers "B.Cu" "B.Mask" "B.Paste")
			(roundrect_rratio 0.25)
			(net 215 "Net-(C137-Pad2)")
			(pintype "passive")
		)
	)
	(footprint "antmicro-footprints:C_0402_1005Metric"
		(layer "B.Cu")
		(at 137.525501 204.850501 -90)
		(descr "Capacitor SMD 0402")
		(tags "capacitor SMD 0402")
		(property "Reference" "C233"
			(at 0 0.699 90)
			(layer "B.SilkS")
			(hide yes)
			(effects
				(font
					(size 0.7 0.7)
					(thickness 0.15)
				)
				(justify left bottom mirror)
			)
		)
		(property "Value" "C_100n_0402"
			(at -1.022927 -2.155213 90)
			(layer "B.Fab")
			(effects
				(font
					(size 0.7 0.7)
					(thickness 0.15)
				)
				(justify left bottom mirror)
			)
		)
		(property "Datasheet" "https://www.murata.com/products/productdetail?partno=GRM155R61H104KE14%23"
			(at 0 0 270)
			(layer "F.Fab")
			(hide yes)
			(effects
				(font
					(size 1.27 1.27)
					(thickness 0.15)
				)
			)
		)
		(property "Author" "Antmicro"
			(at -67.325 342.376002 0)
			(layer "B.Fab")
			(hide yes)
			(effects
				(font
					(size 1 1)
					(thickness 0.15)
				)
				(justify mirror)
			)
		)
		(property "Dielectric" "X5R"
			(at -67.325 342.376002 0)
			(layer "B.Fab")
			(hide yes)
			(effects
				(font
					(size 1 1)
					(thickness 0.15)
				)
				(justify mirror)
			)
		)
		(property "License" "Apache-2.0"
			(at -67.325 342.376002 0)
			(layer "B.Fab")
			(hide yes)
			(effects
				(font
					(size 1 1)
					(thickness 0.15)
				)
				(justify mirror)
			)
		)
		(property "MPN" "GRM155R61H104KE14D"
			(at -67.325 342.376002 0)
			(layer "B.Fab")
			(hide yes)
			(effects
				(font
					(size 1 1)
					(thickness 0.15)
				)
				(justify mirror)
			)
		)
		(property "Manufacturer" "Murata"
			(at -67.325 342.376002 0)
			(layer "B.Fab")
			(hide yes)
			(effects
				(font
					(size 1 1)
					(thickness 0.15)
				)
				(justify mirror)
			)
		)
		(property "Val" "100n"
			(at -67.325 342.376002 0)
			(layer "B.Fab")
			(hide yes)
			(effects
				(font
					(size 1 1)
					(thickness 0.15)
				)
				(justify mirror)
			)
		)
		(property "Voltage" "50V"
			(at -67.325 342.376002 0)
			(layer "B.Fab")
			(hide yes)
			(effects
				(font
					(size 1 1)
					(thickness 0.15)
				)
				(justify mirror)
			)
		)
		(sheetname "/FPGA MGT Interface/")
		(sheetfile "fpga-mgt.kicad_sch")
		(attr smd)
		(fp_rect
			(start -0.9659 0.481258)
			(end 0.9649 -0.458742)
			(stroke
				(width 0.05)
				(type solid)
			)
			(fill no)
			(layer "B.CrtYd")
		)
		(fp_line
			(start -0.499 0.25)
			(end 0.499 0.25)
			(stroke
				(width 0.15)
				(type solid)
			)
			(layer "B.Fab")
		)
		(fp_line
			(start 0.499 0.25)
			(end 0.499 -0.248)
			(stroke
				(width 0.15)
				(type solid)
			)
			(layer "B.Fab")
		)
		(fp_line
			(start -0.499 -0.248)
			(end -0.499 0.25)
			(stroke
				(width 0.15)
				(type solid)
			)
			(layer "B.Fab")
		)
		(fp_line
			(start 0.499 -0.248)
			(end -0.499 -0.248)
			(stroke
				(width 0.15)
				(type solid)
			)
			(layer "B.Fab")
		)
		(pad "1" smd roundrect
			(at -0.484 0 270)
			(size 0.59 0.64)
			(layers "B.Cu" "B.Mask" "B.Paste")
			(roundrect_rratio 0.25)
			(net 30 "/FPGA MGT Interface/GTX_TX2_N")
			(pintype "passive")
		)
		(pad "2" smd roundrect
			(at 0.484 0 270)
			(size 0.59 0.64)
			(layers "B.Cu" "B.Mask" "B.Paste")
			(roundrect_rratio 0.25)
			(net 31 "/FPGA MGT Interface/PCIE.TXD1_N")
			(pintype "passive")
		)
	)
	(footprint "antmicro-footprints:C_0402_1005Metric"
		(layer "B.Cu")
		(at 131.525501 204.850501 90)
		(descr "Capacitor SMD 0402")
		(tags "capacitor SMD 0402")
		(property "Reference" "C229"
			(at 0 0.699 270)
			(layer "B.SilkS")
			(hide yes)
			(effects
				(font
					(size 0.7 0.7)
					(thickness 0.15)
				)
				(justify left bottom mirror)
			)
		)
		(property "Value" "C_100n_0402"
			(at -1.022927 -2.155213 270)
			(layer "B.Fab")
			(effects
				(font
					(size 0.7 0.7)
					(thickness 0.15)
				)
				(justify left bottom mirror)
			)
		)
		(property "Datasheet" "https://www.murata.com/products/productdetail?partno=GRM155R61H104KE14%23"
			(at 0 0 90)
			(layer "F.Fab")
			(hide yes)
			(effects
				(font
					(size 1.27 1.27)
					(thickness 0.15)
				)
			)
		)
		(property "Author" "Antmicro"
			(at 336.376002 73.325 0)
			(layer "B.Fab")
			(hide yes)
			(effects
				(font
					(size 1 1)
					(thickness 0.15)
				)
				(justify mirror)
			)
		)
		(property "Dielectric" "X5R"
			(at 336.376002 73.325 0)
			(layer "B.Fab")
			(hide yes)
			(effects
				(font
					(size 1 1)
					(thickness 0.15)
				)
				(justify mirror)
			)
		)
		(property "License" "Apache-2.0"
			(at 336.376002 73.325 0)
			(layer "B.Fab")
			(hide yes)
			(effects
				(font
					(size 1 1)
					(thickness 0.15)
				)
				(justify mirror)
			)
		)
		(property "MPN" "GRM155R61H104KE14D"
			(at 336.376002 73.325 0)
			(layer "B.Fab")
			(hide yes)
			(effects
				(font
					(size 1 1)
					(thickness 0.15)
				)
				(justify mirror)
			)
		)
		(property "Manufacturer" "Murata"
			(at 336.376002 73.325 0)
			(layer "B.Fab")
			(hide yes)
			(effects
				(font
					(size 1 1)
					(thickness 0.15)
				)
				(justify mirror)
			)
		)
		(property "Val" "100n"
			(at 336.376002 73.325 0)
			(layer "B.Fab")
			(hide yes)
			(effects
				(font
					(size 1 1)
					(thickness 0.15)
				)
				(justify mirror)
			)
		)
		(property "Voltage" "50V"
			(at 336.376002 73.325 0)
			(layer "B.Fab")
			(hide yes)
			(effects
				(font
					(size 1 1)
					(thickness 0.15)
				)
				(justify mirror)
			)
		)
		(sheetname "/FPGA MGT Interface/")
		(sheetfile "fpga-mgt.kicad_sch")
		(attr smd)
		(fp_rect
			(start -0.9659 0.481258)
			(end 0.9649 -0.458742)
			(stroke
				(width 0.05)
				(type solid)
			)
			(fill no)
			(layer "B.CrtYd")
		)
		(fp_line
			(start 0.499 -0.248)
			(end -0.499 -0.248)
			(stroke
				(width 0.15)
				(type solid)
			)
			(layer "B.Fab")
		)
		(fp_line
			(start -0.499 -0.248)
			(end -0.499 0.25)
			(stroke
				(width 0.15)
				(type solid)
			)
			(layer "B.Fab")
		)
		(fp_line
			(start 0.499 0.25)
			(end 0.499 -0.248)
			(stroke
				(width 0.15)
				(type solid)
			)
			(layer "B.Fab")
		)
		(fp_line
			(start -0.499 0.25)
			(end 0.499 0.25)
			(stroke
				(width 0.15)
				(type solid)
			)
			(layer "B.Fab")
		)
		(pad "1" smd roundrect
			(at -0.484 0 90)
			(size 0.59 0.64)
			(layers "B.Cu" "B.Mask" "B.Paste")
			(roundrect_rratio 0.25)
			(net 22 "/FPGA MGT Interface/PCIE.TXD0_P")
			(pintype "passive")
		)
		(pad "2" smd roundrect
			(at 0.484 0 90)
			(size 0.59 0.64)
			(layers "B.Cu" "B.Mask" "B.Paste")
			(roundrect_rratio 0.25)
			(net 23 "/FPGA MGT Interface/GTX_TX3_P")
			(pintype "passive")
		)
	)
	(footprint "antmicro-footprints:C_0402_1005Metric"
		(layer "B.Cu")
		(at 142.875501 167.301 180)
		(descr "Capacitor SMD 0402 (1005 Metric), square (rectangular) end terminal, IPC_7351 nominal, (Body size source: IPC-SM-782 page 76, https://www.pcb-3d.com/wordpress/wp-content/uploads/ipc-sm-782a_amendment_1_and_2.pdf)")
		(tags "capacitor 0402")
		(property "Reference" "C74"
			(at 0 1.17 0)
			(layer "B.SilkS")
			(hide yes)
			(effects
				(font
					(size 0.7 0.7)
					(thickness 0.15)
				)
				(justify left bottom mirror)
			)
		)
		(property "Value" "C_100n_0402"
			(at 0 -1.169 0)
			(layer "B.Fab")
			(effects
				(font
					(size 0.7 0.7)
					(thickness 0.15)
				)
				(justify left bottom mirror)
			)
		)
		(property "Datasheet" "https://www.murata.com/products/productdetail?partno=GRM155R61H104KE14%23"
			(at 0 0 180)
			(layer "F.Fab")
			(hide yes)
			(effects
				(font
					(size 1.27 1.27)
					(thickness 0.15)
				)
			)
		)
		(property "Author" "Antmicro"
			(at 285.751002 334.602 0)
			(layer "B.Fab")
			(hide yes)
			(effects
				(font
					(size 1 1)
					(thickness 0.15)
				)
				(justify mirror)
			)
		)
		(property "Dielectric" "X5R"
			(at 285.751002 334.602 0)
			(layer "B.Fab")
			(hide yes)
			(effects
				(font
					(size 1 1)
					(thickness 0.15)
				)
				(justify mirror)
			)
		)
		(property "License" "Apache-2.0"
			(at 285.751002 334.602 0)
			(layer "B.Fab")
			(hide yes)
			(effects
				(font
					(size 1 1)
					(thickness 0.15)
				)
				(justify mirror)
			)
		)
		(property "MPN" "GRM155R61H104KE14D"
			(at 285.751002 334.602 0)
			(layer "B.Fab")
			(hide yes)
			(effects
				(font
					(size 1 1)
					(thickness 0.15)
				)
				(justify mirror)
			)
		)
		(property "Manufacturer" "Murata"
			(at 285.751002 334.602 0)
			(layer "B.Fab")
			(hide yes)
			(effects
				(font
					(size 1 1)
					(thickness 0.15)
				)
				(justify mirror)
			)
		)
		(property "Val" "100n"
			(at 285.751002 334.602 0)
			(layer "B.Fab")
			(hide yes)
			(effects
				(font
					(size 1 1)
					(thickness 0.15)
				)
				(justify mirror)
			)
		)
		(property "Voltage" "50V"
			(at 285.751002 334.602 0)
			(layer "B.Fab")
			(hide yes)
			(effects
				(font
					(size 1 1)
					(thickness 0.15)
				)
				(justify mirror)
			)
		)
		(sheetname "/FPGA power/")
		(sheetfile "fpga-power.kicad_sch")
		(attr smd)
		(fp_rect
			(start -0.9656 0.4572)
			(end 0.9652 -0.4828)
			(stroke
				(width 0.05)
				(type solid)
			)
			(fill no)
			(layer "B.CrtYd")
		)
		(fp_line
			(start 0.498 0.25)
			(end 0.498 -0.248)
			(stroke
				(width 0.15)
				(type solid)
			)
			(layer "B.Fab")
		)
		(fp_line
			(start 0.498 -0.248)
			(end -0.5 -0.248)
			(stroke
				(width 0.15)
				(type solid)
			)
			(layer "B.Fab")
		)
		(fp_line
			(start -0.5 0.25)
			(end 0.498 0.25)
			(stroke
				(width 0.15)
				(type solid)
			)
			(layer "B.Fab")
		)
		(fp_line
			(start -0.5 -0.248)
			(end -0.5 0.25)
			(stroke
				(width 0.15)
				(type solid)
			)
			(layer "B.Fab")
		)
		(pad "1" smd roundrect
			(at -0.5 0 90)
			(size 0.6 0.6)
			(layers "B.Cu" "B.Mask" "B.Paste")
			(roundrect_rratio 0.25)
			(net 1 "GND")
			(pintype "passive")
		)
		(pad "2" smd roundrect
			(at 0.498 0 180)
			(size 0.6 0.6)
			(layers "B.Cu" "B.Mask" "B.Paste")
			(roundrect_rratio 0.25)
			(net 206 "+1V1")
			(pintype "passive")
		)
	)
	(footprint "antmicro-footprints:C_0402_1005Metric"
		(layer "B.Cu")
		(at 137.875001 178.3025)
		(descr "Capacitor SMD 0402 (1005 Metric), square (rectangular) end terminal, IPC_7351 nominal, (Body size source: IPC-SM-782 page 76, https://www.pcb-3d.com/wordpress/wp-content/uploads/ipc-sm-782a_amendment_1_and_2.pdf)")
		(tags "capacitor 0402")
		(property "Reference" "C67"
			(at 0 1.17 180)
			(layer "B.SilkS")
			(hide yes)
			(effects
				(font
					(size 0.7 0.7)
					(thickness 0.15)
				)
				(justify left bottom mirror)
			)
		)
		(property "Value" "C_4u7_0402"
			(at 0 -1.169 180)
			(layer "B.Fab")
			(effects
				(font
					(size 0.7 0.7)
					(thickness 0.15)
				)
				(justify left bottom mirror)
			)
		)
		(property "Datasheet" "https://www.murata.com/products/productdetail?partno=GRM155R61A475MEAA%23"
			(at 0 0 0)
			(layer "F.Fab")
			(hide yes)
			(effects
				(font
					(size 1.27 1.27)
					(thickness 0.15)
				)
			)
		)
		(property "Author" "Antmicro"
			(at 0 0 0)
			(layer "B.Fab")
			(hide yes)
			(effects
				(font
					(size 1 1)
					(thickness 0.15)
				)
				(justify mirror)
			)
		)
		(property "Dielectric" ""
			(at 0 0 0)
			(layer "B.Fab")
			(hide yes)
			(effects
				(font
					(size 1 1)
					(thickness 0.15)
				)
				(justify mirror)
			)
		)
		(property "License" "Apache-2.0"
			(at 0 0 0)
			(layer "B.Fab")
			(hide yes)
			(effects
				(font
					(size 1 1)
					(thickness 0.15)
				)
				(justify mirror)
			)
		)
		(property "MPN" "GRM155R61A475MEAAD"
			(at 0 0 0)
			(layer "B.Fab")
			(hide yes)
			(effects
				(font
					(size 1 1)
					(thickness 0.15)
				)
				(justify mirror)
			)
		)
		(property "Manufacturer" "Murata"
			(at 0 0 0)
			(layer "B.Fab")
			(hide yes)
			(effects
				(font
					(size 1 1)
					(thickness 0.15)
				)
				(justify mirror)
			)
		)
		(property "Val" "4u7"
			(at 0 0 0)
			(layer "B.Fab")
			(hide yes)
			(effects
				(font
					(size 1 1)
					(thickness 0.15)
				)
				(justify mirror)
			)
		)
		(property "Voltage" ""
			(at 0 0 0)
			(layer "B.Fab")
			(hide yes)
			(effects
				(font
					(size 1 1)
					(thickness 0.15)
				)
				(justify mirror)
			)
		)
		(sheetname "/FPGA power/")
		(sheetfile "fpga-power.kicad_sch")
		(attr smd)
		(fp_rect
			(start -0.9656 0.4572)
			(end 0.9652 -0.4828)
			(stroke
				(width 0.05)
				(type solid)
			)
			(fill no)
			(layer "B.CrtYd")
		)
		(fp_line
			(start -0.5 -0.248)
			(end -0.5 0.25)
			(stroke
				(width 0.15)
				(type solid)
			)
			(layer "B.Fab")
		)
		(fp_line
			(start -0.5 0.25)
			(end 0.498 0.25)
			(stroke
				(width 0.15)
				(type solid)
			)
			(layer "B.Fab")
		)
		(fp_line
			(start 0.498 -0.248)
			(end -0.5 -0.248)
			(stroke
				(width 0.15)
				(type solid)
			)
			(layer "B.Fab")
		)
		(fp_line
			(start 0.498 0.25)
			(end 0.498 -0.248)
			(stroke
				(width 0.15)
				(type solid)
			)
			(layer "B.Fab")
		)
		(pad "1" smd roundrect
			(at -0.5 0 270)
			(size 0.6 0.6)
			(layers "B.Cu" "B.Mask" "B.Paste")
			(roundrect_rratio 0.25)
			(net 227 "+1V0")
			(pintype "passive")
		)
		(pad "2" smd roundrect
			(at 0.498 0)
			(size 0.6 0.6)
			(layers "B.Cu" "B.Mask" "B.Paste")
			(roundrect_rratio 0.25)
			(net 1 "GND")
			(pintype "passive")
		)
	)
	(footprint "antmicro-footprints:C_0402_1005Metric"
		(layer "B.Cu")
		(at 84.289 129.7)
		(descr "Capacitor SMD 0402")
		(tags "capacitor SMD 0402")
		(property "Reference" "C234"
			(at 0 0.699 180)
			(layer "B.SilkS")
			(hide yes)
			(effects
				(font
					(size 0.7 0.7)
					(thickness 0.15)
				)
				(justify left bottom mirror)
			)
		)
		(property "Value" "C_100n_0402"
			(at -1.022927 -2.155213 180)
			(layer "B.Fab")
			(effects
				(font
					(size 0.7 0.7)
					(thickness 0.15)
				)
				(justify left bottom mirror)
			)
		)
		(property "Datasheet" "https://www.murata.com/products/productdetail?partno=GRM155R61H104KE14%23"
			(at 0 0 0)
			(layer "F.Fab")
			(hide yes)
			(effects
				(font
					(size 1.27 1.27)
					(thickness 0.15)
				)
			)
		)
		(property "Author" "Antmicro"
			(at 0 0 0)
			(layer "B.Fab")
			(hide yes)
			(effects
				(font
					(size 1 1)
					(thickness 0.15)
				)
				(justify mirror)
			)
		)
		(property "Dielectric" "X5R"
			(at 0 0 0)
			(layer "B.Fab")
			(hide yes)
			(effects
				(font
					(size 1 1)
					(thickness 0.15)
				)
				(justify mirror)
			)
		)
		(property "License" "Apache-2.0"
			(at 0 0 0)
			(layer "B.Fab")
			(hide yes)
			(effects
				(font
					(size 1 1)
					(thickness 0.15)
				)
				(justify mirror)
			)
		)
		(property "MPN" "GRM155R61H104KE14D"
			(at 0 0 0)
			(layer "B.Fab")
			(hide yes)
			(effects
				(font
					(size 1 1)
					(thickness 0.15)
				)
				(justify mirror)
			)
		)
		(property "Manufacturer" "Murata"
			(at 0 0 0)
			(layer "B.Fab")
			(hide yes)
			(effects
				(font
					(size 1 1)
					(thickness 0.15)
				)
				(justify mirror)
			)
		)
		(property "Val" "100n"
			(at 0 0 0)
			(layer "B.Fab")
			(hide yes)
			(effects
				(font
					(size 1 1)
					(thickness 0.15)
				)
				(justify mirror)
			)
		)
		(property "Voltage" "50V"
			(at 0 0 0)
			(layer "B.Fab")
			(hide yes)
			(effects
				(font
					(size 1 1)
					(thickness 0.15)
				)
				(justify mirror)
			)
		)
		(sheetname "/Ethernet/")
		(sheetfile "ethernet.kicad_sch")
		(attr smd)
		(fp_rect
			(start -0.9659 0.481258)
			(end 0.9649 -0.458742)
			(stroke
				(width 0.05)
				(type solid)
			)
			(fill no)
			(layer "B.CrtYd")
		)
		(fp_line
			(start -0.499 -0.248)
			(end -0.499 0.25)
			(stroke
				(width 0.15)
				(type solid)
			)
			(layer "B.Fab")
		)
		(fp_line
			(start -0.499 0.25)
			(end 0.499 0.25)
			(stroke
				(width 0.15)
				(type solid)
			)
			(layer "B.Fab")
		)
		(fp_line
			(start 0.499 -0.248)
			(end -0.499 -0.248)
			(stroke
				(width 0.15)
				(type solid)
			)
			(layer "B.Fab")
		)
		(fp_line
			(start 0.499 0.25)
			(end 0.499 -0.248)
			(stroke
				(width 0.15)
				(type solid)
			)
			(layer "B.Fab")
		)
		(pad "1" smd roundrect
			(at -0.484 0)
			(size 0.59 0.64)
			(layers "B.Cu" "B.Mask" "B.Paste")
			(roundrect_rratio 0.25)
			(net 32 "Net-(C234-Pad1)")
			(pintype "passive")
		)
		(pad "2" smd roundrect
			(at 0.484 0)
			(size 0.59 0.64)
			(layers "B.Cu" "B.Mask" "B.Paste")
			(roundrect_rratio 0.25)
			(net 1 "GND")
			(pintype "passive")
		)
	)
	(footprint "antmicro-footprints:TP_SMD_1mm"
		(layer "B.Cu")
		(at 173.9 189.5 180)
		(property "Reference" "TP69"
			(at 0.5 0.05 0)
			(layer "B.SilkS")
			(effects
				(font
					(size 0.7 0.7)
					(thickness 0.15)
				)
				(justify left bottom mirror)
			)
		)
		(property "Value" "TP_1mm_SMD"
			(at 0 -1.4 0)
			(layer "B.Fab")
			(effects
				(font
					(size 0.7 0.7)
					(thickness 0.15)
				)
				(justify left bottom mirror)
			)
		)
		(property "MPN" ""
			(at 0 0 0)
			(unlocked yes)
			(layer "B.Fab")
			(hide yes)
			(effects
				(font
					(size 1 1)
					(thickness 0.15)
				)
				(justify mirror)
			)
		)
		(property "Manufacturer" ""
			(at 0 0 0)
			(unlocked yes)
			(layer "B.Fab")
			(hide yes)
			(effects
				(font
					(size 1 1)
					(thickness 0.15)
				)
				(justify mirror)
			)
		)
		(property "Author" "Antmicro"
			(at 0 0 0)
			(unlocked yes)
			(layer "B.Fab")
			(hide yes)
			(effects
				(font
					(size 1 1)
					(thickness 0.15)
				)
				(justify mirror)
			)
		)
		(property "License" "Apache-2.0"
			(at 0 0 0)
			(unlocked yes)
			(layer "B.Fab")
			(hide yes)
			(effects
				(font
					(size 1 1)
					(thickness 0.15)
				)
				(justify mirror)
			)
		)
		(sheetname "/I^{2}C/")
		(sheetfile "i2c.kicad_sch")
		(attr exclude_from_pos_files)
		(fp_circle
			(center 0 0)
			(end 0.6 0)
			(stroke
				(width 0.05)
				(type default)
			)
			(fill no)
			(layer "B.CrtYd")
		)
		(fp_text user "Author: Antmicro"
			(at -0.5 -4 0)
			(layer "B.Fab")
			(effects
				(font
					(size 0.7 0.7)
					(thickness 0.15)
				)
				(justify left bottom mirror)
			)
		)
		(fp_text user "${REFERENCE}"
			(at -0.5 -2.8 0)
			(layer "B.Fab")
			(effects
				(font
					(size 0.7 0.7)
					(thickness 0.15)
				)
				(justify left bottom mirror)
			)
		)
		(fp_text user "License: Apache-2.0"
			(at -0.5 -5.2 0)
			(layer "B.Fab")
			(effects
				(font
					(size 0.7 0.7)
					(thickness 0.15)
				)
				(justify left bottom mirror)
			)
		)
		(pad "1" smd circle
			(at 0 0 180)
			(size 1 1)
			(layers "B.Cu" "B.Mask")
			(net 761 "Net-(U34-SDA)")
			(pinfunction "1")
			(pintype "passive")
		)
	)
	(footprint "antmicro-footprints:C_0402_1005Metric"
		(layer "B.Cu")
		(at 138.870501 172.296)
		(descr "Capacitor SMD 0402 (1005 Metric), square (rectangular) end terminal, IPC_7351 nominal, (Body size source: IPC-SM-782 page 76, https://www.pcb-3d.com/wordpress/wp-content/uploads/ipc-sm-782a_amendment_1_and_2.pdf)")
		(tags "capacitor 0402")
		(property "Reference" "C61"
			(at 0 1.17 180)
			(layer "B.SilkS")
			(hide yes)
			(effects
				(font
					(size 0.7 0.7)
					(thickness 0.15)
				)
				(justify left bottom mirror)
			)
		)
		(property "Value" "C_100n_0402"
			(at 0 -1.169 180)
			(layer "B.Fab")
			(effects
				(font
					(size 0.7 0.7)
					(thickness 0.15)
				)
				(justify left bottom mirror)
			)
		)
		(property "Datasheet" "https://www.murata.com/products/productdetail?partno=GRM155R61H104KE14%23"
			(at 0 0 0)
			(layer "F.Fab")
			(hide yes)
			(effects
				(font
					(size 1.27 1.27)
					(thickness 0.15)
				)
			)
		)
		(property "Author" "Antmicro"
			(at 0 0 0)
			(layer "B.Fab")
			(hide yes)
			(effects
				(font
					(size 1 1)
					(thickness 0.15)
				)
				(justify mirror)
			)
		)
		(property "Dielectric" "X5R"
			(at 0 0 0)
			(layer "B.Fab")
			(hide yes)
			(effects
				(font
					(size 1 1)
					(thickness 0.15)
				)
				(justify mirror)
			)
		)
		(property "License" "Apache-2.0"
			(at 0 0 0)
			(layer "B.Fab")
			(hide yes)
			(effects
				(font
					(size 1 1)
					(thickness 0.15)
				)
				(justify mirror)
			)
		)
		(property "MPN" "GRM155R61H104KE14D"
			(at 0 0 0)
			(layer "B.Fab")
			(hide yes)
			(effects
				(font
					(size 1 1)
					(thickness 0.15)
				)
				(justify mirror)
			)
		)
		(property "Manufacturer" "Murata"
			(at 0 0 0)
			(layer "B.Fab")
			(hide yes)
			(effects
				(font
					(size 1 1)
					(thickness 0.15)
				)
				(justify mirror)
			)
		)
		(property "Val" "100n"
			(at 0 0 0)
			(layer "B.Fab")
			(hide yes)
			(effects
				(font
					(size 1 1)
					(thickness 0.15)
				)
				(justify mirror)
			)
		)
		(property "Voltage" "50V"
			(at 0 0 0)
			(layer "B.Fab")
			(hide yes)
			(effects
				(font
					(size 1 1)
					(thickness 0.15)
				)
				(justify mirror)
			)
		)
		(sheetname "/FPGA power/")
		(sheetfile "fpga-power.kicad_sch")
		(attr smd)
		(fp_rect
			(start -0.9656 0.4572)
			(end 0.9652 -0.4828)
			(stroke
				(width 0.05)
				(type solid)
			)
			(fill no)
			(layer "B.CrtYd")
		)
		(fp_line
			(start -0.5 -0.248)
			(end -0.5 0.25)
			(stroke
				(width 0.15)
				(type solid)
			)
			(layer "B.Fab")
		)
		(fp_line
			(start -0.5 0.25)
			(end 0.498 0.25)
			(stroke
				(width 0.15)
				(type solid)
			)
			(layer "B.Fab")
		)
		(fp_line
			(start 0.498 -0.248)
			(end -0.5 -0.248)
			(stroke
				(width 0.15)
				(type solid)
			)
			(layer "B.Fab")
		)
		(fp_line
			(start 0.498 0.25)
			(end 0.498 -0.248)
			(stroke
				(width 0.15)
				(type solid)
			)
			(layer "B.Fab")
		)
		(pad "1" smd roundrect
			(at -0.5 0 270)
			(size 0.6 0.6)
			(layers "B.Cu" "B.Mask" "B.Paste")
			(roundrect_rratio 0.25)
			(net 1 "GND")
			(pintype "passive")
		)
		(pad "2" smd roundrect
			(at 0.498 0)
			(size 0.6 0.6)
			(layers "B.Cu" "B.Mask" "B.Paste")
			(roundrect_rratio 0.25)
			(net 227 "+1V0")
			(pintype "passive")
		)
	)
	(footprint "antmicro-footprints:C_0402_1005Metric"
		(layer "B.Cu")
		(at 132.05 142.4 -90)
		(descr "Capacitor SMD 0402")
		(tags "capacitor SMD 0402")
		(property "Reference" "C10"
			(at 0 0.699 90)
			(layer "B.SilkS")
			(hide yes)
			(effects
				(font
					(size 0.7 0.7)
					(thickness 0.15)
				)
				(justify left bottom mirror)
			)
		)
		(property "Value" "C_100n_0402"
			(at -1.022927 -2.155213 90)
			(layer "B.Fab")
			(effects
				(font
					(size 0.7 0.7)
					(thickness 0.15)
				)
				(justify left bottom mirror)
			)
		)
		(property "Datasheet" "https://www.murata.com/products/productdetail?partno=GRM155R61H104KE14%23"
			(at 0 0 270)
			(layer "F.Fab")
			(hide yes)
			(effects
				(font
					(size 1.27 1.27)
					(thickness 0.15)
				)
			)
		)
		(property "Author" "Antmicro"
			(at -10.35 274.45 0)
			(layer "B.Fab")
			(hide yes)
			(effects
				(font
					(size 1 1)
					(thickness 0.15)
				)
				(justify mirror)
			)
		)
		(property "Dielectric" "X5R"
			(at -10.35 274.45 0)
			(layer "B.Fab")
			(hide yes)
			(effects
				(font
					(size 1 1)
					(thickness 0.15)
				)
				(justify mirror)
			)
		)
		(property "License" "Apache-2.0"
			(at -10.35 274.45 0)
			(layer "B.Fab")
			(hide yes)
			(effects
				(font
					(size 1 1)
					(thickness 0.15)
				)
				(justify mirror)
			)
		)
		(property "MPN" "GRM155R61H104KE14D"
			(at -10.35 274.45 0)
			(layer "B.Fab")
			(hide yes)
			(effects
				(font
					(size 1 1)
					(thickness 0.15)
				)
				(justify mirror)
			)
		)
		(property "Manufacturer" "Murata"
			(at -10.35 274.45 0)
			(layer "B.Fab")
			(hide yes)
			(effects
				(font
					(size 1 1)
					(thickness 0.15)
				)
				(justify mirror)
			)
		)
		(property "Val" "100n"
			(at -10.35 274.45 0)
			(layer "B.Fab")
			(hide yes)
			(effects
				(font
					(size 1 1)
					(thickness 0.15)
				)
				(justify mirror)
			)
		)
		(property "Voltage" "50V"
			(at -10.35 274.45 0)
			(layer "B.Fab")
			(hide yes)
			(effects
				(font
					(size 1 1)
					(thickness 0.15)
				)
				(justify mirror)
			)
		)
		(sheetname "/DDR5 SODIMM/")
		(sheetfile "ddr5-sodimm.kicad_sch")
		(attr smd)
		(fp_rect
			(start -0.9659 0.481258)
			(end 0.9649 -0.458742)
			(stroke
				(width 0.05)
				(type solid)
			)
			(fill no)
			(layer "B.CrtYd")
		)
		(fp_line
			(start -0.499 0.25)
			(end 0.499 0.25)
			(stroke
				(width 0.15)
				(type solid)
			)
			(layer "B.Fab")
		)
		(fp_line
			(start 0.499 0.25)
			(end 0.499 -0.248)
			(stroke
				(width 0.15)
				(type solid)
			)
			(layer "B.Fab")
		)
		(fp_line
			(start -0.499 -0.248)
			(end -0.499 0.25)
			(stroke
				(width 0.15)
				(type solid)
			)
			(layer "B.Fab")
		)
		(fp_line
			(start 0.499 -0.248)
			(end -0.499 -0.248)
			(stroke
				(width 0.15)
				(type solid)
			)
			(layer "B.Fab")
		)
		(pad "1" smd roundrect
			(at -0.484 0 270)
			(size 0.59 0.64)
			(layers "B.Cu" "B.Mask" "B.Paste")
			(roundrect_rratio 0.25)
			(net 1 "GND")
			(pintype "passive")
		)
		(pad "2" smd roundrect
			(at 0.484 0 270)
			(size 0.59 0.64)
			(layers "B.Cu" "B.Mask" "B.Paste")
			(roundrect_rratio 0.25)
			(net 206 "+1V1")
			(pintype "passive")
		)
	)
	(footprint "antmicro-footprints:C_0402_1005Metric"
		(layer "B.Cu")
		(at 144.875001 176.3025)
		(descr "Capacitor SMD 0402 (1005 Metric), square (rectangular) end terminal, IPC_7351 nominal, (Body size source: IPC-SM-782 page 76, https://www.pcb-3d.com/wordpress/wp-content/uploads/ipc-sm-782a_amendment_1_and_2.pdf)")
		(tags "capacitor 0402")
		(property "Reference" "C42"
			(at 0 1.17 180)
			(layer "B.SilkS")
			(hide yes)
			(effects
				(font
					(size 0.7 0.7)
					(thickness 0.15)
				)
				(justify left bottom mirror)
			)
		)
		(property "Value" "C_100n_0402"
			(at 0 -1.169 180)
			(layer "B.Fab")
			(effects
				(font
					(size 0.7 0.7)
					(thickness 0.15)
				)
				(justify left bottom mirror)
			)
		)
		(property "Datasheet" "https://www.murata.com/products/productdetail?partno=GRM155R61H104KE14%23"
			(at 0 0 0)
			(layer "F.Fab")
			(hide yes)
			(effects
				(font
					(size 1.27 1.27)
					(thickness 0.15)
				)
			)
		)
		(property "Author" "Antmicro"
			(at 0 0 0)
			(layer "B.Fab")
			(hide yes)
			(effects
				(font
					(size 1 1)
					(thickness 0.15)
				)
				(justify mirror)
			)
		)
		(property "Dielectric" "X5R"
			(at 0 0 0)
			(layer "B.Fab")
			(hide yes)
			(effects
				(font
					(size 1 1)
					(thickness 0.15)
				)
				(justify mirror)
			)
		)
		(property "License" "Apache-2.0"
			(at 0 0 0)
			(layer "B.Fab")
			(hide yes)
			(effects
				(font
					(size 1 1)
					(thickness 0.15)
				)
				(justify mirror)
			)
		)
		(property "MPN" "GRM155R61H104KE14D"
			(at 0 0 0)
			(layer "B.Fab")
			(hide yes)
			(effects
				(font
					(size 1 1)
					(thickness 0.15)
				)
				(justify mirror)
			)
		)
		(property "Manufacturer" "Murata"
			(at 0 0 0)
			(layer "B.Fab")
			(hide yes)
			(effects
				(font
					(size 1 1)
					(thickness 0.15)
				)
				(justify mirror)
			)
		)
		(property "Val" "100n"
			(at 0 0 0)
			(layer "B.Fab")
			(hide yes)
			(effects
				(font
					(size 1 1)
					(thickness 0.15)
				)
				(justify mirror)
			)
		)
		(property "Voltage" "50V"
			(at 0 0 0)
			(layer "B.Fab")
			(hide yes)
			(effects
				(font
					(size 1 1)
					(thickness 0.15)
				)
				(justify mirror)
			)
		)
		(sheetname "/FPGA power/")
		(sheetfile "fpga-power.kicad_sch")
		(attr smd)
		(fp_rect
			(start -0.9656 0.4572)
			(end 0.9652 -0.4828)
			(stroke
				(width 0.05)
				(type solid)
			)
			(fill no)
			(layer "B.CrtYd")
		)
		(fp_line
			(start -0.5 -0.248)
			(end -0.5 0.25)
			(stroke
				(width 0.15)
				(type solid)
			)
			(layer "B.Fab")
		)
		(fp_line
			(start -0.5 0.25)
			(end 0.498 0.25)
			(stroke
				(width 0.15)
				(type solid)
			)
			(layer "B.Fab")
		)
		(fp_line
			(start 0.498 -0.248)
			(end -0.5 -0.248)
			(stroke
				(width 0.15)
				(type solid)
			)
			(layer "B.Fab")
		)
		(fp_line
			(start 0.498 0.25)
			(end 0.498 -0.248)
			(stroke
				(width 0.15)
				(type solid)
			)
			(layer "B.Fab")
		)
		(pad "1" smd roundrect
			(at -0.5 0 270)
			(size 0.6 0.6)
			(layers "B.Cu" "B.Mask" "B.Paste")
			(roundrect_rratio 0.25)
			(net 1 "GND")
			(pintype "passive")
		)
		(pad "2" smd roundrect
			(at 0.498 0)
			(size 0.6 0.6)
			(layers "B.Cu" "B.Mask" "B.Paste")
			(roundrect_rratio 0.25)
			(net 227 "+1V0")
			(pintype "passive")
		)
	)
	(footprint "antmicro-footprints:TP_SMD_1mm"
		(layer "B.Cu")
		(at 190.5 161.7 180)
		(property "Reference" "TP61"
			(at -3.2 -0.25 0)
			(layer "B.SilkS")
			(effects
				(font
					(size 0.7 0.7)
					(thickness 0.15)
				)
				(justify left bottom mirror)
			)
		)
		(property "Value" "TP_1mm_SMD"
			(at 0 -1.4 0)
			(layer "B.Fab")
			(effects
				(font
					(size 0.7 0.7)
					(thickness 0.15)
				)
				(justify left bottom mirror)
			)
		)
		(property "MPN" ""
			(at 0 0 0)
			(unlocked yes)
			(layer "B.Fab")
			(hide yes)
			(effects
				(font
					(size 1 1)
					(thickness 0.15)
				)
				(justify mirror)
			)
		)
		(property "Manufacturer" ""
			(at 0 0 0)
			(unlocked yes)
			(layer "B.Fab")
			(hide yes)
			(effects
				(font
					(size 1 1)
					(thickness 0.15)
				)
				(justify mirror)
			)
		)
		(property "Author" "Antmicro"
			(at 0 0 0)
			(unlocked yes)
			(layer "B.Fab")
			(hide yes)
			(effects
				(font
					(size 1 1)
					(thickness 0.15)
				)
				(justify mirror)
			)
		)
		(property "License" "Apache-2.0"
			(at 0 0 0)
			(unlocked yes)
			(layer "B.Fab")
			(hide yes)
			(effects
				(font
					(size 1 1)
					(thickness 0.15)
				)
				(justify mirror)
			)
		)
		(sheetname "/Supply/")
		(sheetfile "supply.kicad_sch")
		(attr exclude_from_pos_files)
		(fp_circle
			(center 0 0)
			(end 0.6 0)
			(stroke
				(width 0.05)
				(type default)
			)
			(fill no)
			(layer "B.CrtYd")
		)
		(fp_text user "${REFERENCE}"
			(at -0.5 -2.8 0)
			(layer "B.Fab")
			(effects
				(font
					(size 0.7 0.7)
					(thickness 0.15)
				)
				(justify left bottom mirror)
			)
		)
		(fp_text user "License: Apache-2.0"
			(at -0.5 -5.2 0)
			(layer "B.Fab")
			(effects
				(font
					(size 0.7 0.7)
					(thickness 0.15)
				)
				(justify left bottom mirror)
			)
		)
		(fp_text user "Author: Antmicro"
			(at -0.5 -4 0)
			(layer "B.Fab")
			(effects
				(font
					(size 0.7 0.7)
					(thickness 0.15)
				)
				(justify left bottom mirror)
			)
		)
		(pad "1" smd circle
			(at 0 0 180)
			(size 1 1)
			(layers "B.Cu" "B.Mask")
			(net 60 "/Supply/5V_local")
			(pinfunction "1")
			(pintype "passive")
		)
	)
	(footprint "antmicro-footprints:R_0402_1005Metric"
		(layer "B.Cu")
		(at 202.925 182.4 90)
		(descr "Resistor SMD 0402")
		(tags "resistor SMD 0402")
		(property "Reference" "R163"
			(at 3.9 0.325 270)
			(layer "B.SilkS")
			(effects
				(font
					(size 0.7 0.7)
					(thickness 0.15)
				)
				(justify left bottom mirror)
			)
		)
		(property "Value" "R_0R_0402"
			(at -1.011843 -1.772047 270)
			(layer "B.Fab")
			(effects
				(font
					(size 0.7 0.7)
					(thickness 0.15)
				)
				(justify left bottom mirror)
			)
		)
		(property "Datasheet" "https://industrial.panasonic.com/cdbs/www-data/pdf/RDA0000/AOA0000C301.pdf"
			(at 0 0 90)
			(layer "F.Fab")
			(hide yes)
			(effects
				(font
					(size 1.27 1.27)
					(thickness 0.15)
				)
			)
		)
		(property "Author" "Antmicro"
			(at 385.325 -20.525 0)
			(layer "B.Fab")
			(hide yes)
			(effects
				(font
					(size 1 1)
					(thickness 0.15)
				)
				(justify mirror)
			)
		)
		(property "Current" "1A"
			(at 385.325 -20.525 0)
			(layer "B.Fab")
			(hide yes)
			(effects
				(font
					(size 1 1)
					(thickness 0.15)
				)
				(justify mirror)
			)
		)
		(property "License" "Apache-2.0"
			(at 385.325 -20.525 0)
			(layer "B.Fab")
			(hide yes)
			(effects
				(font
					(size 1 1)
					(thickness 0.15)
				)
				(justify mirror)
			)
		)
		(property "MPN" "ERJ2GE0R00X"
			(at 385.325 -20.525 0)
			(layer "B.Fab")
			(hide yes)
			(effects
				(font
					(size 1 1)
					(thickness 0.15)
				)
				(justify mirror)
			)
		)
		(property "Manufacturer" "Panasonic"
			(at 385.325 -20.525 0)
			(layer "B.Fab")
			(hide yes)
			(effects
				(font
					(size 1 1)
					(thickness 0.15)
				)
				(justify mirror)
			)
		)
		(property "Tolerance" ""
			(at 385.325 -20.525 0)
			(layer "B.Fab")
			(hide yes)
			(effects
				(font
					(size 1 1)
					(thickness 0.15)
				)
				(justify mirror)
			)
		)
		(property "Val" "0R"
			(at 385.325 -20.525 0)
			(layer "B.Fab")
			(hide yes)
			(effects
				(font
					(size 1 1)
					(thickness 0.15)
				)
				(justify mirror)
			)
		)
		(sheetname "/Supply/")
		(sheetfile "supply.kicad_sch")
		(attr exclude_from_pos_files exclude_from_bom dnp)
		(fp_rect
			(start -0.93 0.47)
			(end 0.93 -0.47)
			(stroke
				(width 0.05)
				(type solid)
			)
			(fill no)
			(layer "B.CrtYd")
		)
		(fp_rect
			(start -0.5 0.25)
			(end 0.5 -0.25)
			(stroke
				(width 0.15)
				(type solid)
			)
			(fill no)
			(layer "B.Fab")
		)
		(pad "1" smd roundrect
			(at -0.485 0 90)
			(size 0.59 0.64)
			(layers "B.Cu" "B.Mask" "B.Paste")
			(roundrect_rratio 0.25)
			(net 1 "GND")
			(pintype "passive")
		)
		(pad "2" smd roundrect
			(at 0.485 0 90)
			(size 0.59 0.64)
			(layers "B.Cu" "B.Mask" "B.Paste")
			(roundrect_rratio 0.25)
			(net 216 "/Supply/FB3")
			(pintype "passive")
		)
	)
	(footprint "antmicro-footprints:C_0402_1005Metric"
		(layer "B.Cu")
		(at 145.375501 169.801 90)
		(descr "Capacitor SMD 0402 (1005 Metric), square (rectangular) end terminal, IPC_7351 nominal, (Body size source: IPC-SM-782 page 76, https://www.pcb-3d.com/wordpress/wp-content/uploads/ipc-sm-782a_amendment_1_and_2.pdf)")
		(tags "capacitor 0402")
		(property "Reference" "C82"
			(at 0 1.17 270)
			(layer "B.SilkS")
			(hide yes)
			(effects
				(font
					(size 0.7 0.7)
					(thickness 0.15)
				)
				(justify left bottom mirror)
			)
		)
		(property "Value" "C_100n_0402"
			(at 0 -1.169 270)
			(layer "B.Fab")
			(effects
				(font
					(size 0.7 0.7)
					(thickness 0.15)
				)
				(justify left bottom mirror)
			)
		)
		(property "Datasheet" "https://www.murata.com/products/productdetail?partno=GRM155R61H104KE14%23"
			(at 0 0 90)
			(layer "F.Fab")
			(hide yes)
			(effects
				(font
					(size 1.27 1.27)
					(thickness 0.15)
				)
			)
		)
		(property "Author" "Antmicro"
			(at 315.176501 24.425499 0)
			(layer "B.Fab")
			(hide yes)
			(effects
				(font
					(size 1 1)
					(thickness 0.15)
				)
				(justify mirror)
			)
		)
		(property "Dielectric" "X5R"
			(at 315.176501 24.425499 0)
			(layer "B.Fab")
			(hide yes)
			(effects
				(font
					(size 1 1)
					(thickness 0.15)
				)
				(justify mirror)
			)
		)
		(property "License" "Apache-2.0"
			(at 315.176501 24.425499 0)
			(layer "B.Fab")
			(hide yes)
			(effects
				(font
					(size 1 1)
					(thickness 0.15)
				)
				(justify mirror)
			)
		)
		(property "MPN" "GRM155R61H104KE14D"
			(at 315.176501 24.425499 0)
			(layer "B.Fab")
			(hide yes)
			(effects
				(font
					(size 1 1)
					(thickness 0.15)
				)
				(justify mirror)
			)
		)
		(property "Manufacturer" "Murata"
			(at 315.176501 24.425499 0)
			(layer "B.Fab")
			(hide yes)
			(effects
				(font
					(size 1 1)
					(thickness 0.15)
				)
				(justify mirror)
			)
		)
		(property "Val" "100n"
			(at 315.176501 24.425499 0)
			(layer "B.Fab")
			(hide yes)
			(effects
				(font
					(size 1 1)
					(thickness 0.15)
				)
				(justify mirror)
			)
		)
		(property "Voltage" "50V"
			(at 315.176501 24.425499 0)
			(layer "B.Fab")
			(hide yes)
			(effects
				(font
					(size 1 1)
					(thickness 0.15)
				)
				(justify mirror)
			)
		)
		(sheetname "/FPGA power/")
		(sheetfile "fpga-power.kicad_sch")
		(attr smd)
		(fp_rect
			(start -0.9656 0.4572)
			(end 0.9652 -0.4828)
			(stroke
				(width 0.05)
				(type solid)
			)
			(fill no)
			(layer "B.CrtYd")
		)
		(fp_line
			(start 0.498 -0.248)
			(end -0.5 -0.248)
			(stroke
				(width 0.15)
				(type solid)
			)
			(layer "B.Fab")
		)
		(fp_line
			(start -0.5 -0.248)
			(end -0.5 0.25)
			(stroke
				(width 0.15)
				(type solid)
			)
			(layer "B.Fab")
		)
		(fp_line
			(start 0.498 0.25)
			(end 0.498 -0.248)
			(stroke
				(width 0.15)
				(type solid)
			)
			(layer "B.Fab")
		)
		(fp_line
			(start -0.5 0.25)
			(end 0.498 0.25)
			(stroke
				(width 0.15)
				(type solid)
			)
			(layer "B.Fab")
		)
		(pad "1" smd roundrect
			(at -0.5 0)
			(size 0.6 0.6)
			(layers "B.Cu" "B.Mask" "B.Paste")
			(roundrect_rratio 0.25)
			(net 1 "GND")
			(pintype "passive")
		)
		(pad "2" smd roundrect
			(at 0.498 0 90)
			(size 0.6 0.6)
			(layers "B.Cu" "B.Mask" "B.Paste")
			(roundrect_rratio 0.25)
			(net 206 "+1V1")
			(pintype "passive")
		)
	)
	(footprint "antmicro-footprints:TP_SMD_1mm"
		(layer "B.Cu")
		(at 186.4 193.15 180)
		(property "Reference" "TP35"
			(at 0 0.731898 0)
			(layer "B.SilkS")
			(hide yes)
			(effects
				(font
					(size 0.7 0.7)
					(thickness 0.15)
				)
				(justify left bottom mirror)
			)
		)
		(property "Value" "TP_1mm_SMD"
			(at 0 -1.4 0)
			(layer "B.Fab")
			(effects
				(font
					(size 0.7 0.7)
					(thickness 0.15)
				)
				(justify left bottom mirror)
			)
		)
		(property "MPN" ""
			(at 0 0 0)
			(unlocked yes)
			(layer "B.Fab")
			(hide yes)
			(effects
				(font
					(size 1 1)
					(thickness 0.15)
				)
				(justify mirror)
			)
		)
		(property "Manufacturer" ""
			(at 0 0 0)
			(unlocked yes)
			(layer "B.Fab")
			(hide yes)
			(effects
				(font
					(size 1 1)
					(thickness 0.15)
				)
				(justify mirror)
			)
		)
		(property "Author" "Antmicro"
			(at 0 0 0)
			(unlocked yes)
			(layer "B.Fab")
			(hide yes)
			(effects
				(font
					(size 1 1)
					(thickness 0.15)
				)
				(justify mirror)
			)
		)
		(property "License" "Apache-2.0"
			(at 0 0 0)
			(unlocked yes)
			(layer "B.Fab")
			(hide yes)
			(effects
				(font
					(size 1 1)
					(thickness 0.15)
				)
				(justify mirror)
			)
		)
		(sheetname "/Supply/")
		(sheetfile "supply.kicad_sch")
		(attr exclude_from_pos_files)
		(fp_circle
			(center 0 0)
			(end 0.6 0)
			(stroke
				(width 0.05)
				(type default)
			)
			(fill no)
			(layer "B.CrtYd")
		)
		(fp_text user "${REFERENCE}"
			(at -0.5 -2.8 0)
			(layer "B.Fab")
			(effects
				(font
					(size 0.7 0.7)
					(thickness 0.15)
				)
				(justify left bottom mirror)
			)
		)
		(fp_text user "Author: Antmicro"
			(at -0.5 -4 0)
			(layer "B.Fab")
			(effects
				(font
					(size 0.7 0.7)
					(thickness 0.15)
				)
				(justify left bottom mirror)
			)
		)
		(fp_text user "License: Apache-2.0"
			(at -0.5 -5.2 0)
			(layer "B.Fab")
			(effects
				(font
					(size 0.7 0.7)
					(thickness 0.15)
				)
				(justify left bottom mirror)
			)
		)
		(pad "1" smd circle
			(at 0 0 180)
			(size 1 1)
			(layers "B.Cu" "B.Mask")
			(net 226 "+1V2_MGTAVTT")
			(pinfunction "1")
			(pintype "passive")
		)
	)
	(footprint "antmicro-footprints:R_0402_1005Metric"
		(layer "B.Cu")
		(at 159.700501 181.676)
		(descr "Resistor SMD 0402")
		(tags "resistor SMD 0402")
		(property "Reference" "R14"
			(at -1.122484 0.772697 180)
			(layer "B.SilkS")
			(hide yes)
			(effects
				(font
					(size 0.7 0.7)
					(thickness 0.15)
				)
				(justify left bottom mirror)
			)
		)
		(property "Value" "R_10k_0402"
			(at -1.011843 -1.772047 180)
			(layer "B.Fab")
			(effects
				(font
					(size 0.7 0.7)
					(thickness 0.15)
				)
				(justify left bottom mirror)
			)
		)
		(property "Datasheet" "https://www.bourns.com/docs/product-datasheets/cr.pdf"
			(at 0 0 0)
			(layer "F.Fab")
			(hide yes)
			(effects
				(font
					(size 1.27 1.27)
					(thickness 0.15)
				)
			)
		)
		(property "Author" "Antmicro"
			(at 0 0 0)
			(layer "B.Fab")
			(hide yes)
			(effects
				(font
					(size 1 1)
					(thickness 0.15)
				)
				(justify mirror)
			)
		)
		(property "License" "Apache-2.0"
			(at 0 0 0)
			(layer "B.Fab")
			(hide yes)
			(effects
				(font
					(size 1 1)
					(thickness 0.15)
				)
				(justify mirror)
			)
		)
		(property "MPN" "CR0402-FX-1002GLF"
			(at 0 0 0)
			(layer "B.Fab")
			(hide yes)
			(effects
				(font
					(size 1 1)
					(thickness 0.15)
				)
				(justify mirror)
			)
		)
		(property "Manufacturer" "Bourns"
			(at 0 0 0)
			(layer "B.Fab")
			(hide yes)
			(effects
				(font
					(size 1 1)
					(thickness 0.15)
				)
				(justify mirror)
			)
		)
		(property "Tolerance" "1%"
			(at 0 0 0)
			(layer "B.Fab")
			(hide yes)
			(effects
				(font
					(size 1 1)
					(thickness 0.15)
				)
				(justify mirror)
			)
		)
		(property "Val" "10k"
			(at 0 0 0)
			(layer "B.Fab")
			(hide yes)
			(effects
				(font
					(size 1 1)
					(thickness 0.15)
				)
				(justify mirror)
			)
		)
		(sheetname "/FPGA Config/")
		(sheetfile "fpga-config.kicad_sch")
		(attr smd)
		(fp_rect
			(start -0.93 0.47)
			(end 0.93 -0.47)
			(stroke
				(width 0.05)
				(type solid)
			)
			(fill no)
			(layer "B.CrtYd")
		)
		(fp_rect
			(start -0.5 0.25)
			(end 0.5 -0.25)
			(stroke
				(width 0.15)
				(type solid)
			)
			(fill no)
			(layer "B.Fab")
		)
		(pad "1" smd roundrect
			(at -0.485 0)
			(size 0.59 0.64)
			(layers "B.Cu" "B.Mask" "B.Paste")
			(roundrect_rratio 0.25)
			(net 631 "/FPGA Config/MODE2")
			(pintype "passive")
		)
		(pad "2" smd roundrect
			(at 0.485 0)
			(size 0.59 0.64)
			(layers "B.Cu" "B.Mask" "B.Paste")
			(roundrect_rratio 0.25)
			(net 200 "+3V3")
			(pintype "passive")
		)
	)
	(footprint "antmicro-footprints:TP_SMD_1mm"
		(layer "B.Cu")
		(at 182.88 177.9 180)
		(property "Reference" "TP36"
			(at 0 0.731898 0)
			(layer "B.SilkS")
			(hide yes)
			(effects
				(font
					(size 0.7 0.7)
					(thickness 0.15)
				)
				(justify left bottom mirror)
			)
		)
		(property "Value" "TP_1mm_SMD"
			(at 0 -1.4 0)
			(layer "B.Fab")
			(effects
				(font
					(size 0.7 0.7)
					(thickness 0.15)
				)
				(justify left bottom mirror)
			)
		)
		(property "MPN" ""
			(at 0 0 0)
			(unlocked yes)
			(layer "B.Fab")
			(hide yes)
			(effects
				(font
					(size 1 1)
					(thickness 0.15)
				)
				(justify mirror)
			)
		)
		(property "Manufacturer" ""
			(at 0 0 0)
			(unlocked yes)
			(layer "B.Fab")
			(hide yes)
			(effects
				(font
					(size 1 1)
					(thickness 0.15)
				)
				(justify mirror)
			)
		)
		(property "Author" "Antmicro"
			(at 0 0 0)
			(unlocked yes)
			(layer "B.Fab")
			(hide yes)
			(effects
				(font
					(size 1 1)
					(thickness 0.15)
				)
				(justify mirror)
			)
		)
		(property "License" "Apache-2.0"
			(at 0 0 0)
			(unlocked yes)
			(layer "B.Fab")
			(hide yes)
			(effects
				(font
					(size 1 1)
					(thickness 0.15)
				)
				(justify mirror)
			)
		)
		(sheetname "/Supply/")
		(sheetfile "supply.kicad_sch")
		(attr exclude_from_pos_files)
		(fp_circle
			(center 0 0)
			(end 0.6 0)
			(stroke
				(width 0.05)
				(type default)
			)
			(fill no)
			(layer "B.CrtYd")
		)
		(fp_text user "Author: Antmicro"
			(at -0.5 -4 0)
			(layer "B.Fab")
			(effects
				(font
					(size 0.7 0.7)
					(thickness 0.15)
				)
				(justify left bottom mirror)
			)
		)
		(fp_text user "${REFERENCE}"
			(at -0.5 -2.8 0)
			(layer "B.Fab")
			(effects
				(font
					(size 0.7 0.7)
					(thickness 0.15)
				)
				(justify left bottom mirror)
			)
		)
		(fp_text user "License: Apache-2.0"
			(at -0.5 -5.2 0)
			(layer "B.Fab")
			(effects
				(font
					(size 0.7 0.7)
					(thickness 0.15)
				)
				(justify left bottom mirror)
			)
		)
		(pad "1" smd circle
			(at 0 0 180)
			(size 1 1)
			(layers "B.Cu" "B.Mask")
			(net 1 "GND")
			(pinfunction "1")
			(pintype "passive")
		)
	)
	(footprint "antmicro-footprints:C_0402_1005Metric"
		(layer "B.Cu")
		(at 134.600501 189.276)
		(descr "Capacitor SMD 0402")
		(tags "capacitor SMD 0402")
		(property "Reference" "C164"
			(at 0 0.699 180)
			(layer "B.SilkS")
			(hide yes)
			(effects
				(font
					(size 0.7 0.7)
					(thickness 0.15)
				)
				(justify left bottom mirror)
			)
		)
		(property "Value" "C_100n_0402"
			(at -1.022927 -2.155213 180)
			(layer "B.Fab")
			(effects
				(font
					(size 0.7 0.7)
					(thickness 0.15)
				)
				(justify left bottom mirror)
			)
		)
		(property "Datasheet" "https://www.murata.com/products/productdetail?partno=GRM155R61H104KE14%23"
			(at 0 0 0)
			(layer "F.Fab")
			(hide yes)
			(effects
				(font
					(size 1.27 1.27)
					(thickness 0.15)
				)
			)
		)
		(property "Author" "Antmicro"
			(at 0 0 0)
			(layer "B.Fab")
			(hide yes)
			(effects
				(font
					(size 1 1)
					(thickness 0.15)
				)
				(justify mirror)
			)
		)
		(property "Dielectric" "X5R"
			(at 0 0 0)
			(layer "B.Fab")
			(hide yes)
			(effects
				(font
					(size 1 1)
					(thickness 0.15)
				)
				(justify mirror)
			)
		)
		(property "License" "Apache-2.0"
			(at 0 0 0)
			(layer "B.Fab")
			(hide yes)
			(effects
				(font
					(size 1 1)
					(thickness 0.15)
				)
				(justify mirror)
			)
		)
		(property "MPN" "GRM155R61H104KE14D"
			(at 0 0 0)
			(layer "B.Fab")
			(hide yes)
			(effects
				(font
					(size 1 1)
					(thickness 0.15)
				)
				(justify mirror)
			)
		)
		(property "Manufacturer" "Murata"
			(at 0 0 0)
			(layer "B.Fab")
			(hide yes)
			(effects
				(font
					(size 1 1)
					(thickness 0.15)
				)
				(justify mirror)
			)
		)
		(property "Val" "100n"
			(at 0 0 0)
			(layer "B.Fab")
			(hide yes)
			(effects
				(font
					(size 1 1)
					(thickness 0.15)
				)
				(justify mirror)
			)
		)
		(property "Voltage" "50V"
			(at 0 0 0)
			(layer "B.Fab")
			(hide yes)
			(effects
				(font
					(size 1 1)
					(thickness 0.15)
				)
				(justify mirror)
			)
		)
		(sheetname "/FPGA bank 16/")
		(sheetfile "fpga-bank-16.kicad_sch")
		(attr smd)
		(fp_rect
			(start -0.9659 0.481258)
			(end 0.9649 -0.458742)
			(stroke
				(width 0.05)
				(type solid)
			)
			(fill no)
			(layer "B.CrtYd")
		)
		(fp_line
			(start -0.499 -0.248)
			(end -0.499 0.25)
			(stroke
				(width 0.15)
				(type solid)
			)
			(layer "B.Fab")
		)
		(fp_line
			(start -0.499 0.25)
			(end 0.499 0.25)
			(stroke
				(width 0.15)
				(type solid)
			)
			(layer "B.Fab")
		)
		(fp_line
			(start 0.499 -0.248)
			(end -0.499 -0.248)
			(stroke
				(width 0.15)
				(type solid)
			)
			(layer "B.Fab")
		)
		(fp_line
			(start 0.499 0.25)
			(end 0.499 -0.248)
			(stroke
				(width 0.15)
				(type solid)
			)
			(layer "B.Fab")
		)
		(pad "1" smd roundrect
			(at -0.484 0)
			(size 0.59 0.64)
			(layers "B.Cu" "B.Mask" "B.Paste")
			(roundrect_rratio 0.25)
			(net 200 "+3V3")
			(pintype "passive")
		)
		(pad "2" smd roundrect
			(at 0.484 0)
			(size 0.59 0.64)
			(layers "B.Cu" "B.Mask" "B.Paste")
			(roundrect_rratio 0.25)
			(net 1 "GND")
			(pintype "passive")
		)
	)
	(footprint "antmicro-footprints:C_0402_1005Metric"
		(layer "B.Cu")
		(at 146.375501 176.801 -90)
		(descr "Capacitor SMD 0402 (1005 Metric), square (rectangular) end terminal, IPC_7351 nominal, (Body size source: IPC-SM-782 page 76, https://www.pcb-3d.com/wordpress/wp-content/uploads/ipc-sm-782a_amendment_1_and_2.pdf)")
		(tags "capacitor 0402")
		(property "Reference" "C97"
			(at 0 1.17 90)
			(layer "B.SilkS")
			(hide yes)
			(effects
				(font
					(size 0.7 0.7)
					(thickness 0.15)
				)
				(justify left bottom mirror)
			)
		)
		(property "Value" "C_4u7_0402"
			(at 0 -1.169 90)
			(layer "B.Fab")
			(effects
				(font
					(size 0.7 0.7)
					(thickness 0.15)
				)
				(justify left bottom mirror)
			)
		)
		(property "Datasheet" "https://www.murata.com/products/productdetail?partno=GRM155R61A475MEAA%23"
			(at 0 0 270)
			(layer "F.Fab")
			(hide yes)
			(effects
				(font
					(size 1.27 1.27)
					(thickness 0.15)
				)
			)
		)
		(property "Author" "Antmicro"
			(at -30.425499 323.176501 0)
			(layer "B.Fab")
			(hide yes)
			(effects
				(font
					(size 1 1)
					(thickness 0.15)
				)
				(justify mirror)
			)
		)
		(property "Dielectric" ""
			(at -30.425499 323.176501 0)
			(layer "B.Fab")
			(hide yes)
			(effects
				(font
					(size 1 1)
					(thickness 0.15)
				)
				(justify mirror)
			)
		)
		(property "License" "Apache-2.0"
			(at -30.425499 323.176501 0)
			(layer "B.Fab")
			(hide yes)
			(effects
				(font
					(size 1 1)
					(thickness 0.15)
				)
				(justify mirror)
			)
		)
		(property "MPN" "GRM155R61A475MEAAD"
			(at -30.425499 323.176501 0)
			(layer "B.Fab")
			(hide yes)
			(effects
				(font
					(size 1 1)
					(thickness 0.15)
				)
				(justify mirror)
			)
		)
		(property "Manufacturer" "Murata"
			(at -30.425499 323.176501 0)
			(layer "B.Fab")
			(hide yes)
			(effects
				(font
					(size 1 1)
					(thickness 0.15)
				)
				(justify mirror)
			)
		)
		(property "Val" "4u7"
			(at -30.425499 323.176501 0)
			(layer "B.Fab")
			(hide yes)
			(effects
				(font
					(size 1 1)
					(thickness 0.15)
				)
				(justify mirror)
			)
		)
		(property "Voltage" ""
			(at -30.425499 323.176501 0)
			(layer "B.Fab")
			(hide yes)
			(effects
				(font
					(size 1 1)
					(thickness 0.15)
				)
				(justify mirror)
			)
		)
		(sheetname "/FPGA power/")
		(sheetfile "fpga-power.kicad_sch")
		(attr smd)
		(fp_rect
			(start -0.9656 0.4572)
			(end 0.9652 -0.4828)
			(stroke
				(width 0.05)
				(type solid)
			)
			(fill no)
			(layer "B.CrtYd")
		)
		(fp_line
			(start -0.5 0.25)
			(end 0.498 0.25)
			(stroke
				(width 0.15)
				(type solid)
			)
			(layer "B.Fab")
		)
		(fp_line
			(start 0.498 0.25)
			(end 0.498 -0.248)
			(stroke
				(width 0.15)
				(type solid)
			)
			(layer "B.Fab")
		)
		(fp_line
			(start -0.5 -0.248)
			(end -0.5 0.25)
			(stroke
				(width 0.15)
				(type solid)
			)
			(layer "B.Fab")
		)
		(fp_line
			(start 0.498 -0.248)
			(end -0.5 -0.248)
			(stroke
				(width 0.15)
				(type solid)
			)
			(layer "B.Fab")
		)
		(pad "1" smd roundrect
			(at -0.5 0 180)
			(size 0.6 0.6)
			(layers "B.Cu" "B.Mask" "B.Paste")
			(roundrect_rratio 0.25)
			(net 188 "+1V8")
			(pintype "passive")
		)
		(pad "2" smd roundrect
			(at 0.498 0 270)
			(size 0.6 0.6)
			(layers "B.Cu" "B.Mask" "B.Paste")
			(roundrect_rratio 0.25)
			(net 1 "GND")
			(pintype "passive")
		)
	)
	(footprint "antmicro-footprints:R_0402_1005Metric"
		(layer "B.Cu")
		(at 195.3 138.75 90)
		(descr "Resistor SMD 0402")
		(tags "resistor SMD 0402")
		(property "Reference" "R160"
			(at -1.122484 0.772697 270)
			(layer "B.SilkS")
			(hide yes)
			(effects
				(font
					(size 0.7 0.7)
					(thickness 0.15)
				)
				(justify left bottom mirror)
			)
		)
		(property "Value" "R_47k_0402"
			(at -1.011843 -1.772047 270)
			(layer "B.Fab")
			(effects
				(font
					(size 0.7 0.7)
					(thickness 0.15)
				)
				(justify left bottom mirror)
			)
		)
		(property "Datasheet" "https://www.bourns.com/docs/product-datasheets/cr.pdf"
			(at 0 0 90)
			(layer "F.Fab")
			(hide yes)
			(effects
				(font
					(size 1.27 1.27)
					(thickness 0.15)
				)
			)
		)
		(property "Author" "Antmicro"
			(at 334.05 -56.55 0)
			(layer "B.Fab")
			(hide yes)
			(effects
				(font
					(size 1 1)
					(thickness 0.15)
				)
				(justify mirror)
			)
		)
		(property "License" "Apache-2.0"
			(at 334.05 -56.55 0)
			(layer "B.Fab")
			(hide yes)
			(effects
				(font
					(size 1 1)
					(thickness 0.15)
				)
				(justify mirror)
			)
		)
		(property "MPN" "CR0402-FX-4702GLF"
			(at 334.05 -56.55 0)
			(layer "B.Fab")
			(hide yes)
			(effects
				(font
					(size 1 1)
					(thickness 0.15)
				)
				(justify mirror)
			)
		)
		(property "Manufacturer" "Bourns"
			(at 334.05 -56.55 0)
			(layer "B.Fab")
			(hide yes)
			(effects
				(font
					(size 1 1)
					(thickness 0.15)
				)
				(justify mirror)
			)
		)
		(property "Tolerance" "1%"
			(at 334.05 -56.55 0)
			(layer "B.Fab")
			(hide yes)
			(effects
				(font
					(size 1 1)
					(thickness 0.15)
				)
				(justify mirror)
			)
		)
		(property "Val" "47k"
			(at 334.05 -56.55 0)
			(layer "B.Fab")
			(hide yes)
			(effects
				(font
					(size 1 1)
					(thickness 0.15)
				)
				(justify mirror)
			)
		)
		(sheetname "/Supply/")
		(sheetfile "supply.kicad_sch")
		(attr smd)
		(fp_rect
			(start -0.93 0.47)
			(end 0.93 -0.47)
			(stroke
				(width 0.05)
				(type solid)
			)
			(fill no)
			(layer "B.CrtYd")
		)
		(fp_rect
			(start -0.5 0.25)
			(end 0.5 -0.25)
			(stroke
				(width 0.15)
				(type solid)
			)
			(fill no)
			(layer "B.Fab")
		)
		(pad "1" smd roundrect
			(at -0.485 0 90)
			(size 0.59 0.64)
			(layers "B.Cu" "B.Mask" "B.Paste")
			(roundrect_rratio 0.25)
			(net 207 "/Supply/~{PB_CTRL_INT}")
			(pintype "passive")
		)
		(pad "2" smd roundrect
			(at 0.485 0 90)
			(size 0.59 0.64)
			(layers "B.Cu" "B.Mask" "B.Paste")
			(roundrect_rratio 0.25)
			(net 186 "/Supply/PB_CTRL_OUT")
			(pintype "passive")
		)
	)
	(footprint "antmicro-footprints:TP_SMD_1mm"
		(layer "B.Cu")
		(at 89.5 182.85 180)
		(property "Reference" "TP46"
			(at -1.4 0.7 0)
			(layer "B.SilkS")
			(effects
				(font
					(size 0.7 0.7)
					(thickness 0.15)
				)
				(justify left bottom mirror)
			)
		)
		(property "Value" "TP_1mm_SMD"
			(at 0 -1.4 0)
			(layer "B.Fab")
			(effects
				(font
					(size 0.7 0.7)
					(thickness 0.15)
				)
				(justify left bottom mirror)
			)
		)
		(property "MPN" ""
			(at 0 0 0)
			(unlocked yes)
			(layer "B.Fab")
			(hide yes)
			(effects
				(font
					(size 1 1)
					(thickness 0.15)
				)
				(justify mirror)
			)
		)
		(property "Manufacturer" ""
			(at 0 0 0)
			(unlocked yes)
			(layer "B.Fab")
			(hide yes)
			(effects
				(font
					(size 1 1)
					(thickness 0.15)
				)
				(justify mirror)
			)
		)
		(property "Author" "Antmicro"
			(at 0 0 0)
			(unlocked yes)
			(layer "B.Fab")
			(hide yes)
			(effects
				(font
					(size 1 1)
					(thickness 0.15)
				)
				(justify mirror)
			)
		)
		(property "License" "Apache-2.0"
			(at 0 0 0)
			(unlocked yes)
			(layer "B.Fab")
			(hide yes)
			(effects
				(font
					(size 1 1)
					(thickness 0.15)
				)
				(justify mirror)
			)
		)
		(sheetname "/Debug FTDI/")
		(sheetfile "debug-ftdi.kicad_sch")
		(attr exclude_from_pos_files)
		(fp_circle
			(center 0 0)
			(end 0.6 0)
			(stroke
				(width 0.05)
				(type default)
			)
			(fill no)
			(layer "B.CrtYd")
		)
		(fp_text user "Author: Antmicro"
			(at -0.5 -4 0)
			(layer "B.Fab")
			(effects
				(font
					(size 0.7 0.7)
					(thickness 0.15)
				)
				(justify left bottom mirror)
			)
		)
		(fp_text user "License: Apache-2.0"
			(at -0.5 -5.2 0)
			(layer "B.Fab")
			(effects
				(font
					(size 0.7 0.7)
					(thickness 0.15)
				)
				(justify left bottom mirror)
			)
		)
		(fp_text user "${REFERENCE}"
			(at -0.5 -2.8 0)
			(layer "B.Fab")
			(effects
				(font
					(size 0.7 0.7)
					(thickness 0.15)
				)
				(justify left bottom mirror)
			)
		)
		(pad "1" smd circle
			(at 0 0 180)
			(size 1 1)
			(layers "B.Cu" "B.Mask")
			(net 263 "FTDI_DIS")
			(pinfunction "1")
			(pintype "passive")
		)
	)
	(footprint "antmicro-footprints:TP_SMD_1mm"
		(layer "B.Cu")
		(at 191.69 189.26 180)
		(property "Reference" "TP58"
			(at -1.22 -1.72 0)
			(layer "B.SilkS")
			(effects
				(font
					(size 0.7 0.7)
					(thickness 0.15)
				)
				(justify left bottom mirror)
			)
		)
		(property "Value" "TP_1mm_SMD"
			(at 0 -1.4 0)
			(layer "B.Fab")
			(effects
				(font
					(size 0.7 0.7)
					(thickness 0.15)
				)
				(justify left bottom mirror)
			)
		)
		(property "MPN" ""
			(at 0 0 0)
			(unlocked yes)
			(layer "B.Fab")
			(hide yes)
			(effects
				(font
					(size 1 1)
					(thickness 0.15)
				)
				(justify mirror)
			)
		)
		(property "Manufacturer" ""
			(at 0 0 0)
			(unlocked yes)
			(layer "B.Fab")
			(hide yes)
			(effects
				(font
					(size 1 1)
					(thickness 0.15)
				)
				(justify mirror)
			)
		)
		(property "Author" "Antmicro"
			(at 0 0 0)
			(unlocked yes)
			(layer "B.Fab")
			(hide yes)
			(effects
				(font
					(size 1 1)
					(thickness 0.15)
				)
				(justify mirror)
			)
		)
		(property "License" "Apache-2.0"
			(at 0 0 0)
			(unlocked yes)
			(layer "B.Fab")
			(hide yes)
			(effects
				(font
					(size 1 1)
					(thickness 0.15)
				)
				(justify mirror)
			)
		)
		(sheetname "/Supply/")
		(sheetfile "supply.kicad_sch")
		(attr exclude_from_pos_files)
		(fp_circle
			(center 0 0)
			(end 0.6 0)
			(stroke
				(width 0.05)
				(type default)
			)
			(fill no)
			(layer "B.CrtYd")
		)
		(fp_text user "License: Apache-2.0"
			(at -0.5 -5.2 0)
			(layer "B.Fab")
			(effects
				(font
					(size 0.7 0.7)
					(thickness 0.15)
				)
				(justify left bottom mirror)
			)
		)
		(fp_text user "Author: Antmicro"
			(at -0.5 -4 0)
			(layer "B.Fab")
			(effects
				(font
					(size 0.7 0.7)
					(thickness 0.15)
				)
				(justify left bottom mirror)
			)
		)
		(fp_text user "${REFERENCE}"
			(at -0.5 -2.8 0)
			(layer "B.Fab")
			(effects
				(font
					(size 0.7 0.7)
					(thickness 0.15)
				)
				(justify left bottom mirror)
			)
		)
		(pad "1" smd circle
			(at 0 0 180)
			(size 1 1)
			(layers "B.Cu" "B.Mask")
			(net 42 "/Supply/MGTAVCC_local")
			(pinfunction "1")
			(pintype "passive")
		)
	)
	(footprint "antmicro-footprints:R_0402_1005Metric"
		(layer "B.Cu")
		(at 196.575 142.3)
		(descr "Resistor SMD 0402")
		(tags "resistor SMD 0402")
		(property "Reference" "R172"
			(at -1.122484 0.772697 180)
			(layer "B.SilkS")
			(hide yes)
			(effects
				(font
					(size 0.7 0.7)
					(thickness 0.15)
				)
				(justify left bottom mirror)
			)
		)
		(property "Value" "R_47k_0402"
			(at -1.011843 -1.772047 180)
			(layer "B.Fab")
			(effects
				(font
					(size 0.7 0.7)
					(thickness 0.15)
				)
				(justify left bottom mirror)
			)
		)
		(property "Datasheet" "https://www.bourns.com/docs/product-datasheets/cr.pdf"
			(at 0 0 0)
			(layer "F.Fab")
			(hide yes)
			(effects
				(font
					(size 1.27 1.27)
					(thickness 0.15)
				)
			)
		)
		(property "Author" "Antmicro"
			(at 0 0 0)
			(layer "B.Fab")
			(hide yes)
			(effects
				(font
					(size 1 1)
					(thickness 0.15)
				)
				(justify mirror)
			)
		)
		(property "License" "Apache-2.0"
			(at 0 0 0)
			(layer "B.Fab")
			(hide yes)
			(effects
				(font
					(size 1 1)
					(thickness 0.15)
				)
				(justify mirror)
			)
		)
		(property "MPN" "CR0402-FX-4702GLF"
			(at 0 0 0)
			(layer "B.Fab")
			(hide yes)
			(effects
				(font
					(size 1 1)
					(thickness 0.15)
				)
				(justify mirror)
			)
		)
		(property "Manufacturer" "Bourns"
			(at 0 0 0)
			(layer "B.Fab")
			(hide yes)
			(effects
				(font
					(size 1 1)
					(thickness 0.15)
				)
				(justify mirror)
			)
		)
		(property "Tolerance" "1%"
			(at 0 0 0)
			(layer "B.Fab")
			(hide yes)
			(effects
				(font
					(size 1 1)
					(thickness 0.15)
				)
				(justify mirror)
			)
		)
		(property "Val" "47k"
			(at 0 0 0)
			(layer "B.Fab")
			(hide yes)
			(effects
				(font
					(size 1 1)
					(thickness 0.15)
				)
				(justify mirror)
			)
		)
		(sheetname "/Supply/")
		(sheetfile "supply.kicad_sch")
		(attr smd)
		(fp_rect
			(start -0.93 0.47)
			(end 0.93 -0.47)
			(stroke
				(width 0.05)
				(type solid)
			)
			(fill no)
			(layer "B.CrtYd")
		)
		(fp_rect
			(start -0.5 0.25)
			(end 0.5 -0.25)
			(stroke
				(width 0.15)
				(type solid)
			)
			(fill no)
			(layer "B.Fab")
		)
		(pad "1" smd roundrect
			(at -0.485 0)
			(size 0.59 0.64)
			(layers "B.Cu" "B.Mask" "B.Paste")
			(roundrect_rratio 0.25)
			(net 367 "Net-(Q16-D)")
			(pintype "passive")
		)
		(pad "2" smd roundrect
			(at 0.485 0)
			(size 0.59 0.64)
			(layers "B.Cu" "B.Mask" "B.Paste")
			(roundrect_rratio 0.25)
			(net 41 "+3V3_AON")
			(pintype "passive")
		)
	)
	(footprint "antmicro-footprints:C_0402_1005Metric"
		(layer "B.Cu")
		(at 114.800502 183.8)
		(descr "Capacitor SMD 0402")
		(tags "capacitor SMD 0402")
		(property "Reference" "C5"
			(at 0 0.699 180)
			(layer "B.SilkS")
			(hide yes)
			(effects
				(font
					(size 0.7 0.7)
					(thickness 0.15)
				)
				(justify left bottom mirror)
			)
		)
		(property "Value" "C_100n_0402"
			(at -1.022927 -2.155213 180)
			(layer "B.Fab")
			(effects
				(font
					(size 0.7 0.7)
					(thickness 0.15)
				)
				(justify left bottom mirror)
			)
		)
		(property "Datasheet" "https://www.murata.com/products/productdetail?partno=GRM155R61H104KE14%23"
			(at 0 0 0)
			(layer "F.Fab")
			(hide yes)
			(effects
				(font
					(size 1.27 1.27)
					(thickness 0.15)
				)
			)
		)
		(property "Author" "Antmicro"
			(at 0 0 0)
			(layer "B.Fab")
			(hide yes)
			(effects
				(font
					(size 1 1)
					(thickness 0.15)
				)
				(justify mirror)
			)
		)
		(property "Dielectric" "X5R"
			(at 0 0 0)
			(layer "B.Fab")
			(hide yes)
			(effects
				(font
					(size 1 1)
					(thickness 0.15)
				)
				(justify mirror)
			)
		)
		(property "License" "Apache-2.0"
			(at 0 0 0)
			(layer "B.Fab")
			(hide yes)
			(effects
				(font
					(size 1 1)
					(thickness 0.15)
				)
				(justify mirror)
			)
		)
		(property "MPN" "GRM155R61H104KE14D"
			(at 0 0 0)
			(layer "B.Fab")
			(hide yes)
			(effects
				(font
					(size 1 1)
					(thickness 0.15)
				)
				(justify mirror)
			)
		)
		(property "Manufacturer" "Murata"
			(at 0 0 0)
			(layer "B.Fab")
			(hide yes)
			(effects
				(font
					(size 1 1)
					(thickness 0.15)
				)
				(justify mirror)
			)
		)
		(property "Val" "100n"
			(at 0 0 0)
			(layer "B.Fab")
			(hide yes)
			(effects
				(font
					(size 1 1)
					(thickness 0.15)
				)
				(justify mirror)
			)
		)
		(property "Voltage" "50V"
			(at 0 0 0)
			(layer "B.Fab")
			(hide yes)
			(effects
				(font
					(size 1 1)
					(thickness 0.15)
				)
				(justify mirror)
			)
		)
		(sheetname "/HyperRAM + QSPI Flash/")
		(sheetfile "hyperram-flash.kicad_sch")
		(attr smd)
		(fp_rect
			(start -0.9659 0.481258)
			(end 0.9649 -0.458742)
			(stroke
				(width 0.05)
				(type solid)
			)
			(fill no)
			(layer "B.CrtYd")
		)
		(fp_line
			(start -0.499 -0.248)
			(end -0.499 0.25)
			(stroke
				(width 0.15)
				(type solid)
			)
			(layer "B.Fab")
		)
		(fp_line
			(start -0.499 0.25)
			(end 0.499 0.25)
			(stroke
				(width 0.15)
				(type solid)
			)
			(layer "B.Fab")
		)
		(fp_line
			(start 0.499 -0.248)
			(end -0.499 -0.248)
			(stroke
				(width 0.15)
				(type solid)
			)
			(layer "B.Fab")
		)
		(fp_line
			(start 0.499 0.25)
			(end 0.499 -0.248)
			(stroke
				(width 0.15)
				(type solid)
			)
			(layer "B.Fab")
		)
		(pad "1" smd roundrect
			(at -0.484 0)
			(size 0.59 0.64)
			(layers "B.Cu" "B.Mask" "B.Paste")
			(roundrect_rratio 0.25)
			(net 200 "+3V3")
			(pintype "passive")
		)
		(pad "2" smd roundrect
			(at 0.484 0)
			(size 0.59 0.64)
			(layers "B.Cu" "B.Mask" "B.Paste")
			(roundrect_rratio 0.25)
			(net 1 "GND")
			(pintype "passive")
		)
	)
	(footprint "antmicro-footprints:R_0402_1005Metric"
		(layer "B.Cu")
		(at 133.75 142.4 -90)
		(descr "Resistor SMD 0402")
		(tags "resistor SMD 0402")
		(property "Reference" "R25"
			(at -3.044968 -0.354606 90)
			(layer "B.SilkS")
			(effects
				(font
					(size 0.7 0.7)
					(thickness 0.15)
				)
				(justify left bottom mirror)
			)
		)
		(property "Value" "R_47k_0402"
			(at -1.011843 -1.772047 90)
			(layer "B.Fab")
			(effects
				(font
					(size 0.7 0.7)
					(thickness 0.15)
				)
				(justify left bottom mirror)
			)
		)
		(property "Datasheet" "https://www.bourns.com/docs/product-datasheets/cr.pdf"
			(at 0 0 270)
			(layer "F.Fab")
			(hide yes)
			(effects
				(font
					(size 1.27 1.27)
					(thickness 0.15)
				)
			)
		)
		(property "Author" "Antmicro"
			(at -8.65 276.15 0)
			(layer "B.Fab")
			(hide yes)
			(effects
				(font
					(size 1 1)
					(thickness 0.15)
				)
				(justify mirror)
			)
		)
		(property "License" "Apache-2.0"
			(at -8.65 276.15 0)
			(layer "B.Fab")
			(hide yes)
			(effects
				(font
					(size 1 1)
					(thickness 0.15)
				)
				(justify mirror)
			)
		)
		(property "MPN" "CR0402-FX-4702GLF"
			(at -8.65 276.15 0)
			(layer "B.Fab")
			(hide yes)
			(effects
				(font
					(size 1 1)
					(thickness 0.15)
				)
				(justify mirror)
			)
		)
		(property "Manufacturer" "Bourns"
			(at -8.65 276.15 0)
			(layer "B.Fab")
			(hide yes)
			(effects
				(font
					(size 1 1)
					(thickness 0.15)
				)
				(justify mirror)
			)
		)
		(property "Tolerance" "1%"
			(at -8.65 276.15 0)
			(layer "B.Fab")
			(hide yes)
			(effects
				(font
					(size 1 1)
					(thickness 0.15)
				)
				(justify mirror)
			)
		)
		(property "Val" "47k"
			(at -8.65 276.15 0)
			(layer "B.Fab")
			(hide yes)
			(effects
				(font
					(size 1 1)
					(thickness 0.15)
				)
				(justify mirror)
			)
		)
		(sheetname "/DDR5 SODIMM/")
		(sheetfile "ddr5-sodimm.kicad_sch")
		(attr smd)
		(fp_rect
			(start -0.93 0.47)
			(end 0.93 -0.47)
			(stroke
				(width 0.05)
				(type solid)
			)
			(fill no)
			(layer "B.CrtYd")
		)
		(fp_rect
			(start -0.5 0.25)
			(end 0.5 -0.25)
			(stroke
				(width 0.15)
				(type solid)
			)
			(fill no)
			(layer "B.Fab")
		)
		(pad "1" smd roundrect
			(at -0.485 0 270)
			(size 0.59 0.64)
			(layers "B.Cu" "B.Mask" "B.Paste")
			(roundrect_rratio 0.25)
			(net 140 "/DDR5 SODIMM/VSS_DET1")
			(pintype "passive")
		)
		(pad "2" smd roundrect
			(at 0.485 0 270)
			(size 0.59 0.64)
			(layers "B.Cu" "B.Mask" "B.Paste")
			(roundrect_rratio 0.25)
			(net 200 "+3V3")
			(pintype "passive")
		)
	)
	(footprint "antmicro-footprints:R_0402_1005Metric"
		(layer "B.Cu")
		(at 139 142.4 -90)
		(descr "Resistor SMD 0402")
		(tags "resistor SMD 0402")
		(property "Reference" "R28"
			(at -3.044968 -0.354606 90)
			(layer "B.SilkS")
			(effects
				(font
					(size 0.7 0.7)
					(thickness 0.15)
				)
				(justify left bottom mirror)
			)
		)
		(property "Value" "R_0R_0402"
			(at -1.011843 -1.772047 90)
			(layer "B.Fab")
			(effects
				(font
					(size 0.7 0.7)
					(thickness 0.15)
				)
				(justify left bottom mirror)
			)
		)
		(property "Datasheet" "https://industrial.panasonic.com/cdbs/www-data/pdf/RDA0000/AOA0000C301.pdf"
			(at 0 0 270)
			(layer "F.Fab")
			(hide yes)
			(effects
				(font
					(size 1.27 1.27)
					(thickness 0.15)
				)
			)
		)
		(property "Author" "Antmicro"
			(at -3.4 281.4 0)
			(layer "B.Fab")
			(hide yes)
			(effects
				(font
					(size 1 1)
					(thickness 0.15)
				)
				(justify mirror)
			)
		)
		(property "Current" "1A"
			(at -3.4 281.4 0)
			(layer "B.Fab")
			(hide yes)
			(effects
				(font
					(size 1 1)
					(thickness 0.15)
				)
				(justify mirror)
			)
		)
		(property "License" "Apache-2.0"
			(at -3.4 281.4 0)
			(layer "B.Fab")
			(hide yes)
			(effects
				(font
					(size 1 1)
					(thickness 0.15)
				)
				(justify mirror)
			)
		)
		(property "MPN" "ERJ2GE0R00X"
			(at -3.4 281.4 0)
			(layer "B.Fab")
			(hide yes)
			(effects
				(font
					(size 1 1)
					(thickness 0.15)
				)
				(justify mirror)
			)
		)
		(property "Manufacturer" "Panasonic"
			(at -3.4 281.4 0)
			(layer "B.Fab")
			(hide yes)
			(effects
				(font
					(size 1 1)
					(thickness 0.15)
				)
				(justify mirror)
			)
		)
		(property "Tolerance" ""
			(at -3.4 281.4 0)
			(layer "B.Fab")
			(hide yes)
			(effects
				(font
					(size 1 1)
					(thickness 0.15)
				)
				(justify mirror)
			)
		)
		(property "Val" "0R"
			(at -3.4 281.4 0)
			(layer "B.Fab")
			(hide yes)
			(effects
				(font
					(size 1 1)
					(thickness 0.15)
				)
				(justify mirror)
			)
		)
		(sheetname "/DDR5 SODIMM/")
		(sheetfile "ddr5-sodimm.kicad_sch")
		(attr smd)
		(fp_rect
			(start -0.93 0.47)
			(end 0.93 -0.47)
			(stroke
				(width 0.05)
				(type solid)
			)
			(fill no)
			(layer "B.CrtYd")
		)
		(fp_rect
			(start -0.5 0.25)
			(end 0.5 -0.25)
			(stroke
				(width 0.15)
				(type solid)
			)
			(fill no)
			(layer "B.Fab")
		)
		(pad "1" smd roundrect
			(at -0.485 0 270)
			(size 0.59 0.64)
			(layers "B.Cu" "B.Mask" "B.Paste")
			(roundrect_rratio 0.25)
			(net 172 "/DDR5 SODIMM/VSS_DET2")
			(pintype "passive")
		)
		(pad "2" smd roundrect
			(at 0.485 0 270)
			(size 0.59 0.64)
			(layers "B.Cu" "B.Mask" "B.Paste")
			(roundrect_rratio 0.25)
			(net 249 "TB_DETECT")
			(pintype "passive")
		)
	)
	(footprint "antmicro-footprints:C_0402_1005Metric"
		(layer "B.Cu")
		(at 131.375501 170.801 90)
		(descr "Capacitor SMD 0402 (1005 Metric), square (rectangular) end terminal, IPC_7351 nominal, (Body size source: IPC-SM-782 page 76, https://www.pcb-3d.com/wordpress/wp-content/uploads/ipc-sm-782a_amendment_1_and_2.pdf)")
		(tags "capacitor 0402")
		(property "Reference" "C52"
			(at 0 1.17 270)
			(layer "B.SilkS")
			(hide yes)
			(effects
				(font
					(size 0.7 0.7)
					(thickness 0.15)
				)
				(justify left bottom mirror)
			)
		)
		(property "Value" "C_100n_0402"
			(at 0 -1.169 270)
			(layer "B.Fab")
			(effects
				(font
					(size 0.7 0.7)
					(thickness 0.15)
				)
				(justify left bottom mirror)
			)
		)
		(property "Datasheet" "https://www.murata.com/products/productdetail?partno=GRM155R61H104KE14%23"
			(at 0 0 90)
			(layer "F.Fab")
			(hide yes)
			(effects
				(font
					(size 1.27 1.27)
					(thickness 0.15)
				)
			)
		)
		(property "Author" "Antmicro"
			(at 302.176501 39.425499 0)
			(layer "B.Fab")
			(hide yes)
			(effects
				(font
					(size 1 1)
					(thickness 0.15)
				)
				(justify mirror)
			)
		)
		(property "Dielectric" "X5R"
			(at 302.176501 39.425499 0)
			(layer "B.Fab")
			(hide yes)
			(effects
				(font
					(size 1 1)
					(thickness 0.15)
				)
				(justify mirror)
			)
		)
		(property "License" "Apache-2.0"
			(at 302.176501 39.425499 0)
			(layer "B.Fab")
			(hide yes)
			(effects
				(font
					(size 1 1)
					(thickness 0.15)
				)
				(justify mirror)
			)
		)
		(property "MPN" "GRM155R61H104KE14D"
			(at 302.176501 39.425499 0)
			(layer "B.Fab")
			(hide yes)
			(effects
				(font
					(size 1 1)
					(thickness 0.15)
				)
				(justify mirror)
			)
		)
		(property "Manufacturer" "Murata"
			(at 302.176501 39.425499 0)
			(layer "B.Fab")
			(hide yes)
			(effects
				(font
					(size 1 1)
					(thickness 0.15)
				)
				(justify mirror)
			)
		)
		(property "Val" "100n"
			(at 302.176501 39.425499 0)
			(layer "B.Fab")
			(hide yes)
			(effects
				(font
					(size 1 1)
					(thickness 0.15)
				)
				(justify mirror)
			)
		)
		(property "Voltage" "50V"
			(at 302.176501 39.425499 0)
			(layer "B.Fab")
			(hide yes)
			(effects
				(font
					(size 1 1)
					(thickness 0.15)
				)
				(justify mirror)
			)
		)
		(sheetname "/FPGA power/")
		(sheetfile "fpga-power.kicad_sch")
		(attr smd)
		(fp_rect
			(start -0.9656 0.4572)
			(end 0.9652 -0.4828)
			(stroke
				(width 0.05)
				(type solid)
			)
			(fill no)
			(layer "B.CrtYd")
		)
		(fp_line
			(start 0.498 -0.248)
			(end -0.5 -0.248)
			(stroke
				(width 0.15)
				(type solid)
			)
			(layer "B.Fab")
		)
		(fp_line
			(start -0.5 -0.248)
			(end -0.5 0.25)
			(stroke
				(width 0.15)
				(type solid)
			)
			(layer "B.Fab")
		)
		(fp_line
			(start 0.498 0.25)
			(end 0.498 -0.248)
			(stroke
				(width 0.15)
				(type solid)
			)
			(layer "B.Fab")
		)
		(fp_line
			(start -0.5 0.25)
			(end 0.498 0.25)
			(stroke
				(width 0.15)
				(type solid)
			)
			(layer "B.Fab")
		)
		(pad "1" smd roundrect
			(at -0.5 0)
			(size 0.6 0.6)
			(layers "B.Cu" "B.Mask" "B.Paste")
			(roundrect_rratio 0.25)
			(net 1 "GND")
			(pintype "passive")
		)
		(pad "2" smd roundrect
			(at 0.498 0 90)
			(size 0.6 0.6)
			(layers "B.Cu" "B.Mask" "B.Paste")
			(roundrect_rratio 0.25)
			(net 200 "+3V3")
			(pintype "passive")
		)
	)
	(footprint "antmicro-footprints:C_0402_1005Metric"
		(layer "B.Cu")
		(at 142.875501 162.301)
		(descr "Capacitor SMD 0402 (1005 Metric), square (rectangular) end terminal, IPC_7351 nominal, (Body size source: IPC-SM-782 page 76, https://www.pcb-3d.com/wordpress/wp-content/uploads/ipc-sm-782a_amendment_1_and_2.pdf)")
		(tags "capacitor 0402")
		(property "Reference" "C63"
			(at 0 1.17 180)
			(layer "B.SilkS")
			(hide yes)
			(effects
				(font
					(size 0.7 0.7)
					(thickness 0.15)
				)
				(justify left bottom mirror)
			)
		)
		(property "Value" "C_100n_0402"
			(at 0 -1.169 180)
			(layer "B.Fab")
			(effects
				(font
					(size 0.7 0.7)
					(thickness 0.15)
				)
				(justify left bottom mirror)
			)
		)
		(property "Datasheet" "https://www.murata.com/products/productdetail?partno=GRM155R61H104KE14%23"
			(at 0 0 0)
			(layer "F.Fab")
			(hide yes)
			(effects
				(font
					(size 1.27 1.27)
					(thickness 0.15)
				)
			)
		)
		(property "Author" "Antmicro"
			(at 0 0 0)
			(layer "B.Fab")
			(hide yes)
			(effects
				(font
					(size 1 1)
					(thickness 0.15)
				)
				(justify mirror)
			)
		)
		(property "Dielectric" "X5R"
			(at 0 0 0)
			(layer "B.Fab")
			(hide yes)
			(effects
				(font
					(size 1 1)
					(thickness 0.15)
				)
				(justify mirror)
			)
		)
		(property "License" "Apache-2.0"
			(at 0 0 0)
			(layer "B.Fab")
			(hide yes)
			(effects
				(font
					(size 1 1)
					(thickness 0.15)
				)
				(justify mirror)
			)
		)
		(property "MPN" "GRM155R61H104KE14D"
			(at 0 0 0)
			(layer "B.Fab")
			(hide yes)
			(effects
				(font
					(size 1 1)
					(thickness 0.15)
				)
				(justify mirror)
			)
		)
		(property "Manufacturer" "Murata"
			(at 0 0 0)
			(layer "B.Fab")
			(hide yes)
			(effects
				(font
					(size 1 1)
					(thickness 0.15)
				)
				(justify mirror)
			)
		)
		(property "Val" "100n"
			(at 0 0 0)
			(layer "B.Fab")
			(hide yes)
			(effects
				(font
					(size 1 1)
					(thickness 0.15)
				)
				(justify mirror)
			)
		)
		(property "Voltage" "50V"
			(at 0 0 0)
			(layer "B.Fab")
			(hide yes)
			(effects
				(font
					(size 1 1)
					(thickness 0.15)
				)
				(justify mirror)
			)
		)
		(sheetname "/FPGA power/")
		(sheetfile "fpga-power.kicad_sch")
		(attr smd)
		(fp_rect
			(start -0.9656 0.4572)
			(end 0.9652 -0.4828)
			(stroke
				(width 0.05)
				(type solid)
			)
			(fill no)
			(layer "B.CrtYd")
		)
		(fp_line
			(start -0.5 -0.248)
			(end -0.5 0.25)
			(stroke
				(width 0.15)
				(type solid)
			)
			(layer "B.Fab")
		)
		(fp_line
			(start -0.5 0.25)
			(end 0.498 0.25)
			(stroke
				(width 0.15)
				(type solid)
			)
			(layer "B.Fab")
		)
		(fp_line
			(start 0.498 -0.248)
			(end -0.5 -0.248)
			(stroke
				(width 0.15)
				(type solid)
			)
			(layer "B.Fab")
		)
		(fp_line
			(start 0.498 0.25)
			(end 0.498 -0.248)
			(stroke
				(width 0.15)
				(type solid)
			)
			(layer "B.Fab")
		)
		(pad "1" smd roundrect
			(at -0.5 0 270)
			(size 0.6 0.6)
			(layers "B.Cu" "B.Mask" "B.Paste")
			(roundrect_rratio 0.25)
			(net 1 "GND")
			(pintype "passive")
		)
		(pad "2" smd roundrect
			(at 0.498 0)
			(size 0.6 0.6)
			(layers "B.Cu" "B.Mask" "B.Paste")
			(roundrect_rratio 0.25)
			(net 206 "+1V1")
			(pintype "passive")
		)
	)
	(footprint "antmicro-footprints:C_0603_1608Metric"
		(layer "B.Cu")
		(at 153.275001 166.7025)
		(descr "Capacitor SMD 0603")
		(tags "capacitor 0603")
		(property "Reference" "C60"
			(at 0 0.9 0)
			(layer "B.SilkS")
			(hide yes)
			(effects
				(font
					(size 0.7 0.7)
					(thickness 0.15)
				)
				(justify right bottom mirror)
			)
		)
		(property "Value" "C_47u_0603"
			(at 0 -1.6 0)
			(layer "B.Fab")
			(effects
				(font
					(size 0.7 0.7)
					(thickness 0.15)
				)
				(justify right bottom mirror)
			)
		)
		(property "Datasheet" "https://www.murata.com/products/productdetail?partno=GRM188R60J476ME15%23"
			(at 0 0 0)
			(layer "F.Fab")
			(hide yes)
			(effects
				(font
					(size 1.27 1.27)
					(thickness 0.15)
				)
			)
		)
		(property "Author" "Antmicro"
			(at 0 0 0)
			(layer "B.Fab")
			(hide yes)
			(effects
				(font
					(size 1 1)
					(thickness 0.15)
				)
				(justify mirror)
			)
		)
		(property "Dielectric" ""
			(at 0 0 0)
			(layer "B.Fab")
			(hide yes)
			(effects
				(font
					(size 1 1)
					(thickness 0.15)
				)
				(justify mirror)
			)
		)
		(property "License" "Apache-2.0"
			(at 0 0 0)
			(layer "B.Fab")
			(hide yes)
			(effects
				(font
					(size 1 1)
					(thickness 0.15)
				)
				(justify mirror)
			)
		)
		(property "MPN" "GRM188R60J476ME15D"
			(at 0 0 0)
			(layer "B.Fab")
			(hide yes)
			(effects
				(font
					(size 1 1)
					(thickness 0.15)
				)
				(justify mirror)
			)
		)
		(property "Manufacturer" "Murata"
			(at 0 0 0)
			(layer "B.Fab")
			(hide yes)
			(effects
				(font
					(size 1 1)
					(thickness 0.15)
				)
				(justify mirror)
			)
		)
		(property "Val" "47u"
			(at 0 0 0)
			(layer "B.Fab")
			(hide yes)
			(effects
				(font
					(size 1 1)
					(thickness 0.15)
				)
				(justify mirror)
			)
		)
		(property "Voltage" ""
			(at 0 0 0)
			(layer "B.Fab")
			(hide yes)
			(effects
				(font
					(size 1 1)
					(thickness 0.15)
				)
				(justify mirror)
			)
		)
		(sheetname "/FPGA power/")
		(sheetfile "fpga-power.kicad_sch")
		(attr smd)
		(fp_line
			(start -0.3 -0.3)
			(end 0.3 -0.3)
			(stroke
				(width 0.15)
				(type solid)
			)
			(layer "B.SilkS")
		)
		(fp_line
			(start -0.3 0.3)
			(end 0.3 0.3)
			(stroke
				(width 0.15)
				(type solid)
			)
			(layer "B.SilkS")
		)
		(fp_rect
			(start -1.24 0.7)
			(end 1.24 -0.7)
			(stroke
				(width 0.05)
				(type solid)
			)
			(fill no)
			(layer "B.CrtYd")
		)
		(fp_rect
			(start -0.8 0.4)
			(end 0.8 -0.4)
			(stroke
				(width 0.15)
				(type solid)
			)
			(fill no)
			(layer "B.Fab")
		)
		(pad "1" smd roundrect
			(at -0.7 0)
			(size 0.6 0.8)
			(layers "B.Cu" "B.Mask" "B.Paste")
			(roundrect_rratio 0.2)
			(net 206 "+1V1")
			(pintype "passive")
		)
		(pad "2" smd roundrect
			(at 0.7 0)
			(size 0.6 0.8)
			(layers "B.Cu" "B.Mask" "B.Paste")
			(roundrect_rratio 0.2)
			(net 1 "GND")
			(pintype "passive")
		)
	)
	(gr_line
		(start 186.5 137)
		(end 186.791759 136.307099)
		(stroke
			(width 0.25)
			(type solid)
		)
		(layer "B.Cu")
		(net 38)
	)
	(gr_line
		(start 165.75 198.35)
		(end 165.25 199.15)
		(stroke
			(width 0.2)
			(type default)
		)
		(layer "B.Cu")
		(net 227)
	)
	(gr_line
		(start 68.875501 209.801)
		(end 83.875501 209.801)
		(stroke
			(width 0.12)
			(type solid)
		)
		(layer "Edge.Cuts")
	)
	(gr_line
		(start 68.875501 111.551)
		(end 68.875501 209.801)
		(stroke
			(width 0.12)
			(type solid)
		)
		(layer "Edge.Cuts")
	)
	(gr_line
		(start 102.225501 201.551)
		(end 102.225501 209.801)
		(stroke
			(width 0.12)
			(type solid)
		)
		(layer "Edge.Cuts")
	)
	(gr_line
		(start 148.175501 201.551)
		(end 148.175501 205.901)
		(stroke
			(width 0.12)
			(type solid)
		)
		(layer "Edge.Cuts")
	)
	(gr_line
		(start 206.875501 111.551)
		(end 206.878201 201.551)
		(stroke
			(width 0.12)
			(type solid)
		)
		(layer "Edge.Cuts")
	)
	(gr_line
		(start 110.225501 209.801)
		(end 110.225501 203.376)
		(stroke
			(width 0.12)
			(type solid)
		)
		(layer "Edge.Cuts")
	)
	(gr_line
		(start 83.875501 201.551)
		(end 102.225501 201.551)
		(stroke
			(width 0.12)
			(type solid)
		)
		(layer "Edge.Cuts")
	)
	(gr_arc
		(start 110.225501 203.376)
		(mid 112.050501 201.551)
		(end 113.875501 203.376)
		(stroke
			(width 0.12)
			(type solid)
		)
		(layer "Edge.Cuts")
	)
	(gr_line
		(start 206.878201 201.551)
		(end 148.175501 201.551)
		(stroke
			(width 0.12)
			(type solid)
		)
		(layer "Edge.Cuts")
	)
	(gr_line
		(start 113.875501 205.901)
		(end 113.875501 203.376)
		(stroke
			(width 0.12)
			(type solid)
		)
		(layer "Edge.Cuts")
	)
	(gr_line
		(start 83.875501 209.801)
		(end 83.875501 201.551)
		(stroke
			(width 0.12)
			(type solid)
		)
		(layer "Edge.Cuts")
	)
	(gr_line
		(start 102.225501 209.801)
		(end 110.225501 209.801)
		(stroke
			(width 0.12)
			(type solid)
		)
		(layer "Edge.Cuts")
	)
	(gr_line
		(start 68.875501 111.551)
		(end 206.875501 111.551)
		(stroke
			(width 0.12)
			(type solid)
		)
		(layer "Edge.Cuts")
	)
	(gr_text "SO-DIMM DDR5 Tester"
		(at 109.3 168.750002 0)
		(layer "F.Cu")
		(effects
			(font
				(size 0.7 0.7)
				(thickness 0.15)
			)
			(justify left)
		)
	)
	(gr_text "11/2025"
		(at 109.3 170.899999 0)
		(layer "F.Cu")
		(effects
			(font
				(size 0.7 0.7)
				(thickness 0.15)
			)
			(justify left)
		)
	)
	(gr_text "Rev. ${REVISION}"
		(at 109.3 169.8 0)
		(layer "F.Cu")
		(effects
			(font
				(size 0.7 0.7)
				(thickness 0.15)
			)
			(justify left)
		)
	)
	(segment
		(start 88.491829 151.183859)
		(end 88.491829 150.623157)
		(width 0.2)
		(layer "F.Cu")
		(net 1)
	)
	(segment
		(start 88.491829 154.553859)
		(end 87.391829 154.553859)
		(width 0.2)
		(layer "F.Cu")
		(net 1)
	)
	(segment
		(start 102.191829 151.718859)
		(end 102.191829 150.523157)
		(width 0.2)
		(layer "F.Cu")
		(net 1)
	)
	(segment
		(start 100.400501 150.873851)
		(end 100.400501 150.213149)
		(width 0.2)
		(layer "F.Cu")
		(net 1)
	)
	(segment
		(start 108.0975 131.1025)
		(end 108.1 131.1)
		(width 0.4)
		(layer "F.Cu")
		(net 1)
	)
	(segment
		(start 82.010758 182.4431)
		(end 82.9724 182.4431)
		(width 0.4)
		(layer "F.Cu")
		(net 1)
	)
	(segment
		(start 112.400001 146.2025)
		(end 112.400001 145.1275)
		(width 0.201)
		(layer "F.Cu")
		(net 1)
	)
	(segment
		(start 141.375501 182.301)
		(end 141.875001 182.8005)
		(width 0.256)
		(layer "F.Cu")
		(net 1)
	)
	(segment
		(start 145.375501 183.301)
		(end 145.875001 183.8005)
		(width 0.256)
		(layer "F.Cu")
		(net 1)
	)
	(segment
		(start 156.650003 138.8025)
		(end 156.650002 137.7275)
		(width 0.201)
		(layer "F.Cu")
		(net 1)
	)
	(segment
		(start 103.37765 150.158851)
		(end 102.980501 150.556)
		(width 0.256)
		(layer "F.Cu")
		(net 1)
	)
	(segment
		(start 183.057 148.650001)
		(end 183.057 149.666)
		(width 0.256)
		(layer "F.Cu")
		(net 1)
	)
	(segment
		(start 137.000501 194.176)
		(end 137.000501 193.731501)
		(width 0.4)
		(layer "F.Cu")
		(net 1)
	)
	(segment
		(start 160.149501 182.674)
		(end 159.4545 182.674)
		(width 0.201)
		(layer "F.Cu")
		(net 1)
	)
	(segment
		(start 154.346 172.904)
		(end 155.1005 172.1495)
		(width 0.4)
		(layer "F.Cu")
		(net 1)
	)
	(segment
		(start 78.199999 160.6)
		(end 79.085 160.6)
		(width 0.4)
		(layer "F.Cu")
		(net 1)
	)
	(segment
		(start 168.400001 146.2025)
		(end 168.4 145.127499)
		(width 0.201)
		(layer "F.Cu")
		(net 1)
	)
	(segment
		(start 103.152 181.435)
		(end 102.735 181.435)
		(width 0.15)
		(layer "F.Cu")
		(net 1)
	)
	(segment
		(start 148.375501 174.302)
		(end 148.875001 173.802501)
		(width 0.256)
		(layer "F.Cu")
		(net 1)
	)
	(segment
		(start 115.400001 146.2025)
		(end 115.400001 145.1275)
		(width 0.201)
		(layer "F.Cu")
		(net 1)
	)
	(segment
		(start 203.752 147.7)
		(end 203.752 146.848)
		(width 0.4)
		(layer "F.Cu")
		(net 1)
	)
	(segment
		(start 92.400501 130.3)
		(end 92.400501 130.300501)
		(width 0.15)
		(layer "F.Cu")
		(net 1)
	)
	(segment
		(start 190.545 142.23)
		(end 191.43 142.23)
		(width 0.201)
		(layer "F.Cu")
		(net 1)
	)
	(segment
		(start 79.979501 191.817)
		(end 79.980501 191.816)
		(width 0.201)
		(layer "F.Cu")
		(net 1)
	)
	(segment
		(start 140.375501 173.302001)
		(end 140.875001 172.8025)
		(width 0.256)
		(layer "F.Cu")
		(net 1)
	)
	(segment
		(start 169.150001 138.8025)
		(end 169.15 137.727499)
		(width 0.201)
		(layer "F.Cu")
		(net 1)
	)
	(segment
		(start 137.000501 193.731501)
		(end 136.269 193)
		(width 0.4)
		(layer "F.Cu")
		(net 1)
	)
	(segment
		(start 146.375502 167.302)
		(end 146.875001 166.802501)
		(width 0.256)
		(layer "F.Cu")
		(net 1)
	)
	(segment
		(start 141.65 138.8025)
		(end 141.65 139.8775)
		(width 0.201)
		(layer "F.Cu")
		(net 1)
	)
	(segment
		(start 98.350501 130.949499)
		(end 98.3 131)
		(width 0.15)
		(layer "F.Cu")
		(net 1)
	)
	(segment
		(start 195.375 141.225)
		(end 195.375 141.877)
		(width 0.256)
		(layer "F.Cu")
		(net 1)
	)
	(segment
		(start 153.9 146.2025)
		(end 153.9 145.127499)
		(width 0.201)
		(layer "F.Cu")
		(net 1)
	)
	(segment
		(start 183.444759 131.420258)
		(end 183.330501 131.306)
		(width 0.256)
		(layer "F.Cu")
		(net 1)
	)
	(segment
		(start 87.000501 123.876)
		(end 87.000501 124.606)
		(width 0.15)
		(layer "F.Cu")
		(net 1)
	)
	(segment
		(start 166.098501 181.672)
		(end 166.115501 181.655)
		(width 0.201)
		(layer "F.Cu")
		(net 1)
	)
	(segment
		(start 134.376501 181.301)
		(end 133.877001 181.8005)
		(width 0.256)
		(layer "F.Cu")
		(net 1)
	)
	(segment
		(start 89.700501 123.876)
		(end 89.700501 124.606)
		(width 0.15)
		(layer "F.Cu")
		(net 1)
	)
	(segment
		(start 138.376501 183.301)
		(end 137.877001 183.8005)
		(width 0.256)
		(layer "F.Cu")
		(net 1)
	)
	(segment
		(start 117.525501 207.451)
		(end 120.325501 207.451)
		(width 0.4)
		(layer "F.Cu")
		(net 1)
	)
	(segment
		(start 78.244501 194.817)
		(end 79.979501 194.817)
		(width 0.201)
		(layer "F.Cu")
		(net 1)
	)
	(segment
		(start 184.9 184.4)
		(end 184.636 184.664)
		(width 0.256)
		(layer "F.Cu")
		(net 1)
	)
	(segment
		(start 155.1005 172.1495)
		(end 155.1005 171.9015)
		(width 0.4)
		(layer "F.Cu")
		(net 1)
	)
	(segment
		(start 149.375501 174.301999)
		(end 149.875001 173.8025)
		(width 0.256)
		(layer "F.Cu")
		(net 1)
	)
	(segment
		(start 124.900001 146.2025)
		(end 124.900001 145.1275)
		(width 0.201)
		(layer "F.Cu")
		(net 1)
	)
	(segment
		(start 159.650002 138.8025)
		(end 159.650001 137.727499)
		(width 0.201)
		(layer "F.Cu")
		(net 1)
	)
	(segment
		(start 103.050501 117.526)
		(end 103.780501 117.526)
		(width 0.15)
		(layer "F.Cu")
		(net 1)
	)
	(segment
		(start 103.050501 114.826)
		(end 103.780501 114.826)
		(width 0.15)
		(layer "F.Cu")
		(net 1)
	)
	(segment
		(start 114.150001 138.8025)
		(end 114.150001 137.7275)
		(width 0.201)
		(layer "F.Cu")
		(net 1)
	)
	(segment
		(start 152.9 146.2025)
		(end 152.9 145.127499)
		(width 0.201)
		(layer "F.Cu")
		(net 1)
	)
	(segment
		(start 85.762531 157.953859)
		(end 85.741829 157.933157)
		(width 0.2)
		(layer "F.Cu")
		(net 1)
	)
	(segment
		(start 116.15 194.75)
		(end 115.6 195.3)
		(width 0.4)
		(layer "F.Cu")
		(net 1)
	)
	(segment
		(start 155.0015 178.126)
		(end 155.750501 178.126)
		(width 0.4)
		(layer "F.Cu")
		(net 1)
	)
	(segment
		(start 183.604107 181.1755)
		(end 183.605107 181.1745)
		(width 0.256)
		(layer "F.Cu")
		(net 1)
	)
	(segment
		(start 134.000501 206.425501)
		(end 133.525501 206.900501)
		(width 0.22)
		(layer "F.Cu")
		(net 1)
	)
	(segment
		(start 82.015 191)
		(end 81.3 191)
		(width 0.256)
		(layer "F.Cu")
		(net 1)
	)
	(segment
		(start 182.140108 164.370194)
		(end 182.140109 165.286)
		(width 0.256)
		(layer "F.Cu")
		(net 1)
	)
	(segment
		(start 93 190.484)
		(end 93 190.5)
		(width 0.201)
		(layer "F.Cu")
		(net 1)
	)
	(segment
		(start 174.8955 180.3985)
		(end 174.894 180.4)
		(width 0.256)
		(layer "F.Cu")
		(net 1)
	)
	(segment
		(start 184.070501 130.456)
		(end 184.070501 130.469841)
		(width 0.256)
		(layer "F.Cu")
		(net 1)
	)
	(segment
		(start 145.900001 146.2025)
		(end 145.9 145.127499)
		(width 0.201)
		(layer "F.Cu")
		(net 1)
	)
	(segment
		(start 174.8865 168.4235)
		(end 172.9205 168.4235)
		(width 0.256)
		(layer "F.Cu")
		(net 1)
	)
	(segment
		(start 104.401 181.435)
		(end 104.651 181.685)
		(width 0.15)
		(layer "F.Cu")
		(net 1)
	)
	(segment
		(start 183.1416 135.907099)
		(end 183.140501 135.906)
		(width 0.256)
		(layer "F.Cu")
		(net 1)
	)
	(segment
		(start 180.278 198.807)
		(end 179.511 198.807)
		(width 0.177)
		(layer "F.Cu")
		(net 1)
	)
	(segment
		(start 144.000501 206.400501)
		(end 144.525501 206.925501)
		(width 0.22)
		(layer "F.Cu")
		(net 1)
	)
	(segment
		(start 144.375501 181.301)
		(end 144.875001 181.800501)
		(width 0.256)
		(layer "F.Cu")
		(net 1)
	)
	(segment
		(start 177.100501 198.261)
		(end 177.735501 198.261)
		(width 0.256)
		(layer "F.Cu")
		(net 1)
	)
	(segment
		(start 121.900001 146.2025)
		(end 121.900001 145.1275)
		(width 0.201)
		(layer "F.Cu")
		(net 1)
	)
	(segment
		(start 180.288141 166.500001)
		(end 180.926107 166.500001)
		(width 0.256)
		(layer "F.Cu")
		(net 1)
	)
	(segment
		(start 90.690501 176.52)
		(end 90.690501 177.082)
		(width 0.256)
		(layer "F.Cu")
		(net 1)
	)
	(segment
		(start 142.900002 146.2025)
		(end 142.900001 145.1275)
		(width 0.201)
		(layer "F.Cu")
		(net 1)
	)
	(segment
		(start 145.375501 178.301)
		(end 145.875001 178.8005)
		(width 0.256)
		(layer "F.Cu")
		(net 1)
	)
	(segment
		(start 103.88765 154.958851)
		(end 103.910501 154.936)
		(width 0.256)
		(layer "F.Cu")
		(net 1)
	)
	(segment
		(start 100.930016 167.061)
		(end 100.927344 167.058328)
		(width 0.256)
		(layer "F.Cu")
		(net 1)
	)
	(segment
		(start 198.799499 139.214)
		(end 197.754 139.214)
		(width 0.182)
		(layer "F.Cu")
		(net 1)
	)
	(segment
		(start 112.150001 138.8025)
		(end 112.150001 137.7275)
		(width 0.201)
		(layer "F.Cu")
		(net 1)
	)
	(segment
		(start 184.431 128.2)
		(end 183.696 128.2)
		(width 0.256)
		(layer "F.Cu")
		(net 1)
	)
	(segment
		(start 138.376501 163.302)
		(end 137.877002 162.8025)
		(width 0.256)
		(layer "F.Cu")
		(net 1)
	)
	(segment
		(start 141.375501 176.301)
		(end 141.875001 176.8005)
		(width 0.256)
		(layer "F.Cu")
		(net 1)
	)
	(segment
		(start 174.888 168.422)
		(end 174.8865 168.4235)
		(width 0.256)
		(layer "F.Cu")
		(net 1)
	)
	(segment
		(start 120.45 191.65)
		(end 121 191.1)
		(width 0.4)
		(layer "F.Cu")
		(net 1)
	)
	(segment
		(start 160.097501 177.979999)
		(end 160.078501 177.960999)
		(width 0.201)
		(layer "F.Cu")
		(net 1)
	)
	(segment
		(start 103.852503 131.1025)
		(end 103.850002 131.105)
		(width 0.4)
		(layer "F.Cu")
		(net 1)
	)
	(segment
		(start 179.6 166.2)
		(end 179.98814 166.2)
		(width 0.256)
		(layer "F.Cu")
		(net 1)
	)
	(segment
		(start 182.1 190.65)
		(end 182.2 190.65)
		(width 0.177)
		(layer "F.Cu")
		(net 1)
	)
	(segment
		(start 166.150002 138.8025)
		(end 166.150001 137.7275)
		(width 0.201)
		(layer "F.Cu")
		(net 1)
	)
	(segment
		(start 143.375501 168.302)
		(end 143.875001 167.8025)
		(width 0.256)
		(layer "F.Cu")
		(net 1)
	)
	(segment
		(start 78.185 157.5)
		(end 78.185 158.285)
		(width 0.201)
		(layer "F.Cu")
		(net 1)
	)
	(segment
		(start 92.400501 123.876)
		(end 92.400501 124.606)
		(width 0.15)
		(layer "F.Cu")
		(net 1)
	)
	(segment
		(start 122.900001 146.2025)
		(end 122.900001 145.1275)
		(width 0.201)
		(layer "F.Cu")
		(net 1)
	)
	(segment
		(start 174.894 176.4)
		(end 172.928 176.4)
		(width 0.256)
		(layer "F.Cu")
		(net 1)
	)
	(segment
		(start 83.4 169.2)
		(end 82.073501 169.2)
		(width 0.256)
		(layer "F.Cu")
		(net 1)
	)
	(segment
		(start 103.349501 172.361)
		(end 104.38 172.361)
		(width 0.15)
		(layer "F.Cu")
		(net 1)
	)
	(segment
		(start 173.575001 131.1025)
		(end 173.575 128.425)
		(width 0.4)
		(layer "F.Cu")
		(net 1)
	)
	(segment
		(start 100.400501 156.942851)
		(end 100.837352 156.942851)
		(width 0.256)
		(layer "F.Cu")
		(net 1)
	)
	(segment
		(start 92.7 197.849)
		(end 91.95 197.849)
		(width 0.201)
		(layer "F.Cu")
		(net 1)
	)
	(segment
		(start 185 166.2)
		(end 184.7 166.5)
		(width 0.256)
		(layer "F.Cu")
		(net 1)
	)
	(segment
		(start 155.650001 137.9265)
		(end 155.399501 137.676)
		(width 0.201)
		(layer "F.Cu")
		(net 1)
	)
	(segment
		(start 179.05 190.3)
		(end 179.15 190.4)
		(width 0.25)
		(layer "F.Cu")
		(net 1)
	)
	(segment
		(start 195.375 141.877)
		(end 195.5515 142.0535)
		(width 0.256)
		(layer "F.Cu")
		(net 1)
	)
	(segment
		(start 203.75 139.65)
		(end 203.749999 140.672001)
		(width 0.4)
		(layer "F.Cu")
		(net 1)
	)
	(segment
		(start 90.690501 177.082)
		(end 90.683501 177.089)
		(width 0.256)
		(layer "F.Cu")
		(net 1)
	)
	(segment
		(start 92.802501 158.285)
		(end 92.802501 159.624)
		(width 0.256)
		(layer "F.Cu")
		(net 1)
	)
	(segment
		(start 139.375501 186.301)
		(end 139.875001 186.800501)
		(width 0.256)
		(layer "F.Cu")
		(net 1)
	)
	(segment
		(start 119.150001 138.8025)
		(end 119.150001 137.7275)
		(width 0.201)
		(layer "F.Cu")
		(net 1)
	)
	(segment
		(start 87.391829 157.953859)
		(end 85.762531 157.953859)
		(width 0.2)
		(layer "F.Cu")
		(net 1)
	)
	(segment
		(start 96.575 183.184)
		(end 97.209 183.184)
		(width 0.15)
		(layer "F.Cu")
		(net 1)
	)
	(segment
		(start 170.150001 138.8025)
		(end 170.150001 137.727499)
		(width 0.201)
		(layer "F.Cu")
		(net 1)
	)
	(segment
		(start 92.05 181.45)
		(end 91.75 181.15)
		(width 0.256)
		(layer "F.Cu")
		(net 1)
	)
	(segment
		(start 182.140107 182.779)
		(end 182.037107 182.676)
		(width 0.256)
		(layer "F.Cu")
		(net 1)
	)
	(segment
		(start 149.375501 166.302)
		(end 149.875001 165.8025)
		(width 0.256)
		(layer "F.Cu")
		(net 1)
	)
	(segment
		(start 91.689001 170.3525)
		(end 91.689001 171.051)
		(width 0.256)
		(layer "F.Cu")
		(net 1)
	)
	(segment
		(start 109.400001 146.2025)
		(end 109.400001 145.1275)
		(width 0.201)
		(layer "F.Cu")
		(net 1)
	)
	(segment
		(start 132.150001 138.8025)
		(end 132.150001 137.7275)
		(width 0.201)
		(layer "F.Cu")
		(net 1)
	)
	(segment
		(start 191.43 142.23)
		(end 191.55 142.35)
		(width 0.201)
		(layer "F.Cu")
		(net 1)
	)
	(segment
		(start 97.272344 166.455843)
		(end 97.271658 166.455157)
		(width 0.256)
		(layer "F.Cu")
		(net 1)
	)
	(segment
		(start 145.375501 187.301)
		(end 145.875001 187.8005)
		(width 0.256)
		(layer "F.Cu")
		(net 1)
	)
	(segment
		(start 78.244501 187.316)
		(end 79.979501 187.316)
		(width 0.201)
		(layer "F.Cu")
		(net 1)
	)
	(segment
		(start 74.420501 164.236)
		(end 74.091501 164.565)
		(width 0.4)
		(layer "F.Cu")
		(net 1)
	)
	(segment
		(start 96.301 197.849)
		(end 95.551 197.849)
		(width 0.201)
		(layer "F.Cu")
		(net 1)
	)
	(segment
		(start 149.400001 146.2025)
		(end 149.400001 145.3265)
		(width 0.201)
		(layer "F.Cu")
		(net 1)
	)
	(segment
		(start 99.827658 166.413157)
		(end 99.827658 167.038642)
		(width 0.256)
		(layer "F.Cu")
		(net 1)
	)
	(segment
		(start 113.150001 138.8025)
		(end 113.150001 137.7275)
		(width 0.201)
		(layer "F.Cu")
		(net 1)
	)
	(segment
		(start 203.749999 140.672001)
		(end 203.751498 140.673501)
		(width 0.4)
		(layer "F.Cu")
		(net 1)
	)
	(segment
		(start 101.500501 156.942851)
		(end 102.600501 156.942851)
		(width 0.256)
		(layer "F.Cu")
		(net 1)
	)
	(segment
		(start 101.07365 156.942851)
		(end 100.960501 157.056)
		(width 0.256)
		(layer "F.Cu")
		(net 1)
	)
	(segment
		(start 160.400001 146.2025)
		(end 160.400001 145.1275)
		(width 0.201)
		(layer "F.Cu")
		(net 1)
	)
	(segment
		(start 105.951344 177.267328)
		(end 105.951344 177.872329)
		(width 0.256)
		(layer "F.Cu")
		(net 1)
	)
	(segment
		(start 182.153608 164.356694)
		(end 182.140108 164.370194)
		(width 0.256)
		(layer "F.Cu")
		(net 1)
	)
	(segment
		(start 91.689001 176.519)
		(end 91.689001 177.0685)
		(width 0.256)
		(layer "F.Cu")
		(net 1)
	)
	(segment
		(start 177.945999 192.230502)
		(end 176.119502 192.230502)
		(width 0.256)
		(layer "F.Cu")
		(net 1)
	)
	(segment
		(start 166.085501 180.675)
		(end 166.115501 180.705)
		(width 0.201)
		(layer "F.Cu")
		(net 1)
	)
	(segment
		(start 101.375251 160.2955)
		(end 101.384501 160.28625)
		(width 0.256)
		(layer "F.Cu")
		(net 1)
	)
	(segment
		(start 193.753499 135.6)
		(end 193.863499 135.49)
		(width 0.4)
		(layer "F.Cu")
		(net 1)
	)
	(segment
		(start 104.499501 154.375)
		(end 104.510501 154.386)
		(width 0.256)
		(layer "F.Cu")
		(net 1)
	)
	(segment
		(start 189.79 139.385)
		(end 189.775 139.4)
		(width 0.256)
		(layer "F.Cu")
		(net 1)
	)
	(segment
		(start 194.15 193.56)
		(end 194.635 193.075)
		(width 0.4)
		(layer "F.Cu")
		(net 1)
	)
	(segment
		(start 97.209 183.184)
		(end 97.225 183.2)
		(width 0.15)
		(layer "F.Cu")
		(net 1)
	)
	(segment
		(start 140.3755 174.302)
		(end 140.875001 173.8025)
		(width 0.256)
		(layer "F.Cu")
		(net 1)
	)
	(segment
		(start 116.651501 176.925)
		(end 116.150501 177.426)
		(width 0.4)
		(layer "F.Cu")
		(net 1)
	)
	(segment
		(start 138.376501 171.302001)
		(end 137.877001 170.8025)
		(width 0.256)
		(layer "F.Cu")
		(net 1)
	)
	(segment
		(start 105.151001 180.435)
		(end 105.151 179.585)
		(width 0.15)
		(layer "F.Cu")
		(net 1)
	)
	(segment
		(start 137.376501 170.302)
		(end 136.877001 169.8025)
		(width 0.256)
		(layer "F.Cu")
		(net 1)
	)
	(segment
		(start 199.203499 136.54)
		(end 199.213499 136.55)
		(width 0.256)
		(layer "F.Cu")
		(net 1)
	)
	(segment
		(start 174.894 178.4)
		(end 172.928 178.4)
		(width 0.256)
		(layer "F.Cu")
		(net 1)
	)
	(segment
		(start 164.715 174.2)
		(end 165.487 174.2)
		(width 0.256)
		(layer "F.Cu")
		(net 1)
	)
	(segment
		(start 147.3755 185.301)
		(end 147.875001 185.8005)
		(width 0.256)
		(layer "F.Cu")
		(net 1)
	)
	(segment
		(start 184.394759 131.020099)
		(end 184.507759 130.907099)
		(width 0.256)
		(layer "F.Cu")
		(net 1)
	)
	(segment
		(start 141.525501 206.950001)
		(end 141.525501 210.801)
		(width 0.22)
		(layer "F.Cu")
		(net 1)
	)
	(segment
		(start 120.45 194.7)
		(end 121 195.25)
		(width 0.4)
		(layer "F.Cu")
		(net 1)
	)
	(segment
		(start 101.384501 157.958851)
		(end 101.384501 158.958851)
		(width 0.256)
		(layer "F.Cu")
		(net 1)
	)
	(segment
		(start 184.394759 132.1071)
		(end 184.394759 131.020099)
		(width 0.256)
		(layer "F.Cu")
		(net 1)
	)
	(segment
		(start 194.15 193.56)
		(end 194.15 194.3)
		(width 0.4)
		(layer "F.Cu")
		(net 1)
	)
	(segment
		(start 105.975001 131.1025)
		(end 103.852503 131.1025)
		(width 0.4)
		(layer "F.Cu")
		(net 1)
	)
	(segment
		(start 175.6975 131.1025)
		(end 175.7 131.1)
		(width 0.4)
		(layer "F.Cu")
		(net 1)
	)
	(segment
		(start 93.551 197.849)
		(end 93.5 197.9)
		(width 0.201)
		(layer "F.Cu")
		(net 1)
	)
	(segment
		(start 102.6 181.15)
		(end 102.8 180.95)
		(width 0.15)
		(layer "F.Cu")
		(net 1)
	)
	(segment
		(start 179.35 190.875)
		(end 179.375 190.9)
		(width 0.25)
		(layer "F.Cu")
		(net 1)
	)
	(segment
		(start 82.723038 164.316)
		(end 80.988501 164.316)
		(width 0.4)
		(layer "F.Cu")
		(net 1)
	)
	(segment
		(start 174.894 172.401)
		(end 172.928 172.401)
		(width 0.256)
		(layer "F.Cu")
		(net 1)
	)
	(segment
		(start 126.650001 138.8025)
		(end 126.650001 137.7275)
		(width 0.201)
		(layer "F.Cu")
		(net 1)
	)
	(segment
		(start 147.65 138.8025)
		(end 147.65 137.7275)
		(width 0.201)
		(layer "F.Cu")
		(net 1)
	)
	(segment
		(start 160.650002 138.8025)
		(end 160.650002 137.7275)
		(width 0.201)
		(layer "F.Cu")
		(net 1)
	)
	(segment
		(start 179.05 190.211)
		(end 179.05 190.3)
		(width 0.25)
		(layer "F.Cu")
		(net 1)
	)
	(segment
		(start 128.376501 183.301)
		(end 127.877001 183.8005)
		(width 0.256)
		(layer "F.Cu")
		(net 1)
	)
	(segment
		(start 159.4025 178.675)
		(end 159.3835 178.694)
		(width 0.201)
		(layer "F.Cu")
		(net 1)
	)
	(segment
		(start 136.525501 206.925501)
		(end 136.525501 210.801)
		(width 0.22)
		(layer "F.Cu")
		(net 1)
	)
	(segment
		(start 135.376502 174.302)
		(end 134.877001 173.8025)
		(width 0.256)
		(layer "F.Cu")
		(net 1)
	)
	(segment
		(start 107.81 180.184)
		(end 107.826 180.2)
		(width 0.15)
		(layer "F.Cu")
		(net 1)
	)
	(segment
		(start 108.650001 138.8025)
		(end 108.650001 137.7275)
		(width 0.201)
		(layer "F.Cu")
		(net 1)
	)
	(segment
		(start 156.9 146.2025)
		(end 156.9 145.1275)
		(width 0.201)
		(layer "F.Cu")
		(net 1)
	)
	(segment
		(start 195.15 194.85)
		(end 194.175 194.85)
		(width 0.4)
		(layer "F.Cu")
		(net 1)
	)
	(segment
		(start 100.837352 156.942851)
		(end 100.960501 157.066)
		(width 0.256)
		(layer "F.Cu")
		(net 1)
	)
	(segment
		(start 105.952344 173.767328)
		(end 105.952344 173.162328)
		(width 0.256)
		(layer "F.Cu")
		(net 1)
	)
	(segment
		(start 97.9 181.084)
		(end 97.816 181.084)
		(width 0.256)
		(layer "F.Cu")
		(net 1)
	)
	(segment
		(start 148.375501 182.301)
		(end 148.875001 182.800499)
		(width 0.256)
		(layer "F.Cu")
		(net 1)
	)
	(segment
		(start 90.567344 173.382328)
		(end 89.882344 173.382328)
		(width 0.256)
		(layer "F.Cu")
		(net 1)
	)
	(segment
		(start 136.000501 206.400501)
		(end 136.525501 206.925501)
		(width 0.22)
		(layer "F.Cu")
		(net 1)
	)
	(segment
		(start 152.15 138.8025)
		(end 152.15 139.8775)
		(width 0.201)
		(layer "F.Cu")
		(net 1)
	)
	(segment
		(start 113.400001 146.2025)
		(end 113.400001 145.1275)
		(width 0.201)
		(layer "F.Cu")
		(net 1)
	)
	(segment
		(start 78.149 152.151)
		(end 78.149 151.55)
		(width 0.4)
		(layer "F.Cu")
		(net 1)
	)
	(segment
		(start 101.616501 167.061)
		(end 100.930016 167.061)
		(width 0.256)
		(layer "F.Cu")
		(net 1)
	)
	(segment
		(start 179.511 198.807)
		(end 179.505 198.813)
		(width 0.177)
		(layer "F.Cu")
		(net 1)
	)
	(segment
		(start 204.774 142.749999)
		(end 204.775499 142.748499)
		(width 0.4)
		(layer "F.Cu")
		(net 1)
	)
	(segment
		(start 83.684 182.416)
		(end 83.7 182.4)
		(width 0.4)
		(layer "F.Cu")
		(net 1)
	)
	(segment
		(start 135.376502 164.302)
		(end 134.877001 163.8025)
		(width 0.256)
		(layer "F.Cu")
		(net 1)
	)
	(segment
		(start 116.150001 138.8025)
		(end 116.150001 137.7275)
		(width 0.201)
		(layer "F.Cu")
		(net 1)
	)
	(segment
		(start 122.6495 179.995499)
		(end 123.634999 179.995499)
		(width 0.256)
		(layer "F.Cu")
		(net 1)
	)
	(segment
		(start 153.150001 138.8025)
		(end 153.150001 139.877498)
		(width 0.201)
		(layer "F.Cu")
		(net 1)
	)
	(segment
		(start 95.400501 130.3)
		(end 95.400501 130.999499)
		(width 0.15)
		(layer "F.Cu")
		(net 1)
	)
	(segment
		(start 95.896 192.998)
		(end 95.896 193.196)
		(width 0.201)
		(layer "F.Cu")
		(net 1)
	)
	(segment
		(start 103.152 181.435)
		(end 104.401 181.435)
		(width 0.15)
		(layer "F.Cu")
		(net 1)
	)
	(segment
		(start 157.650002 138.8025)
		(end 157.650002 137.7275)
		(width 0.201)
		(layer "F.Cu")
		(net 1)
	)
	(segment
		(start 102.514016 171.634)
		(end 103.113501 171.634)
		(width 0.15)
		(layer "F.Cu")
		(net 1)
	)
	(segment
		(start 182.65 190.2)
		(end 183.001 190.2)
		(width 0.177)
		(layer "F.Cu")
		(net 1)
	)
	(segment
		(start 184.636 184.664)
		(end 183.851107 184.664)
		(width 0.256)
		(layer "F.Cu")
		(net 1)
	)
	(segment
		(start 150.900001 146.2025)
		(end 150.900001 145.3265)
		(width 0.201)
		(layer "F.Cu")
		(net 1)
	)
	(segment
		(start 133.376501 178.301)
		(end 132.877001 178.8005)
		(width 0.256)
		(layer "F.Cu")
		(net 1)
	)
	(segment
		(start 85.185 168.5)
		(end 84.413 168.5)
		(width 0.256)
		(layer "F.Cu")
		(net 1)
	)
	(segment
		(start 183.604107 181.805)
		(end 183.604107 181.1755)
		(width 0.256)
		(layer "F.Cu")
		(net 1)
	)
	(segment
		(start 142.075001 206.400501)
		(end 141.525501 206.950001)
		(width 0.22)
		(layer "F.Cu")
		(net 1)
	)
	(segment
		(start 164.451501 177.979999)
		(end 164.432501 177.960999)
		(width 0.201)
		(layer "F.Cu")
		(net 1)
	)
	(segment
		(start 82.723038 179.816)
		(end 80.988501 179.816)
		(width 0.4)
		(layer "F.Cu")
		(net 1)
	)
	(segment
		(start 104.38 176.061)
		(end 104.219 176.061)
		(width 0.15)
		(layer "F.Cu")
		(net 1)
	)
	(segment
		(start 128.376501 173.302)
		(end 127.877001 172.8025)
		(width 0.256)
		(layer "F.Cu")
		(net 1)
	)
	(segment
		(start 198.714499 146.801)
		(end 197.668 146.801)
		(width 0.198)
		(layer "F.Cu")
		(net 1)
	)
	(segment
		(start 174.894 174.4)
		(end 172.928 174.4)
		(width 0.256)
		(layer "F.Cu")
		(net 1)
	)
	(segment
		(start 148.375501 172.302)
		(end 148.875001 171.8025)
		(width 0.256)
		(layer "F.Cu")
		(net 1)
	)
	(segment
		(start 180.011 190.211)
		(end 179.05 190.211)
		(width 0.25)
		(layer "F.Cu")
		(net 1)
	)
	(segment
		(start 95.100501 123.876)
		(end 95.100501 124.606)
		(width 0.15)
		(layer "F.Cu")
		(net 1)
	)
	(segment
		(start 103.325501 172.385)
		(end 103.349501 172.361)
		(width 0.15)
		(layer "F.Cu")
		(net 1)
	)
	(segment
		(start 83.631 151.1)
		(end 79.649 151.1)
		(width 0.4)
		(layer "F.Cu")
		(net 1)
	)
	(segment
		(start 203.75 135.552)
		(end 203.749999 134.529999)
		(width 0.4)
		(layer "F.Cu")
		(net 1)
	)
	(segment
		(start 191.594 139.595)
		(end 191.449 139.45)
		(width 0.256)
		(layer "F.Cu")
		(net 1)
	)
	(segment
		(start 183.137108 164.117999)
		(end 183.604107 163.651)
		(width 0.256)
		(layer "F.Cu")
		(net 1)
	)
	(segment
		(start 100.808501 169.8335)
		(end 100.536501 169.5615)
		(width 0.15)
		(layer "F.Cu")
		(net 1)
	)
	(segment
		(start 132.376501 175.301)
		(end 131.877001 175.8005)
		(width 0.256)
		(layer "F.Cu")
		(net 1)
	)
	(segment
		(start 123.900001 146.2025)
		(end 123.900001 145.1275)
		(width 0.201)
		(layer "F.Cu")
		(net 1)
	)
	(segment
		(start 174.8955 172.3995)
		(end 174.894 172.401)
		(width 0.256)
		(layer "F.Cu")
		(net 1)
	)
	(segment
		(start 146.978001 206.400501)
		(end 147.525501 206.948001)
		(width 0.22)
		(layer "F.Cu")
		(net 1)
	)
	(segment
		(start 142.375501 177.301)
		(end 142.875001 177.8005)
		(width 0.256)
		(layer "F.Cu")
		(net 1)
	)
	(segment
		(start 174.8955 178.3985)
		(end 174.894 178.4)
		(width 0.256)
		(layer "F.Cu")
		(net 1)
	)
	(segment
		(start 150.15 138.8025)
		(end 150.15 139.8775)
		(width 0.201)
		(layer "F.Cu")
		(net 1)
	)
	(segment
		(start 100.400501 156.942851)
		(end 101.500501 156.942851)
		(width 0.256)
		(layer "F.Cu")
		(net 1)
	)
	(segment
		(start 101.500501 156.942851)
		(end 101.07365 156.942851)
		(width 0.256)
		(layer "F.Cu")
		(net 1)
	)
	(segment
		(start 94.059829 167.063157)
		(end 94.059829 166.467585)
		(width 0.256)
		(layer "F.Cu")
		(net 1)
	)
	(segment
		(start 94.059829 165.647157)
		(end 92.926344 165.647157)
		(width 0.15)
		(layer "F.Cu")
		(net 1)
	)
	(segment
		(start 142.375501 165.302)
		(end 142.875001 164.8025)
		(width 0.256)
		(layer "F.Cu")
		(net 1)
	)
	(segment
		(start 100.960501 157.066)
		(end 100.960501 157.356)
		(width 0.256)
		(layer "F.Cu")
		(net 1)
	)
	(segment
		(start 183.444759 132.1071)
		(end 183.444759 131.420258)
		(width 0.256)
		(layer "F.Cu")
		(net 1)
	)
	(segment
		(start 130.376501 179.301)
		(end 129.877 179.8005)
		(width 0.256)
		(layer "F.Cu")
		(net 1)
	)
	(segment
		(start 118.650501 172.926)
		(end 118.150501 173.426)
		(width 0.4)
		(layer "F.Cu")
		(net 1)
	)
	(segment
		(start 120.45 191.7)
		(end 120.45 191.65)
		(width 0.4)
		(layer "F.Cu")
		(net 1)
	)
	(segment
		(start 97.272344 167.068328)
		(end 97.272344 166.455843)
		(width 0.256)
		(layer "F.Cu")
		(net 1)
	)
	(segment
		(start 145.375501 175.301)
		(end 145.875001 175.8005)
		(width 0.256)
		(layer "F.Cu")
		(net 1)
	)
	(segment
		(start 160.097501 178.675)
		(end 160.097501 177.979999)
		(width 0.201)
		(layer "F.Cu")
		(net 1)
	)
	(segment
		(start 179.98814 166.2)
		(end 180.288141 166.500001)
		(width 0.256)
		(layer "F.Cu")
		(net 1)
	)
	(segment
		(start 175.085501 193.214501)
		(end 176.070502 192.229502)
		(width 0.177)
		(layer "F.Cu")
		(net 1)
	)
	(segment
		(start 134.376501 171.302)
		(end 133.877001 170.8025)
		(width 0.256)
		(layer "F.Cu")
		(net 1)
	)
	(segment
		(start 159.4545 182.674)
		(end 159.4355 182.693)
		(width 0.201)
		(layer "F.Cu")
		(net 1)
	)
	(segment
		(start 190.61 139.45)
		(end 190.545 139.385)
		(width 0.256)
		(layer "F.Cu")
		(net 1)
	)
	(segment
		(start 127.376501 170.302)
		(end 126.877001 169.802499)
		(width 0.256)
		(layer "F.Cu")
		(net 1)
	)
	(segment
		(start 83.649 151.118)
		(end 83.649 151.651)
		(width 0.4)
		(layer "F.Cu")
		(net 1)
	)
	(segment
		(start 78.149 151.55)
		(end 78.599 151.1)
		(width 0.4)
		(layer "F.Cu")
		(net 1)
	)
	(segment
		(start 87.3995 184.9005)
		(end 87.4 184.9)
		(width 0.256)
		(layer "F.Cu")
		(net 1)
	)
	(segment
		(start 142.375501 171.302001)
		(end 142.875001 170.8025)
		(width 0.256)
		(layer "F.Cu")
		(net 1)
	)
	(segment
		(start 91.686501 170.35)
		(end 91.689001 170.3525)
		(width 0.256)
		(layer "F.Cu")
		(net 1)
	)
	(segment
		(start 136.376501 177.301)
		(end 135.877002 177.8005)
		(width 0.256)
		(layer "F.Cu")
		(net 1)
	)
	(segment
		(start 164.451501 178.675)
		(end 164.451501 177.979999)
		(width 0.201)
		(layer "F.Cu")
		(net 1)
	)
	(segment
		(start 139.375502 178.301)
		(end 139.875001 178.8005)
		(width 0.256)
		(layer "F.Cu")
		(net 1)
	)
	(segment
		(start 164.451501 178.675)
		(end 165.146502 178.675)
		(width 0.201)
		(layer "F.Cu")
		(net 1)
	)
	(segment
		(start 147.3755 175.301)
		(end 147.875001 175.8005)
		(width 0.256)
		(layer "F.Cu")
		(net 1)
	)
	(segment
		(start 151.375501 172.301999)
		(end 151.875001 171.8025)
		(width 0.256)
		(layer "F.Cu")
		(net 1)
	)
	(segment
		(start 172.150001 138.8025)
		(end 172.150001 137.7275)
		(width 0.201)
		(layer "F.Cu")
		(net 1)
	)
	(segment
		(start 78.185 153.285)
		(end 78.7 153.8)
		(width 0.15)
		(layer "F.Cu")
		(net 1)
	)
	(segment
		(start 197.668 146.801)
		(end 197.615 146.854)
		(width 0.198)
		(layer "F.Cu")
		(net 1)
	)
	(segment
		(start 92.401 181.45)
		(end 93.65 181.45)
		(width 0.256)
		(layer "F.Cu")
		(net 1)
	)
	(segment
		(start 78.087 155.3)
		(end 78.7 155.3)
		(width 0.201)
		(layer "F.Cu")
		(net 1)
	)
	(segment
		(start 190.455 142.165)
		(end 190.52 142.23)
		(width 0.256)
		(layer "F.Cu")
		(net 1)
	)
	(segment
		(start 127.400001 146.2025)
		(end 127.400001 145.1275)
		(width 0.201)
		(layer "F.Cu")
		(net 1)
	)
	(segment
		(start 128.525501 206.925501)
		(end 128.525501 210.801)
		(width 0.22)
		(layer "F.Cu")
		(net 1)
	)
	(segment
		(start 144.375501 173.302001)
		(end 144.875001 172.8025)
		(width 0.256)
		(layer "F.Cu")
		(net 1)
	)
	(segment
		(start 198.9565 157.8015)
		(end 198.955 157.803)
		(width 0.4)
		(layer "F.Cu")
		(net 1)
	)
	(segment
		(start 134.150001 138.8025)
		(end 134.150001 137.7275)
		(width 0.201)
		(layer "F.Cu")
		(net 1)
	)
	(segment
		(start 183.604108 163.0255)
		(end 183.607608 163.021999)
		(width 0.256)
		(layer "F.Cu")
		(net 1)
	)
	(segment
		(start 129.376501 166.302)
		(end 128.877001 165.8025)
		(width 0.256)
		(layer "F.Cu")
		(net 1)
	)
	(segment
		(start 171.900001 146.2025)
		(end 171.900001 145.1275)
		(width 0.201)
		(layer "F.Cu")
		(net 1)
	)
	(segment
		(start 99.827658 167.038642)
		(end 99.847344 167.058328)
		(width 0.256)
		(layer "F.Cu")
		(net 1)
	)
	(segment
		(start 82.9995 181.8005)
		(end 83 181.8)
		(width 0.4)
		(layer "F.Cu")
		(net 1)
	)
	(segment
		(start 181.082 155.099999)
		(end 181.082 155.740998)
		(width 0.256)
		(layer "F.Cu")
		(net 1)
	)
	(segment
		(start 104.499501 153.507851)
		(end 104.499501 154.375)
		(width 0.256)
		(layer "F.Cu")
		(net 1)
	)
	(segment
		(start 173.575001 131.1025)
		(end 173.575002 133.78)
		(width 0.4)
		(layer "F.Cu")
		(net 1)
	)
	(segment
		(start 151.375501 177.301)
		(end 151.875001 177.8005)
		(width 0.256)
		(layer "F.Cu")
		(net 1)
	)
	(segment
		(start 148.375501 176.301)
		(end 148.875001 176.8005)
		(width 0.256)
		(layer "F.Cu")
		(net 1)
	)
	(segment
		(start 174.7205 193.214501)
		(end 175.085501 193.214501)
		(width 0.177)
		(layer "F.Cu")
		(net 1)
	)
	(segment
		(start 147.525501 206.948001)
		(end 147.525501 210.801)
		(width 0.22)
		(layer "F.Cu")
		(net 1)
	)
	(segment
		(start 139.375501 176.301)
		(end 139.875001 176.8005)
		(width 0.256)
		(layer "F.Cu")
		(net 1)
	)
	(segment
		(start 154.9 146.2025)
		(end 154.9 145.127499)
		(width 0.201)
		(layer "F.Cu")
		(net 1)
	)
	(segment
		(start 86.711001 184.9005)
		(end 87.3995 184.9005)
		(width 0.256)
		(layer "F.Cu")
		(net 1)
	)
	(segment
		(start 190.545 139.385)
		(end 189.79 139.385)
		(width 0.256)
		(layer "F.Cu")
		(net 1)
	)
	(segment
		(start 142.375501 173.302)
		(end 142.875001 172.8025)
		(width 0.256)
		(layer "F.Cu")
		(net 1)
	)
	(segment
		(start 143.150001 138.8025)
		(end 143.15 139.8775)
		(width 0.201)
		(layer "F.Cu")
		(net 1)
	)
	(segment
		(start 184.15 192.416)
		(end 183.516 192.416)
		(width 0.256)
		(layer "F.Cu")
		(net 1)
	)
	(segment
		(start 151.15 138.8025)
		(end 151.15 139.8775)
		(width 0.201)
		(layer "F.Cu")
		(net 1)
	)
	(segment
		(start 94.301 197.849)
		(end 93.551 197.849)
		(width 0.201)
		(layer "F.Cu")
		(net 1)
	)
	(segment
		(start 145.375501 185.301)
		(end 145.875001 185.8005)
		(width 0.256)
		(layer "F.Cu")
		(net 1)
	)
	(segment
		(start 116.15 191.7)
		(end 116.1 191.7)
		(width 0.4)
		(layer "F.Cu")
		(net 1)
	)
	(segment
		(start 97.901 197.849)
		(end 97.151 197.849)
		(width 0.201)
		(layer "F.Cu")
		(net 1)
	)
	(segment
		(start 182.541 150.2)
		(end 182.541 150.157)
		(width 0.256)
		(layer "F.Cu")
		(net 1)
	)
	(segment
		(start 145.375501 176.301)
		(end 145.875001 176.8005)
		(width 0.256)
		(layer "F.Cu")
		(net 1)
	)
	(segment
		(start 147.375501 179.301)
		(end 147.875001 179.8005)
		(width 0.256)
		(layer "F.Cu")
		(net 1)
	)
	(segment
		(start 141.375501 162.302)
		(end 141.875001 161.8025)
		(width 0.256)
		(layer "F.Cu")
		(net 1)
	)
	(segment
		(start 191.449 139.45)
		(end 190.61 139.45)
		(width 0.256)
		(layer "F.Cu")
		(net 1)
	)
	(segment
		(start 179.15 190.4)
		(end 179.15 190.7)
		(width 0.25)
		(layer "F.Cu")
		(net 1)
	)
	(segment
		(start 158.650002 138.8025)
		(end 158.650003 137.727499)
		(width 0.201)
		(layer "F.Cu")
		(net 1)
	)
	(segment
		(start 181.082 154.05)
		(end 181.082 153.409001)
		(width 0.256)
		(layer "F.Cu")
		(net 1)
	)
	(segment
		(start 105.975001 131.1025)
		(end 105.975 128.425)
		(width 0.4)
		(layer "F.Cu")
		(net 1)
	)
	(segment
		(start 194.15 195.35)
		(end 194.15 197.55)
		(width 0.256)
		(layer "F.Cu")
		(net 1)
	)
	(segment
		(start 94.621501 175.635)
		(end 93.820501 175.635)
		(width 0.15)
		(layer "F.Cu")
		(net 1)
	)
	(segment
		(start 147.375501 181.301)
		(end 147.875001 181.8005)
		(width 0.256)
		(layer "F.Cu")
		(net 1)
	)
	(segment
		(start 90.690501 171.052)
		(end 90.690501 170.609499)
		(width 0.256)
		(layer "F.Cu")
		(net 1)
	)
	(segment
		(start 135.376501 184.301)
		(end 134.877001 184.8005)
		(width 0.256)
		(layer "F.Cu")
		(net 1)
	)
	(segment
		(start 82.9995 182.416)
		(end 82.9995 181.8005)
		(width 0.4)
		(layer "F.Cu")
		(net 1)
	)
	(segment
		(start 164.400001 146.2025)
		(end 164.400001 145.127499)
		(width 0.201)
		(layer "F.Cu")
		(net 1)
	)
	(segment
		(start 138.376501 173.302)
		(end 137.877001 172.8025)
		(width 0.256)
		(layer "F.Cu")
		(net 1)
	)
	(segment
		(start 110.650001 138.8025)
		(end 110.650001 137.7275)
		(width 0.201)
		(layer "F.Cu")
		(net 1)
	)
	(segment
		(start 150.375501 183.301)
		(end 151.375501 183.301)
		(width 0.256)
		(layer "F.Cu")
		(net 1)
	)
	(segment
		(start 174.8865 170.4485)
		(end 172.9205 170.4485)
		(width 0.256)
		(layer "F.Cu")
		(net 1)
	)
	(segment
		(start 145.375501 164.302)
		(end 145.875001 163.8025)
		(width 0.256)
		(layer "F.Cu")
		(net 1)
	)
	(segment
		(start 181.225 151.875)
		(end 182.541 151.875)
		(width 0.4)
		(layer "F.Cu")
		(net 1)
	)
	(segment
		(start 167.400001 146.2025)
		(end 167.400002 145.127499)
		(width 0.201)
		(layer "F.Cu")
		(net 1)
	)
	(segment
		(start 165.400002 146.2025)
		(end 165.400001 145.1275)
		(width 0.201)
		(layer "F.Cu")
		(net 1)
	)
	(segment
		(start 205.2985 148.8035)
		(end 205.299998 148.802)
		(width 0.4)
		(layer "F.Cu")
		(net 1)
	)
	(segment
		(start 93.65 181.45)
		(end 93.9 181.7)
		(width 0.256)
		(layer "F.Cu")
		(net 1)
	)
	(segment
		(start 116.900001 146.2025)
		(end 116.900001 145.1275)
		(width 0.201)
		(layer "F.Cu")
		(net 1)
	)
	(segment
		(start 141.375501 173.302)
		(end 141.875001 172.8025)
		(width 0.256)
		(layer "F.Cu")
		(net 1)
	)
	(segment
		(start 126.376501 177.301)
		(end 125.877001 177.8005)
		(width 0.256)
		(layer "F.Cu")
		(net 1)
	)
	(segment
		(start 133.000501 206.375501)
		(end 133.525501 206.900501)
		(width 0.22)
		(layer "F.Cu")
		(net 1)
	)
	(segment
		(start 174.8955 176.3985)
		(end 174.894 176.4)
		(width 0.256)
		(layer "F.Cu")
		(net 1)
	)
	(segment
		(start 137.376501 176.301)
		(end 136.877001 176.8005)
		(width 0.256)
		(layer "F.Cu")
		(net 1)
	)
	(segment
		(start 151.375501 181.301)
		(end 151.376501 181.3)
		(width 0.256)
		(layer "F.Cu")
		(net 1)
	)
	(segment
		(start 173.575001 131.1025)
		(end 175.6975 131.1025)
		(width 0.4)
		(layer "F.Cu")
		(net 1)
	)
	(segment
		(start 165.146501 182.674)
		(end 165.165501 182.655)
		(width 0.201)
		(layer "F.Cu")
		(net 1)
	)
	(segment
		(start 83.649 151.651)
		(end 83.6 151.7)
		(width 0.4)
		(layer "F.Cu")
		(net 1)
	)
	(segment
		(start 137.376501 174.302)
		(end 136.877001 173.8025)
		(width 0.256)
		(layer "F.Cu")
		(net 1)
	)
	(segment
		(start 157.9 146.2025)
		(end 157.900001 145.127499)
		(width 0.201)
		(layer "F.Cu")
		(net 1)
	)
	(segment
		(start 135.400001 146.2025)
		(end 135.400001 145.1275)
		(width 0.201)
		(layer "F.Cu")
		(net 1)
	)
	(segment
		(start 107.91 183.202)
		(end 107.926 183.218)
		(width 0.15)
		(layer "F.Cu")
		(net 1)
	)
	(segment
		(start 174.888 170.447)
		(end 174.8865 170.4485)
		(width 0.256)
		(layer "F.Cu")
		(net 1)
	)
	(segment
		(start 89.523501 167.298743)
		(end 89.527244 167.295)
		(width 0.15)
		(layer "F.Cu")
		(net 1)
	)
	(segment
		(start 165.146502 178.675)
		(end 165.165502 178.656)
		(width 0.201)
		(layer "F.Cu")
		(net 1)
	)
	(segment
		(start 124.650001 138.8025)
		(end 124.650001 137.7275)
		(width 0.201)
		(layer "F.Cu")
		(net 1)
	)
	(segment
		(start 165.249501 180.675)
		(end 166.085501 180.675)
		(width 0.201)
		(layer "F.Cu")
		(net 1)
	)
	(segment
		(start 179.511 195.057)
		(end 179.505 195.063)
		(width 0.177)
		(layer "F.Cu")
		(net 1)
	)
	(segment
		(start 76.109501 152.114)
		(end 76.723501 151.5)
		(width 0.4)
		(layer "F.Cu")
		(net 1)
	)
	(segment
		(start 165.249501 179.675)
		(end 165.935501 179.675)
		(width 0.201)
		(layer "F.Cu")
		(net 1)
	)
	(segment
		(start 103.516501 150.158851)
		(end 103.37765 150.158851)
		(width 0.256)
		(layer "F.Cu")
		(net 1)
	)
	(segment
		(start 137.525501 206.925501)
		(end 137.525501 210.801)
		(width 0.22)
		(layer "F.Cu")
		(net 1)
	)
	(segment
		(start 161.099 172.3)
		(end 160.7005 171.9015)
		(width 0.4)
		(layer "F.Cu")
		(net 1)
	)
	(segment
		(start 131.400001 146.2025)
		(end 131.400001 145.1275)
		(width 0.201)
		(layer "F.Cu")
		(net 1)
	)
	(segment
		(start 194.635 193.075)
		(end 194.666 193.075)
		(width 0.4)
		(layer "F.Cu")
		(net 1)
	)
	(segment
		(start 82.073501 169.2)
		(end 82.039501 169.166)
		(width 0.256)
		(layer "F.Cu")
		(net 1)
	)
	(segment
		(start 143.375501 178.301)
		(end 143.875001 178.8005)
		(width 0.256)
		(layer "F.Cu")
		(net 1)
	)
	(segment
		(start 104.09 176.19)
		(end 104.09 176.55)
		(width 0.15)
		(layer "F.Cu")
		(net 1)
	)
	(segment
		(start 184.15 196.166)
		(end 183.516 196.166)
		(width 0.256)
		(layer "F.Cu")
		(net 1)
	)
	(segment
		(start 140.3755 169.302)
		(end 140.875001 168.8025)
		(width 0.256)
		(layer "F.Cu")
		(net 1)
	)
	(segment
		(start 172.900001 146.2025)
		(end 172.900001 145.1275)
		(width 0.201)
		(layer "F.Cu")
		(net 1)
	)
	(segment
		(start 120.525501 210.801)
		(end 120.525501 207.651)
		(width 0.4)
		(layer "F.Cu")
		(net 1)
	)
	(segment
		(start 154 172.904)
		(end 154.346 172.904)
		(width 0.4)
		(layer "F.Cu")
		(net 1)
	)
	(segment
		(start 78.185 153.2)
		(end 78.185 153.285)
		(width 0.15)
		(layer "F.Cu")
		(net 1)
	)
	(segment
		(start 116.1 191.7)
		(end 115.55 191.15)
		(width 0.4)
		(layer "F.Cu")
		(net 1)
	)
	(segment
		(start 140.375501 179.301)
		(end 140.875001 179.8005)
		(width 0.256)
		(layer "F.Cu")
		(net 1)
	)
	(segment
		(start 146.375501 187.301)
		(end 146.875001 187.8005)
		(width 0.256)
		(layer "F.Cu")
		(net 1)
	)
	(segment
		(start 108.400001 146.2025)
		(end 108.400001 145.1275)
		(width 0.201)
		(layer "F.Cu")
		(net 1)
	)
	(segment
		(start 189.865 142.165)
		(end 190.455 142.165)
		(width 0.256)
		(layer "F.Cu")
		(net 1)
	)
	(segment
		(start 143.375501 174.302)
		(end 143.875002 173.8025)
		(width 0.256)
		(layer "F.Cu")
		(net 1)
	)
	(segment
		(start 203.752 142.749999)
		(end 204.774 142.749999)
		(width 0.4)
		(layer "F.Cu")
		(net 1)
	)
	(segment
		(start 152.374503 185.301)
		(end 151.375501 185.301)
		(width 0.256)
		(layer "F.Cu")
		(net 1)
	)
	(segment
		(start 148.375501 178.301)
		(end 148.875001 178.8005)
		(width 0.256)
		(layer "F.Cu")
		(net 1)
	)
	(segment
		(start 155.900001 146.2025)
		(end 155.9 145.1275)
		(width 0.201)
		(layer "F.Cu")
		(net 1)
	)
	(segment
		(start 177.735501 198.261)
		(end 177.740501 198.256)
		(width 0.256)
		(layer "F.Cu")
		(net 1)
	)
	(segment
		(start 185.152 123.346)
		(end 184.3 123.346)
		(width 0.4)
		(layer "F.Cu")
		(net 1)
	)
	(segment
		(start 144.525501 206.925501)
		(end 144.525501 210.801)
		(width 0.22)
		(layer "F.Cu")
		(net 1)
	)
	(segment
		(start 78.244501 193.317)
		(end 79.979501 193.317)
		(width 0.201)
		(layer "F.Cu")
		(net 1)
	)
	(segment
		(start 117.900001 146.2025)
		(end 117.900001 145.1275)
		(width 0.201)
		(layer "F.Cu")
		(net 1)
	)
	(segment
		(start 171.452503 131.1025)
		(end 171.450002 131.105)
		(width 0.4)
		(layer "F.Cu")
		(net 1)
	)
	(segment
		(start 154.150001 138.8025)
		(end 154.150001 137.9265)
		(width 0.201)
		(layer "F.Cu")
		(net 1)
	)
	(segment
		(start 199.203499 135.964)
		(end 199.203499 136.54)
		(width 0.256)
		(layer "F.Cu")
		(net 1)
	)
	(segment
		(start 161.650001 138.8025)
		(end 161.650002 137.7275)
		(width 0.201)
		(layer "F.Cu")
		(net 1)
	)
	(segment
		(start 75.608501 158.516)
		(end 76.744672 158.516)
		(width 0.2)
		(layer "F.Cu")
		(net 1)
	)
	(segment
		(start 82.787 194.1)
		(end 83.502 194.1)
		(width 0.256)
		(layer "F.Cu")
		(net 1)
	)
	(segment
		(start 137.376501 172.302)
		(end 136.877001 171.8025)
		(width 0.256)
		(layer "F.Cu")
		(net 1)
	)
	(segment
		(start 158.900001 146.2025)
		(end 158.900002 145.127501)
		(width 0.201)
		(layer "F.Cu")
		(net 1)
	)
	(segment
		(start 89.523501 167.3)
		(end 89.523501 167.298743)
		(width 0.15)
		(layer "F.Cu")
		(net 1)
	)
	(segment
		(start 182.541 150.2)
		(end 182.541 150.825)
		(width 0.256)
		(layer "F.Cu")
		(net 1)
	)
	(segment
		(start 162.400001 146.2025)
		(end 162.400001 145.127499)
		(width 0.201)
		(layer "F.Cu")
		(net 1)
	)
	(segment
		(start 149.375501 178.300999)
		(end 149.875001 178.8005)
		(width 0.256)
		(layer "F.Cu")
		(net 1)
	)
	(segment
		(start 149.375501 172.302)
		(end 149.875001 171.8025)
		(width 0.256)
		(layer "F.Cu")
		(net 1)
	)
	(segment
		(start 198.9565 148.8035)
		(end 198.955 148.804999)
		(width 0.4)
		(layer "F.Cu")
		(net 1)
	)
	(segment
		(start 125.900001 146.2025)
		(end 125.900001 145.1275)
		(width 0.201)
		(layer "F.Cu")
		(net 1)
	)
	(segment
		(start 164.451501 183.369001)
		(end 164.470501 183.388001)
		(width 0.201)
		(layer "F.Cu")
		(net 1)
	)
	(segment
		(start 147.375501 177.301)
		(end 147.875001 177.8005)
		(width 0.256)
		(layer "F.Cu")
		(net 1)
	)
	(segment
		(start 191.775 196.575)
		(end 192.85 197.65)
		(width 0.256)
		(layer "F.Cu")
		(net 1)
	)
	(segment
		(start 78.185 158.285)
		(end 78.17 158.3)
		(width 0.1)
		(layer "F.Cu")
		(net 1)
	)
	(segment
		(start 89.523501 166.66)
		(end 89.523501 167.3)
		(width 0.15)
		(layer "F.Cu")
		(net 1)
	)
	(segment
		(start 183.137108 165.286)
		(end 183.137108 164.117999)
		(width 0.256)
		(layer "F.Cu")
		(net 1)
	)
	(segment
		(start 147.375501 170.302)
		(end 147.875001 169.8025)
		(width 0.256)
		(layer "F.Cu")
		(net 1)
	)
	(segment
		(start 93 190.5)
		(end 92.5 191)
		(width 0.201)
		(layer "F.Cu")
		(net 1)
	)
	(segment
		(start 132.400001 146.2025)
		(end 132.400001 145.1275)
		(width 0.201)
		(layer "F.Cu")
		(net 1)
	)
	(segment
		(start 140.525501 206.875501)
		(end 140.525501 210.801)
		(width 0.22)
		(layer "F.Cu")
		(net 1)
	)
	(segment
		(start 75.530501 152.114)
		(end 76.109501 152.114)
		(width 0.4)
		(layer "F.Cu")
		(net 1)
	)
	(segment
		(start 141.375501 178.301)
		(end 141.875001 178.8005)
		(width 0.256)
		(layer "F.Cu")
		(net 1)
	)
	(segment
		(start 183.057 148.625001)
		(end 183.057 147.984002)
		(width 0.256)
		(layer "F.Cu")
		(net 1)
	)
	(segment
		(start 120.150001 138.8025)
		(end 120.150001 137.7275)
		(width 0.201)
		(layer "F.Cu")
		(net 1)
	)
	(segment
		(start 98.313501 138.419)
		(end 98.220501 138.326)
		(width 0.1)
		(layer "F.Cu")
		(net 1)
	)
	(segment
		(start 78.244501 191.817)
		(end 79.979501 191.817)
		(width 0.201)
		(layer "F.Cu")
		(net 1)
	)
	(segment
		(start 194.144 193.56)
		(end 193.634 193.05)
		(width 0.4)
		(layer "F.Cu")
		(net 1)
	)
	(segment
		(start 183.604107 163.651)
		(end 183.604108 163.0255)
		(width 0.256)
		(layer "F.Cu")
		(net 1)
	)
	(segment
		(start 135.650001 138.8025)
		(end 135.650001 139.8775)
		(width 0.201)
		(layer "F.Cu")
		(net 1)
	)
	(segment
		(start 180.3 191.151)
		(end 180.3 190.5)
		(width 0.25)
		(layer "F.Cu")
		(net 1)
	)
	(segment
		(start 193.863499 135.49)
		(end 195.313499 135.49)
		(width 0.4)
		(layer "F.Cu")
		(net 1)
	)
	(segment
		(start 148.375501 184.301)
		(end 148.875001 184.8005)
		(width 0.256)
		(layer "F.Cu")
		(net 1)
	)
	(segment
		(start 136.3765 187.301)
		(end 135.877001 187.8005)
		(width 0.256)
		(layer "F.Cu")
		(net 1)
	)
	(segment
		(start 132.376501 165.302)
		(end 131.877 164.8025)
		(width 0.256)
		(layer "F.Cu")
		(net 1)
	)
	(segment
		(start 129.400001 146.2025)
		(end 129.400001 145.1275)
		(width 0.201)
		(layer "F.Cu")
		(net 1)
	)
	(segment
		(start 97.75 135.575)
		(end 97.75 134.96)
		(width 0.256)
		(layer "F.Cu")
		(net 1)
	)
	(segment
		(start 160.149501 183.369001)
		(end 160.168501 183.388001)
		(width 0.201)
		(layer "F.Cu")
		(net 1)
	)
	(segment
		(start 138.050501 206.400501)
		(end 137.525501 206.925501)
		(width 0.22)
		(layer "F.Cu")
		(net 1)
	)
	(segment
		(start 184.7 166.5)
		(end 183.851108 166.5)
		(width 0.256)
		(layer "F.Cu")
		(net 1)
	)
	(segment
		(start 144.65 138.8025)
		(end 144.649999 137.727499)
		(width 0.201)
		(layer "F.Cu")
		(net 1)
	)
	(segment
		(start 114.400001 146.2025)
		(end 114.400001 145.1275)
		(width 0.201)
		(layer "F.Cu")
		(net 1)
	)
	(segment
		(start 149.876001 182.8015)
		(end 150.375501 183.301)
		(width 0.256)
		(layer "F.Cu")
		(net 1)
	)
	(segment
		(start 169.400001 146.2025)
		(end 169.400001 145.127499)
		(width 0.201)
		(layer "F.Cu")
		(net 1)
	)
	(segment
		(start 183.775 151.875)
		(end 182.541 151.875)
		(width 0.4)
		(layer "F.Cu")
		(net 1)
	)
	(segment
		(start 149.149999 138.8025)
		(end 149.15 139.877499)
		(width 0.201)
		(layer "F.Cu")
		(net 1)
	)
	(segment
		(start 100.960501 157.056)
		(end 100.960501 157.356)
		(width 0.256)
		(layer "F.Cu")
		(net 1)
	)
	(segment
		(start 92.400501 130.300501)
		(end 93 130.9)
		(width 0.15)
		(layer "F.Cu")
		(net 1)
	)
	(segment
		(start 204.2765 148.8035)
		(end 205.2985 148.8035)
		(width 0.4)
		(layer "F.Cu")
		(net 1)
	)
	(segment
		(start 85.185 168.5)
		(end 86 168.5)
		(width 0.256)
		(layer "F.Cu")
		(net 1)
	)
	(segment
		(start 166.400001 146.2025)
		(end 166.400001 145.1275)
		(width 0.201)
		(layer "F.Cu")
		(net 1)
	)
	(segment
		(start 150.375501 187.301)
		(end 150.875001 187.800501)
		(width 0.256)
		(layer "F.Cu")
		(net 1)
	)
	(segment
		(start 121.150001 138.8025)
		(end 121.150001 137.7275)
		(width 0.201)
		(layer "F.Cu")
		(net 1)
	)
	(segment
		(start 191.55 145.125)
		(end 190.895 145.125)
		(width 0.201)
		(layer "F.Cu")
		(net 1)
	)
	(segment
		(start 136.376501 167.302)
		(end 135.877001 166.8025)
		(width 0.256)
		(layer "F.Cu")
		(net 1)
	)
	(segment
		(start 78.599 151.1)
		(end 79.649 151.1)
		(width 0.4)
		(layer "F.Cu")
		(net 1)
	)
	(segment
		(start 78.225 161.275)
		(end 78.225 160.601)
		(width 0.4)
		(layer "F.Cu")
		(net 1)
	)
	(segment
		(start 151.376501 181.3)
		(end 152.2 181.3)
		(width 0.256)
		(layer "F.Cu")
		(net 1)
	)
	(segment
		(start 183.137107 182.282)
		(end 183.604107 181.815)
		(width 0.256)
		(layer "F.Cu")
		(net 1)
	)
	(segment
		(start 183.791759 135.907099)
		(end 183.1416 135.907099)
		(width 0.256)
		(layer "F.Cu")
		(net 1)
	)
	(segment
		(start 134.000501 206.375501)
		(end 134.000501 206.425501)
		(width 0.22)
		(layer "F.Cu")
		(net 1)
	)
	(segment
		(start 182.034 149.65)
		(end 182.034 149.009001)
		(width 0.256)
		(layer "F.Cu")
		(net 1)
	)
	(segment
		(start 130.400001 146.2025)
		(end 130.400001 145.1275)
		(width 0.201)
		(layer "F.Cu")
		(net 1)
	)
	(segment
		(start 147.375501 183.301)
		(end 147.875001 183.8005)
		(width 0.256)
		(layer "F.Cu")
		(net 1)
	)
	(segment
		(start 107.176 180.184)
		(end 107.81 180.184)
		(width 0.15)
		(layer "F.Cu")
		(net 1)
	)
	(segment
		(start 123.634999 179.995499)
		(end 123.649499 179.980999)
		(width 0.256)
		(layer "F.Cu")
		(net 1)
	)
	(segment
		(start 129.650001 138.8025)
		(end 129.650001 137.7275)
		(width 0.201)
		(layer "F.Cu")
		(net 1)
	)
	(segment
		(start 182.541 150.157)
		(end 182.034 149.65)
		(width 0.256)
		(layer "F.Cu")
		(net 1)
	)
	(segment
		(start 155.650001 138.8025)
		(end 155.650001 137.9265)
		(width 0.201)
		(layer "F.Cu")
		(net 1)
	)
	(segment
		(start 141.375501 175.301)
		(end 141.875001 175.8005)
		(width 0.256)
		(layer "F.Cu")
		(net 1)
	)
	(segment
		(start 102.900501 157.636)
		(end 102.600501 157.336)
		(width 0.256)
		(layer "F.Cu")
		(net 1)
	)
	(segment
		(start 122.650001 138.8025)
		(end 122.650001 137.7275)
		(width 0.201)
		(layer "F.Cu")
		(net 1)
	)
	(segment
		(start 74.599501 180.265)
		(end 71.489501 180.265)
		(width 0.4)
		(layer "F.Cu")
		(net 1)
	)
	(segment
		(start 76.744672 158.516)
		(end 76.750344 158.510328)
		(width 0.2)
		(layer "F.Cu")
		(net 1)
	)
	(segment
		(start 110.400001 146.2025)
		(end 110.400001 145.1275)
		(width 0.201)
		(layer "F.Cu")
		(net 1)
	)
	(segment
		(start 161.8 172.3)
		(end 161.099 172.3)
		(width 0.4)
		(layer "F.Cu")
		(net 1)
	)
	(segment
		(start 109.650001 138.8025)
		(end 109.650001 137.7275)
		(width 0.201)
		(layer "F.Cu")
		(net 1)
	)
	(segment
		(start 152.374503 187.301)
		(end 151.375501 187.301)
		(width 0.256)
		(layer "F.Cu")
		(net 1)
	)
	(segment
		(start 139.375501 172.302)
		(end 139.875001 171.8025)
		(width 0.256)
		(layer "F.Cu")
		(net 1)
	)
	(segment
		(start 120.325501 207.451)
		(end 120.525501 207.651)
		(width 0.4)
		(layer "F.Cu")
		(net 1)
	)
	(segment
		(start 183.516 192.416)
		(end 183.5 192.4)
		(width 0.256)
		(layer "F.Cu")
		(net 1)
	)
	(segment
		(start 130.376501 169.302)
		(end 129.877001 168.8025)
		(width 0.256)
		(layer "F.Cu")
		(net 1)
	)
	(segment
		(start 170.900001 146.2025)
		(end 170.900001 145.1275)
		(width 0.201)
		(layer "F.Cu")
		(net 1)
	)
	(segment
		(start 90.690501 170.609499)
		(end 91 170.3)
		(width 0.256)
		(layer "F.Cu")
		(net 1)
	)
	(segment
		(start 78.087 155.3)
		(end 77.315 155.3)
		(width 0.182)
		(layer "F.Cu")
		(net 1)
	)
	(segment
		(start 161.4 146.2025)
		(end 161.400001 145.1275)
		(width 0.201)
		(layer "F.Cu")
		(net 1)
	)
	(segment
		(start 104.219 176.061)
		(end 104.09 176.19)
		(width 0.15)
		(layer "F.Cu")
		(net 1)
	)
	(segment
		(start 98.220501 138.226)
		(end 98.313501 138.319)
		(width 0.256)
		(layer "F.Cu")
		(net 1)
	)
	(segment
		(start 163.502 174.2)
		(end 164.715 174.2)
		(width 0.256)
		(layer "F.Cu")
		(net 1)
	)
	(segment
		(start 130.650001 138.8025)
		(end 130.650001 137.7275)
		(width 0.201)
		(layer "F.Cu")
		(net 1)
	)
	(segment
		(start 140.050501 206.400501)
		(end 140.525501 206.875501)
		(width 0.22)
		(layer "F.Cu")
		(net 1)
	)
	(segment
		(start 97.816 181.084)
		(end 97.3 181.6)
		(width 0.256)
		(layer "F.Cu")
		(net 1)
	)
	(segment
		(start 165.935501 179.675)
		(end 166.115501 179.855)
		(width 0.201)
		(layer "F.Cu")
		(net 1)
	)
	(segment
		(start 151.375501 162.302001)
		(end 151.875001 161.8025)
		(width 0.256)
		(layer "F.Cu")
		(net 1)
	)
	(segment
		(start 143.375501 172.302)
		(end 143.875001 171.8025)
		(width 0.256)
		(layer "F.Cu")
		(net 1)
	)
	(segment
		(start 131.000501 206.400501)
		(end 131.525501 206.925501)
		(width 0.22)
		(layer "F.Cu")
		(net 1)
	)
	(segment
		(start 146.15 138.8025)
		(end 146.15 139.8775)
		(width 0.201)
		(layer "F.Cu")
		(net 1)
	)
	(segment
		(start 138.376501 177.301)
		(end 137.877001 177.8005)
		(width 0.256)
		(layer "F.Cu")
		(net 1)
	)
	(segment
		(start 133.525501 210.801)
		(end 133.525501 206.900501)
		(width 0.44)
		(layer "F.Cu")
		(net 1)
	)
	(segment
		(start 82.9995 182.416)
		(end 83.684 182.416)
		(width 0.4)
		(layer "F.Cu")
		(net 1)
	)
	(segment
		(start 85.185 172.95)
		(end 86 172.95)
		(width 0.256)
		(layer "F.Cu")
		(net 1)
	)
	(segment
		(start 98.309501 178.323)
		(end 98.309501 179.191499)
		(width 0.15)
		(layer "F.Cu")
		(net 1)
	)
	(segment
		(start 117.525501 210.801)
		(end 117.525501 207.451)
		(width 0.4)
		(layer "F.Cu")
		(net 1)
	)
	(segment
		(start 129.376501 186.301)
		(end 128.877001 186.8005)
		(width 0.256)
		(layer "F.Cu")
		(net 1)
	)
	(segment
		(start 180.3 190.5)
		(end 180.011 190.211)
		(width 0.25)
		(layer "F.Cu")
		(net 1)
	)
	(segment
		(start 92.401 181.45)
		(end 92.05 181.45)
		(width 0.256)
		(layer "F.Cu")
		(net 1)
	)
	(segment
		(start 102.240501 157.646)
		(end 101.92765 157.958851)
		(width 0.256)
		(layer "F.Cu")
		(net 1)
	)
	(segment
		(start 102.6 181.3)
		(end 102.6 181.15)
		(width 0.15)
		(layer "F.Cu")
		(net 1)
	)
	(segment
		(start 139.375502 174.302)
		(end 139.875001 173.802501)
		(width 0.256)
		(layer "F.Cu")
		(net 1)
	)
	(segment
		(start 107.276 183.202)
		(end 107.91 183.202)
		(width 0.15)
		(layer "F.Cu")
		(net 1)
	)
	(segment
		(start 129.376501 176.300999)
		(end 128.877001 176.8005)
		(width 0.256)
		(layer "F.Cu")
		(net 1)
	)
	(segment
		(start 184.070501 130.469841)
		(end 184.507759 130.907099)
		(width 0.256)
		(layer "F.Cu")
		(net 1)
	)
	(segment
		(start 203.749999 134.529999)
		(end 203.7485 134.5285)
		(width 0.4)
		(layer "F.Cu")
		(net 1)
	)
	(segment
		(start 142.375501 175.301001)
		(end 142.875001 175.8005)
		(width 0.256)
		(layer "F.Cu")
		(net 1)
	)
	(segment
		(start 128.376501 163.302)
		(end 127.877001 162.8025)
		(width 0.256)
		(layer "F.Cu")
		(net 1)
	)
	(segment
		(start 173.575001 131.1025)
		(end 171.452503 131.1025)
		(width 0.4)
		(layer "F.Cu")
		(net 1)
	)
	(segment
		(start 111.400001 146.2025)
		(end 111.400001 145.1275)
		(width 0.201)
		(layer "F.Cu")
		(net 1)
	)
	(segment
		(start 197.754 139.214)
		(end 197.7 139.268)
		(width 0.182)
		(layer "F.Cu")
		(net 1)
	)
	(segment
		(start 145.375501 186.301)
		(end 145.875001 186.8005)
		(width 0.256)
		(layer "F.Cu")
		(net 1)
	)
	(segment
		(start 150.375501 173.302)
		(end 150.875001 172.8025)
		(width 0.256)
		(layer "F.Cu")
		(net 1)
	)
	(segment
		(start 205.0785 156.8025)
		(end 206.0795 156.8025)
		(width 0.256)
		(layer "F.Cu")
		(net 1)
	)
	(segment
		(start 77.2 160.6)
		(end 78.199999 160.6)
		(width 0.4)
		(layer "F.Cu")
		(net 1)
	)
	(segment
		(start 102.600501 157.336)
		(end 102.600501 156.942851)
		(width 0.256)
		(layer "F.Cu")
		(net 1)
	)
	(segment
		(start 96.1 193.4)
		(end 97.1 193.4)
		(width 0.201)
		(layer "F.Cu")
		(net 1)
	)
	(segment
		(start 150.375501 169.302)
		(end 150.875001 168.8025)
		(width 0.256)
		(layer "F.Cu")
		(net 1)
	)
	(segment
		(start 131.376501 172.302)
		(end 130.877001 171.8025)
		(width 0.256)
		(layer "F.Cu")
		(net 1)
	)
	(segment
		(start 125.650001 138.8025)
		(end 125.650001 137.7275)
		(width 0.201)
		(layer "F.Cu")
		(net 1)
	)
	(segment
		(start 147.375501 173.302)
		(end 147.875001 172.8025)
		(width 0.256)
		(layer "F.Cu")
		(net 1)
	)
	(segment
		(start 179.325 190.875)
		(end 179.35 190.875)
		(width 0.25)
		(layer "F.Cu")
		(net 1)
	)
	(segment
		(start 199.9785 157.8015)
		(end 198.9565 157.8015)
		(width 0.4)
		(layer "F.Cu")
		(net 1)
	)
	(segment
		(start 118.900001 146.2025)
		(end 118.900001 145.1275)
		(width 0.201)
		(layer "F.Cu")
		(net 1)
	)
	(segment
		(start 182.2 190.65)
		(end 182.65 190.2)
		(width 0.177)
		(layer "F.Cu")
		(net 1)
	)
	(segment
		(start 147.400001 146.2025)
		(end 147.400001 147.2775)
		(width 0.201)
		(layer "F.Cu")
		(net 1)
	)
	(segment
		(start 164.451501 182.674)
		(end 165.146501 182.674)
		(width 0.201)
		(layer "F.Cu")
		(net 1)
	)
	(segment
		(start 103.050501 120.226)
		(end 103.780501 120.226)
		(width 0.15)
		(layer "F.Cu")
		(net 1)
	)
	(segment
		(start 91.95 197.849)
		(end 91.899 197.9)
		(width 0.201)
		(layer "F.Cu")
		(net 1)
	)
	(segment
		(start 151.375501 179.301)
		(end 151.875001 179.8005)
		(width 0.256)
		(layer "F.Cu")
		(net 1)
	)
	(segment
		(start 138.376501 175.301001)
		(end 137.877002 175.8005)
		(width 0.256)
		(layer "F.Cu")
		(net 1)
	)
	(segment
		(start 183.516 196.166)
		(end 183.5 196.15)
		(width 0.256)
		(layer "F.Cu")
		(net 1)
	)
	(segment
		(start 163.650002 138.8025)
		(end 163.650003 137.727499)
		(width 0.201)
		(layer "F.Cu")
		(net 1)
	)
	(segment
		(start 145.375501 180.301)
		(end 145.875001 180.8005)
		(width 0.256)
		(layer "F.Cu")
		(net 1)
	)
	(segment
		(start 171.150001 138.8025)
		(end 171.150001 137.7275)
		(width 0.201)
		(layer "F.Cu")
		(net 1)
	)
	(segment
		(start 123.650001 138.8025)
		(end 123.650001 137.7275)
		(width 0.201)
		(layer "F.Cu")
		(net 1)
	)
	(segment
		(start 143.375501 176.301)
		(end 143.875001 176.8005)
		(width 0.256)
		(layer "F.Cu")
		(net 1)
	)
	(segment
		(start 165.249501 181.672)
		(end 166.098501 181.672)
		(width 0.201)
		(layer "F.Cu")
		(net 1)
	)
	(segment
		(start 92.802501 159.624)
		(end 92.800501 159.626)
		(width 0.256)
		(layer "F.Cu")
		(net 1)
	)
	(segment
		(start 86.621127 154.553859)
		(end 86.591829 154.583157)
		(width 0.2)
		(layer "F.Cu")
		(net 1)
	)
	(segment
		(start 75.150501 180.816)
		(end 74.599501 180.265)
		(width 0.4)
		(layer "F.Cu")
		(net 1)
	)
	(segment
		(start 183.057 149.666)
		(end 183.066 149.675)
		(width 0.256)
		(layer "F.Cu")
		(net 1)
	)
	(segment
		(start 192.85 197.65)
		(end 194.05 197.65)
		(width 0.256)
		(layer "F.Cu")
		(net 1)
	)
	(segment
		(start 139.375501 166.302)
		(end 139.875001 165.8025)
		(width 0.256)
		(layer "F.Cu")
		(net 1)
	)
	(segment
		(start 140.375501 177.301)
		(end 140.875001 177.8005)
		(width 0.256)
		(layer "F.Cu")
		(net 1)
	)
	(segment
		(start 180.278 195.057)
		(end 179.511 195.057)
		(width 0.177)
		(layer "F.Cu")
		(net 1)
	)
	(segment
		(start 78.244501 190.317)
		(end 79.979501 190.317)
		(width 0.201)
		(layer "F.Cu")
		(net 1)
	)
	(segment
		(start 179.2 190.361)
		(end 179.05 190.211)
		(width 0.25)
		(layer "F.Cu")
		(net 1)
	)
	(segment
		(start 91.048501 168.025)
		(end 91.048501 169.15)
		(width 0.15)
		(layer "F.Cu")
		(net 1)
	)
	(segment
		(start 149.375501 182.301001)
		(end 149.875001 182.8005)
		(width 0.256)
		(layer "F.Cu")
		(net 1)
	)
	(segment
		(start 105.975001 131.1025)
		(end 108.0975 131.1025)
		(width 0.4)
		(layer "F.Cu")
		(net 1)
	)
	(segment
		(start 137.376501 180.301)
		(end 136.877001 180.8005)
		(width 0.256)
		(layer "F.Cu")
		(net 1)
	)
	(segment
		(start 144.400001 146.2025)
		(end 144.400001 147.2775)
		(width 0.201)
		(layer "F.Cu")
		(net 1)
	)
	(segment
		(start 182.140107 183.45)
		(end 182.140107 182.779)
		(width 0.256)
		(layer "F.Cu")
		(net 1)
	)
	(segment
		(start 179.350001 123.546001)
		(end 180.202001 123.546001)
		(width 0.4)
		(layer "F.Cu")
		(net 1)
	)
	(segment
		(start 174.8955 174.3985)
		(end 174.894 174.4)
		(width 0.256)
		(layer "F.Cu")
		(net 1)
	)
	(segment
		(start 179.15 190.7)
		(end 179.325 190.875)
		(width 0.25)
		(layer "F.Cu")
		(net 1)
	)
	(segment
		(start 205.2985 157.8015)
		(end 205.3 157.8)
		(width 0.4)
		(layer "F.Cu")
		(net 1)
	)
	(segment
		(start 103.284501 154.958851)
		(end 103.88765 154.958851)
		(width 0.256)
		(layer "F.Cu")
		(net 1)
	)
	(segment
		(start 136.900001 146.2025)
		(end 136.900001 147.2775)
		(width 0.201)
		(layer "F.Cu")
		(net 1)
	)
	(segment
		(start 117.150001 138.8025)
		(end 117.150001 137.7275)
		(width 0.201)
		(layer "F.Cu")
		(net 1)
	)
	(segment
		(start 83.649 151.118)
		(end 83.631 151.1)
		(width 0.4)
		(layer "F.Cu")
		(net 1)
	)
	(segment
		(start 166.115501 180.705)
		(end 166.115501 181.655)
		(width 0.201)
		(layer "F.Cu")
		(net 1)
	)
	(segment
		(start 156.4005 174.4265)
		(end 156.4005 175.578001)
		(width 0.4)
		(layer "F.Cu")
		(net 1)
	)
	(segment
		(start 120.900001 146.2025)
		(end 120.900001 145.1275)
		(width 0.201)
		(layer "F.Cu")
		(net 1)
	)
	(segment
		(start 132.376501 185.301)
		(end 131.877001 185.8005)
		(width 0.256)
		(layer "F.Cu")
		(net 1)
	)
	(segment
		(start 152.374503 183.301)
		(end 151.375501 183.301)
		(width 0.256)
		(layer "F.Cu")
		(net 1)
	)
	(segment
		(start 87.391829 154.553859)
		(end 86.621127 154.553859)
		(width 0.2)
		(layer "F.Cu")
		(net 1)
	)
	(segment
		(start 163.400001 146.2025)
		(end 163.400002 145.127499)
		(width 0.201)
		(layer "F.Cu")
		(net 1)
	)
	(segment
		(start 133.900001 146.2025)
		(end 133.900001 147.2775)
		(width 0.201)
		(layer "F.Cu")
		(net 1)
	)
	(segment
		(start 82.9724 182.4431)
		(end 82.9995 182.416)
		(width 0.4)
		(layer "F.Cu")
		(net 1)
	)
	(segment
		(start 148.375501 163.302)
		(end 148.875001 162.8025)
		(width 0.256)
		(layer "F.Cu")
		(net 1)
	)
	(segment
		(start 131.525501 206.925501)
		(end 131.525501 210.801)
		(width 0.22)
		(layer "F.Cu")
		(net 1)
	)
	(segment
		(start 164.650001 138.8025)
		(end 164.65 137.7275)
		(width 0.201)
		(layer "F.Cu")
		(net 1)
	)
	(segment
		(start 100.808501 170.448)
		(end 100.808501 169.8335)
		(width 0.15)
		(layer "F.Cu")
		(net 1)
	)
	(segment
		(start 167.150001 138.8025)
		(end 167.150001 137.7275)
		(width 0.201)
		(layer "F.Cu")
		(net 1)
	)
	(segment
		(start 194.15 193.56)
		(end 194.144 193.56)
		(width 0.4)
		(layer "F.Cu")
		(net 1)
	)
	(segment
		(start 128.000501 206.400501)
		(end 128.525501 206.925501)
		(width 0.22)
		(layer "F.Cu")
		(net 1)
	)
	(segment
		(start 193.753499 136.32)
		(end 193.753499 135.6)
		(width 0.4)
		(layer "F.Cu")
		(net 1)
	)
	(segment
		(start 168.150001 138.8025)
		(end 168.150002 137.727499)
		(width 0.201)
		(layer "F.Cu")
		(net 1)
	)
	(segment
		(start 154.150001 137.9265)
		(end 154.400501 137.676)
		(width 0.201)
		(layer "F.Cu")
		(net 1)
	)
	(segment
		(start 164.451501 182.674)
		(end 164.451501 183.369001)
		(width 0.201)
		(layer "F.Cu")
		(net 1)
	)
	(segment
		(start 97.1 193.4)
		(end 97.4 193.1)
		(width 0.201)
		(layer "F.Cu")
		(net 1)
	)
	(segment
		(start 127.376501 180.301)
		(end 126.877001 180.8005)
		(width 0.256)
		(layer "F.Cu")
		(net 1)
	)
	(segment
		(start 151.375501 175.301)
		(end 151.875001 175.8005)
		(width 0.256)
		(layer "F.Cu")
		(net 1)
	)
	(segment
		(start 191.775 195.82)
		(end 191.775 196.575)
		(width 0.256)
		(layer "F.Cu")
		(net 1)
	)
	(segment
		(start 205.0785 152.8035)
		(end 206.0795 152.8035)
		(width 0.256)
		(layer "F.Cu")
		(net 1)
	)
	(segment
		(start 181.082 154.05)
		(end 181.082 155.074999)
		(width 0.256)
		(layer "F.Cu")
		(net 1)
	)
	(segment
		(start 119.900001 146.2025)
		(end 119.900001 145.1275)
		(width 0.201)
		(layer "F.Cu")
		(net 1)
	)
	(segment
		(start 150.375501 175.301)
		(end 150.875002 175.8005)
		(width 0.256)
		(layer "F.Cu")
		(net 1)
	)
	(segment
		(start 140.375501 175.301)
		(end 140.875001 175.8005)
		(width 0.256)
		(layer "F.Cu")
		(net 1)
	)
	(segment
		(start 205.0785 151.8035)
		(end 206.0795 151.8035)
		(width 0.256)
		(layer "F.Cu")
		(net 1)
	)
	(segment
		(start 94.059829 166.467585)
		(end 94.047244 166.455)
		(width 0.256)
		(layer "F.Cu")
		(net 1)
	)
	(segment
		(start 166.115501 181.655)
		(end 166.115501 182.305)
		(width 0.201)
		(layer "F.Cu")
		(net 1)
	)
	(segment
		(start 183.137107 183.45)
		(end 183.137107 182.282)
		(width 0.256)
		(layer "F.Cu")
		(net 1)
	)
	(segment
		(start 95.272344 167.068328)
		(end 95.272344 166.468843)
		(width 0.256)
		(layer "F.Cu")
		(net 1)
	)
	(segment
		(start 115.150001 138.8025)
		(end 115.150001 137.7275)
		(width 0.201)
		(layer "F.Cu")
		(net 1)
	)
	(segment
		(start 126.376501 167.302)
		(end 125.877001 166.8025)
		(width 0.256)
		(layer "F.Cu")
		(net 1)
	)
	(segment
		(start 95.272344 166.468843)
		(end 95.268501 166.465)
		(width 0.256)
		(layer "F.Cu")
		(net 1)
	)
	(segment
		(start 128.650001 138.8025)
		(end 128.650001 137.7275)
		(width 0.201)
		(layer "F.Cu")
		(net 1)
	)
	(segment
		(start 133.376501 168.302)
		(end 132.877001 167.8025)
		(width 0.256)
		(layer "F.Cu")
		(net 1)
	)
	(segment
		(start 160.149501 182.674)
		(end 160.149501 183.369001)
		(width 0.201)
		(layer "F.Cu")
		(net 1)
	)
	(segment
		(start 82.015 194.1)
		(end 81.3 194.1)
		(width 0.256)
		(layer "F.Cu")
		(net 1)
	)
	(segment
		(start 146.876001 187.8005)
		(end 147.375501 187.301)
		(width 0.256)
		(layer "F.Cu")
		(net 1)
	)
	(segment
		(start 174.894 180.4)
		(end 172.928 180.4)
		(width 0.256)
		(layer "F.Cu")
		(net 1)
	)
	(segment
		(start 97.151 197.849)
		(end 97.1 197.9)
		(width 0.201)
		(layer "F.Cu")
		(net 1)
	)
	(segment
		(start 98.350501 130.286461)
		(end 98.350501 130.949499)
		(width 0.15)
		(layer "F.Cu")
		(net 1)
	)
	(segment
		(start 199.9785 148.8035)
		(end 198.9565 148.8035)
		(width 0.4)
		(layer "F.Cu")
		(net 1)
	)
	(segment
		(start 95.896 193.196)
		(end 96.1 193.4)
		(width 0.201)
		(layer "F.Cu")
		(net 1)
	)
	(segment
		(start 131.376501 162.302)
		(end 130.877001 161.8025)
		(width 0.256)
		(layer "F.Cu")
		(net 1)
	)
	(segment
		(start 101.384501 160.28625)
		(end 101.384501 158.958851)
		(width 0.256)
		(layer "F.Cu")
		(net 1)
	)
	(segment
		(start 144.375501 171.302)
		(end 144.875001 170.8025)
		(width 0.256)
		(layer "F.Cu")
		(net 1)
	)
	(segment
		(start 141.375501 174.302)
		(end 141.875001 173.8025)
		(width 0.256)
		(layer "F.Cu")
		(net 1)
	)
	(segment
		(start 190.895 145.125)
		(end 190.88 145.14)
		(width 0.201)
		(layer "F.Cu")
		(net 1)
	)
	(segment
		(start 98.313501 138.319)
		(end 98.313501 139.428)
		(width 0.256)
		(layer "F.Cu")
		(net 1)
	)
	(segment
		(start 105.951344 177.872329)
		(end 105.981344 177.902328)
		(width 0.15)
		(layer "F.Cu")
		(net 1)
	)
	(segment
		(start 97.109 180.166)
		(end 97.125 180.182)
		(width 0.15)
		(layer "F.Cu")
		(net 1)
	)
	(segment
		(start 77.315 155.3)
		(end 76.702001 155.3)
		(width 0.201)
		(layer "F.Cu")
		(net 1)
	)
	(segment
		(start 141.375501 172.302)
		(end 141.875002 171.8025)
		(width 0.256)
		(layer "F.Cu")
		(net 1)
	)
	(segment
		(start 183.066 149.675)
		(end 182.541 150.2)
		(width 0.256)
		(layer "F.Cu")
		(net 1)
	)
	(segment
		(start 128.400001 146.2025)
		(end 128.400001 145.1275)
		(width 0.201)
		(layer "F.Cu")
		(net 1)
	)
	(segment
		(start 82.787 191)
		(end 83.502 191)
		(width 0.256)
		(layer "F.Cu")
		(net 1)
	)
	(segment
		(start 87.391829 151.183859)
		(end 87.391829 150.583157)
		(width 0.2)
		(layer "F.Cu")
		(net 1)
	)
	(segment
		(start 131.376501 182.301001)
		(end 130.877001 182.8005)
		(width 0.256)
		(layer "F.Cu")
		(net 1)
	)
	(segment
		(start 119.650501 174.926)
		(end 120.150501 175.426)
		(width 0.4)
		(layer "F.Cu")
		(net 1)
	)
	(segment
		(start 98.313501 139.428)
		(end 98.313501 138.419)
		(width 0.1)
		(layer "F.Cu")
		(net 1)
	)
	(segment
		(start 204.2765 157.8015)
		(end 205.2985 157.8015)
		(width 0.4)
		(layer "F.Cu")
		(net 1)
	)
	(segment
		(start 166.115501 179.855)
		(end 166.115501 180.705)
		(width 0.201)
		(layer "F.Cu")
		(net 1)
	)
	(segment
		(start 126.376502 187.301)
		(end 125.877001 187.8005)
		(width 0.256)
		(layer "F.Cu")
		(net 1)
	)
	(segment
		(start 150.375501 179.301)
		(end 150.875002 179.8005)
		(width 0.256)
		(layer "F.Cu")
		(net 1)
	)
	(segment
		(start 118.150001 138.8025)
		(end 118.150001 137.7275)
		(width 0.201)
		(layer "F.Cu")
		(net 1)
	)
	(segment
		(start 140.375501 171.302)
		(end 140.875001 170.8025)
		(width 0.256)
		(layer "F.Cu")
		(net 1)
	)
	(segment
		(start 145.375501 184.301)
		(end 145.875001 184.8005)
		(width 0.256)
		(layer "F.Cu")
		(net 1)
	)
	(segment
		(start 194.15 197.55)
		(end 194.05 197.65)
		(width 0.256)
		(layer "F.Cu")
		(net 1)
	)
	(segment
		(start 96.475 180.166)
		(end 97.109 180.166)
		(width 0.15)
		(layer "F.Cu")
		(net 1)
	)
	(segment
		(start 173.150001 138.8025)
		(end 173.150001 137.7275)
		(width 0.201)
		(layer "F.Cu")
		(net 1)
	)
	(segment
		(start 151.375501 173.302)
		(end 151.875001 172.8025)
		(width 0.256)
		(layer "F.Cu")
		(net 1)
	)
	(segment
		(start 84.300501 123.876)
		(end 84.300501 124.606)
		(width 0.15)
		(layer "F.Cu")
		(net 1)
	)
	(segment
		(start 74.091501 164.565)
		(end 71.389501 164.565)
		(width 0.4)
		(layer "F.Cu")
		(net 1)
	)
	(segment
		(start 91.689001 177.0685)
		(end 91.689501 177.069)
		(width 0.256)
		(layer "F.Cu")
		(net 1)
	)
	(segment
		(start 139.900001 146.2025)
		(end 139.900001 145.127499)
		(width 0.201)
		(layer "F.Cu")
		(net 1)
	)
	(segment
		(start 149.400001 145.3265)
		(end 149.650501 145.076)
		(width 0.201)
		(layer "F.Cu")
		(net 1)
	)
	(segment
		(start 95.551 197.849)
		(end 95.5 197.9)
		(width 0.201)
		(layer "F.Cu")
		(net 1)
	)
	(segment
		(start 150.900001 145.3265)
		(end 150.649501 145.076)
		(width 0.201)
		(layer "F.Cu")
		(net 1)
	)
	(segment
		(start 102.8 180.95)
		(end 102.85 180.95)
		(width 0.15)
		(layer "F.Cu")
		(net 1)
	)
	(segment
		(start 141.400001 146.2025)
		(end 141.4 145.127501)
		(width 0.201)
		(layer "F.Cu")
		(net 1)
	)
	(segment
		(start 151.900002 146.2025)
		(end 151.900001 145.1275)
		(width 0.201)
		(layer "F.Cu")
		(net 1)
	)
	(segment
		(start 105.975001 131.1025)
		(end 105.975002 133.78)
		(width 0.4)
		(layer "F.Cu")
		(net 1)
	)
	(segment
		(start 148.375501 180.301)
		(end 148.875001 180.8005)
		(width 0.256)
		(layer "F.Cu")
		(net 1)
	)
	(segment
		(start 148.375501 186.301)
		(end 148.875001 186.800501)
		(width 0.256)
		(layer "F.Cu")
		(net 1)
	)
	(segment
		(start 101.92765 157.958851)
		(end 101.384501 157.958851)
		(width 0.256)
		(layer "F.Cu")
		(net 1)
	)
	(segment
		(start 116.15 194.7)
		(end 116.15 194.75)
		(width 0.4)
		(layer "F.Cu")
		(net 1)
	)
	(segment
		(start 85.185 172.95)
		(end 84.413 172.95)
		(width 0.256)
		(layer "F.Cu")
		(net 1)
	)
	(segment
		(start 142.375501 185.300999)
		(end 142.875001 185.8005)
		(width 0.256)
		(layer "F.Cu")
		(net 1)
	)
	(segment
		(start 160.097501 178.675)
		(end 159.4025 178.675)
		(width 0.201)
		(layer "F.Cu")
		(net 1)
	)
	(segment
		(start 156.4005 175.578001)
		(end 156.002501 175.976)
		(width 0.4)
		(layer "F.Cu")
		(net 1)
	)
	(segment
		(start 95.400501 130.999499)
		(end 95.4 131)
		(width 0.15)
		(layer "F.Cu")
		(net 1)
	)
	(segment
		(start 162.650002 138.8025)
		(end 162.650002 137.727499)
		(width 0.201)
		(layer "F.Cu")
		(net 1)
	)
	(segment
		(start 127.650001 138.8025)
		(end 127.650001 137.7275)
		(width 0.201)
		(layer "F.Cu")
		(net 1)
	)
	(segment
		(start 183.001 190.2)
		(end 182.9 190.2)
		(width 0.15)
		(layer "F.Cu")
		(net 1)
	)
	(segment
		(start 102.735 181.435)
		(end 102.6 181.3)
		(width 0.15)
		(layer "F.Cu")
		(net 1)
	)
	(segment
		(start 98.309501 179.191499)
		(end 98.301 179.2)
		(width 0.15)
		(layer "F.Cu")
		(net 1)
	)
	(segment
		(start 145.375501 182.301)
		(end 145.875001 182.8005)
		(width 0.256)
		(layer "F.Cu")
		(net 1)
	)
	(via
		(at 88.491829 150.623157)
		(size 0.45)
		(drill 0.1)
		(layers "F.Cu" "B.Cu")
		(net 1)
	)
	(via
		(at 98.65 156)
		(size 0.45)
		(drill 0.1)
		(layers "F.Cu" "B.Cu")
		(net 1)
	)
	(via
		(at 102.191829 150.523157)
		(size 0.45)
		(drill 0.1)
		(layers "F.Cu" "B.Cu")
		(net 1)
	)
	(via
		(at 100.400501 150.213149)
		(size 0.45)
		(drill 0.1)
		(layers "F.Cu" "B.Cu")
		(net 1)
	)
	(via
		(at 103.875001 148.9185)
		(size 0.45)
		(drill 0.1)
		(layers "F.Cu" "B.Cu")
		(net 1)
	)
	(via
		(at 112.17 167.88)
		(size 0.45)
		(drill 0.1)
		(layers "F.Cu" "B.Cu")
		(net 1)
	)
	(via
		(at 151.3 112.1)
		(size 0.45)
		(drill 0.1)
		(layers "F.Cu" "B.Cu")
		(net 1)
	)
	(via
		(at 179.6 166.2)
		(size 0.45)
		(drill 0.1)
		(layers "F.Cu" "B.Cu")
		(net 1)
	)
	(via
		(at 131.877001 175.8005)
		(size 0.45)
		(drill 0.1)
		(layers "F.Cu" "B.Cu")
		(net 1)
	)
	(via
		(at 204.85 169.05)
		(size 0.45)
		(drill 0.1)
		(layers "F.Cu" "B.Cu")
		(net 1)
	)
	(via
		(at 144.875001 170.8025)
		(size 0.45)
		(drill 0.1)
		(layers "F.Cu" "B.Cu")
		(net 1)
	)
	(via
		(at 145.875001 163.8025)
		(size 0.45)
		(drill 0.1)
		(layers "F.Cu" "B.Cu")
		(net 1)
	)
	(via
		(at 115.750001 180.65)
		(size 0.45)
		(drill 0.1)
		(layers "F.Cu" "B.Cu")
		(net 1)
	)
	(via
		(at 114.400001 145.1275)
		(size 0.45)
		(drill 0.1)
		(layers "F.Cu" "B.Cu")
		(net 1)
	)
	(via
		(at 105.151 179.585)
		(size 0.45)
		(drill 0.1)
		(layers "F.Cu" "B.Cu")
		(net 1)
	)
	(via
		(at 193.927 183.351)
		(size 0.45)
		(drill 0.1)
		(layers "F.Cu" "B.Cu")
		(net 1)
	)
	(via
		(at 139.875001 173.802501)
		(size 0.45)
		(drill 0.1)
		(layers "F.Cu" "B.Cu")
		(net 1)
	)
	(via
		(at 74.7 195.4)
		(size 0.45)
		(drill 0.1)
		(layers "F.Cu" "B.Cu")
		(net 1)
	)
	(via
		(at 82.723038 179.816)
		(size 0.45)
		(drill 0.1)
		(layers "F.Cu" "B.Cu")
		(net 1)
	)
	(via
		(at 123.250501 196.876)
		(size 0.45)
		(drill 0.1)
		(layers "F.Cu" "B.Cu")
		(net 1)
	)
	(via
		(at 100.7 194)
		(size 0.45)
		(drill 0.1)
		(layers "F.Cu" "B.Cu")
		(net 1)
	)
	(via
		(at 196.5705 165.4515)
		(size 0.45)
		(drill 0.1)
		(layers "F.Cu" "B.Cu")
		(net 1)
	)
	(via
		(at 90.091329 148.586)
		(size 0.45)
		(drill 0.1)
		(layers "F.Cu" "B.Cu")
		(net 1)
	)
	(via
		(at 96.90491 162.999725)
		(size 0.45)
		(drill 0.1)
		(layers "F.Cu" "B.Cu")
		(net 1)
	)
	(via
		(at 195.4 180.3)
		(size 0.45)
		(drill 0.1)
		(layers "F.Cu" "B.Cu")
		(net 1)
	)
	(via
		(at 144.400001 147.2775)
		(size 0.45)
		(drill 0.1)
		(layers "F.Cu" "B.Cu")
		(net 1)
	)
	(via
		(at 146.875001 166.802501)
		(size 0.45)
		(drill 0.1)
		(layers "F.Cu" "B.Cu")
		(net 1)
	)
	(via
		(at 78.7 153.8)
		(size 0.45)
		(drill 0.1)
		(layers "F.Cu" "B.Cu")
		(net 1)
	)
	(via
		(at 100.536501 169.5615)
		(size 0.45)
		(drill 0.1)
		(layers "F.Cu" "B.Cu")
		(net 1)
	)
	(via
		(at 153.9 145.127499)
		(size 0.45)
		(drill 0.1)
		(layers "F.Cu" "B.Cu")
		(net 1)
	)
	(via
		(at 141.875001 175.8005)
		(size 0.45)
		(drill 0.1)
		(layers "F.Cu" "B.Cu")
		(net 1)
	)
	(via
		(at 147.875001 177.8005)
		(size 0.45)
		(drill 0.1)
		(layers "F.Cu" "B.Cu")
		(net 1)
	)
	(via
		(at 186.5 112.1)
		(size 0.45)
		(drill 0.1)
		(layers "F.Cu" "B.Cu")
		(net 1)
	)
	(via
		(at 195.2 170.7)
		(size 0.45)
		(drill 0.1)
		(layers "F.Cu" "B.Cu")
		(net 1)
	)
	(via
		(at 88.2 192.51)
		(size 0.45)
		(drill 0.1)
		(layers "F.Cu" "B.Cu")
		(net 1)
	)
	(via
		(at 85.741829 157.933157)
		(size 0.45)
		(drill 0.1)
		(layers "F.Cu" "B.Cu")
		(net 1)
	)
	(via
		(at 160.078501 177.960999)
		(size 0.45)
		(drill 0.1)
		(layers "F.Cu" "B.Cu")
		(net 1)
	)
	(via
		(at 132.1 112.1)
		(size 0.45)
		(drill 0.1)
		(layers "F.Cu" "B.Cu")
		(net 1)
	)
	(via
		(at 137.877001 183.8005)
		(size 0.45)
		(drill 0.1)
		(layers "F.Cu" "B.Cu")
		(net 1)
	)
	(via
		(at 94.047244 166.455)
		(size 0.45)
		(drill 0.1)
		(layers "F.Cu" "B.Cu")
		(net 1)
	)
	(via
		(at 147.65 137.7275)
		(size 0.45)
		(drill 0.1)
		(layers "F.Cu" "B.Cu")
		(net 1)
	)
	(via
		(at 120.900001 145.1275)
		(size 0.45)
		(drill 0.1)
		(layers "F.Cu" "B.Cu")
		(net 1)
	)
	(via
		(at 138.877001 170.776)
		(size 0.45)
		(drill 0.1)
		(layers "F.Cu" "B.Cu")
		(net 1)
	)
	(via
		(at 193.9 165.9)
		(size 0.45)
		(drill 0.1)
		(layers "F.Cu" "B.Cu")
		(net 1)
	)
	(via
		(at 171.800501 195.476)
		(size 0.45)
		(drill 0.1)
		(layers "F.Cu" "B.Cu")
		(net 1)
	)
	(via
		(at 142.875001 164.8025)
		(size 0.45)
		(drill 0.1)
		(layers "F.Cu" "B.Cu")
		(net 1)
	)
	(via
		(at 167.400002 145.127499)
		(size 0.45)
		(drill 0.1)
		(layers "F.Cu" "B.Cu")
		(net 1)
	)
	(via
		(at 128.400001 145.1275)
		(size 0.45)
		(drill 0.1)
		(layers "F.Cu" "B.Cu")
		(net 1)
	)
	(via
		(at 137.877001 177.8005)
		(size 0.45)
		(drill 0.1)
		(layers "F.Cu" "B.Cu")
		(net 1)
	)
	(via
		(at 79.1 200.2)
		(size 0.45)
		(drill 0.1)
		(layers "F.Cu" "B.Cu")
		(net 1)
	)
	(via
		(at 137.16 132.08)
		(size 0.45)
		(drill 0.1)
		(layers "F.Cu" "B.Cu")
		(net 1)
	)
	(via
		(at 85.5 200.2)
		(size 0.45)
		(drill 0.1)
		(layers "F.Cu" "B.Cu")
		(net 1)
	)
	(via
		(at 88.2 195.611)
		(size 0.45)
		(drill 0.1)
		(layers "F.Cu" "B.Cu")
		(net 1)
	)
	(via
		(at 91.686501 170.35)
		(size 0.45)
		(drill 0.1)
		(layers "F.Cu" "B.Cu")
		(net 1)
	)
	(via
		(at 194.975 196.025)
		(size 0.45)
		(drill 0.1)
		(layers "F.Cu" "B.Cu")
		(net 1)
	)
	(via
		(at 177.8 157.48)
		(size 0.45)
		(drill 0.1)
		(layers "F.Cu" "B.Cu")
		(net 1)
	)
	(via
		(at 90.435 194.111)
		(size 0.45)
		(drill 0.1)
		(layers "F.Cu" "B.Cu")
		(net 1)
	)
	(via
		(at 129.1 195.5)
		(size 0.45)
		(drill 0.1)
		(layers "F.Cu" "B.Cu")
		(net 1)
	)
	(via
		(at 127.877001 172.8025)
		(size 0.45)
		(drill 0.1)
		(layers "F.Cu" "B.Cu")
		(net 1)
	)
	(via
		(at 189.55 166.875)
		(size 0.45)
		(drill 0.1)
		(layers "F.Cu" "B.Cu")
		(net 1)
	)
	(via
		(at 122.5 112.1)
		(size 0.45)
		(drill 0.1)
		(layers "F.Cu" "B.Cu")
		(net 1)
	)
	(via
		(at 196.2 170.9)
		(size 0.45)
		(drill 0.1)
		(layers "F.Cu" "B.Cu")
		(net 1)
	)
	(via
		(at 142.24 116.84)
		(size 0.45)
		(drill 0.1)
		(layers "F.Cu" "B.Cu")
		(net 1)
	)
	(via
		(at 146.15 139.8775)
		(size 0.45)
		(drill 0.1)
		(layers "F.Cu" "B.Cu")
		(net 1)
	)
	(via
		(at 103.275001 148.3185)
		(size 0.45)
		(drill 0.1)
		(layers "F.Cu" "B.Cu")
		(net 1)
	)
	(via
		(at 197.9975 185.6025)
		(size 0.45)
		(drill 0.1)
		(layers "F.Cu" "B.Cu")
		(net 1)
	)
	(via
		(at 197.158001 185.173)
		(size 0.45)
		(drill 0.1)
		(layers "F.Cu" "B.Cu")
		(net 1)
	)
	(via
		(at 117.900001 145.1275)
		(size 0.45)
		(drill 0.1)
		(layers "F.Cu" "B.Cu")
		(net 1)
	)
	(via
		(at 125.73 159.471)
		(size 0.45)
		(drill 0.1)
		(layers "F.Cu" "B.Cu")
		(net 1)
	)
	(via
		(at 82.3 200.2)
		(size 0.45)
		(drill 0.1)
		(layers "F.Cu" "B.Cu")
		(net 1)
	)
	(via
		(at 135.877001 166.8025)
		(size 0.45)
		(drill 0.1)
		(layers "F.Cu" "B.Cu")
		(net 1)
	)
	(via
		(at 183.775 151.875)
		(size 0.45)
		(drill 0.1)
		(layers "F.Cu" "B.Cu")
		(net 1)
	)
	(via
		(at 120.150001 137.7275)
		(size 0.45)
		(drill 0.1)
		(layers "F.Cu" "B.Cu")
		(net 1)
	)
	(via
		(at 160.6 200.6)
		(size 0.45)
		(drill 0.1)
		(layers "F.Cu" "B.Cu")
		(net 1)
	)
	(via
		(at 172.400501 198.376)
		(size 0.45)
		(drill 0.1)
		(layers "F.Cu" "B.Cu")
		(net 1)
	)
	(via
		(at 147.875001 181.8005)
		(size 0.45)
		(drill 0.1)
		(layers "F.Cu" "B.Cu")
		(net 1)
	)
	(via
		(at 189.725 184.3)
		(size 0.45)
		(drill 0.1)
		(layers "F.Cu" "B.Cu")
		(net 1)
	)
	(via
		(at 153.150001 139.877498)
		(size 0.45)
		(drill 0.1)
		(layers "F.Cu" "B.Cu")
		(net 1)
	)
	(via
		(at 74.7 170.7)
		(size 0.45)
		(drill 0.1)
		(layers "F.Cu" "B.Cu")
		(net 1)
	)
	(via
		(at 203.7 186.575)
		(size 0.45)
		(drill 0.1)
		(layers "F.Cu" "B.Cu")
		(net 1)
	)
	(via
		(at 145.875001 183.8005)
		(size 0.45)
		(drill 0.1)
		(layers "F.Cu" "B.Cu")
		(net 1)
	)
	(via
		(at 145.875001 185.8005)
		(size 0.45)
		(drill 0.1)
		(layers "F.Cu" "B.Cu")
		(net 1)
	)
	(via
		(at 92.400501 124.606)
		(size 0.45)
		(drill 0.1)
		(layers "F.Cu" "B.Cu")
		(net 1)
	)
	(via
		(at 177.740501 198.256)
		(size 0.45)
		(drill 0.1)
		(layers "F.Cu" "B.Cu")
		(net 1)
	)
	(via
		(at 86 172.95)
		(size 0.45)
		(drill 0.1)
		(layers "F.Cu" "B.Cu")
		(net 1)
	)
	(via
		(at 142.900001 145.1275)
		(size 0.45)
		(drill 0.1)
		(layers "F.Cu" "B.Cu")
		(net 1)
	)
	(via
		(at 166.115501 182.305)
		(size 0.45)
		(drill 0.1)
		(layers "F.Cu" "B.Cu")
		(net 1)
	)
	(via
		(at 79.980501 193.316)
		(size 0.45)
		(drill 0.1)
		(layers "F.Cu" "B.Cu")
		(net 1)
	)
	(via
		(at 119.1 177.4275)
		(size 0.45)
		(drill 0.1)
		(layers "F.Cu" "B.Cu")
		(net 1)
	)
	(via
		(at 170.900001 145.1275)
		(size 0.45)
		(drill 0.1)
		(layers "F.Cu" "B.Cu")
		(net 1)
	)
	(via
		(at 141.875001 173.8025)
		(size 0.45)
		(drill 0.1)
		(layers "F.Cu" "B.Cu")
		(net 1)
	)
	(via
		(at 84.455 177.165)
		(size 0.45)
		(drill 0.1)
		(layers "F.Cu" "B.Cu")
		(net 1)
	)
	(via
		(at 181.082 153.409001)
		(size 0.45)
		(drill 0.1)
		(layers "F.Cu" "B.Cu")
		(net 1)
	)
	(via
		(at 182.037107 182.676)
		(size 0.45)
		(drill 0.1)
		(layers "F.Cu" "B.Cu")
		(net 1)
	)
	(via
		(at 102.980501 150.556)
		(size 0.45)
		(drill 0.1)
		(layers "F.Cu" "B.Cu")
		(net 1)
	)
	(via
		(at 184.2 186.9)
		(size 0.45)
		(drill 0.1)
		(layers "F.Cu" "B.Cu")
		(net 1)
	)
	(via
		(at 105.981344 177.902328)
		(size 0.45)
		(drill 0.1)
		(layers "F.Cu" "B.Cu")
		(net 1)
	)
	(via
		(at 139.875001 171.8025)
		(size 0.45)
		(drill 0.1)
		(layers "F.Cu" "B.Cu")
		(net 1)
	)
	(via
		(at 82.083897 137.166537)
		(size 0.45)
		(drill 0.1)
		(layers "F.Cu" "B.Cu")
		(net 1)
	)
	(via
		(at 157.48 121.92)
		(size 0.45)
		(drill 0.1)
		(layers "F.Cu" "B.Cu")
		(net 1)
	)
	(via
		(at 177.88 152.76)
		(size 0.45)
		(drill 0.1)
		(layers "F.Cu" "B.Cu")
		(net 1)
	)
	(via
		(at 170.300501 192.176)
		(size 0.45)
		(drill 0.1)
		(layers "F.Cu" "B.Cu")
		(net 1)
	)
	(via
		(at 163.4 186.7)
		(size 0.45)
		(drill 0.1)
		(layers "F.Cu" "B.Cu")
		(net 1)
	)
	(via
		(at 149.875001 165.8025)
		(size 0.45)
		(drill 0.1)
		(layers "F.Cu" "B.Cu")
		(net 1)
	)
	(via
		(at 171.800501 194.476)
		(size 0.45)
		(drill 0.1)
		(layers "F.Cu" "B.Cu")
		(net 1)
	)
	(via
		(at 148.875001 176.8005)
		(size 0.45)
		(drill 0.1)
		(layers "F.Cu" "B.Cu")
		(net 1)
	)
	(via
		(at 79.980501 191.816)
		(size 0.45)
		(drill 0.1)
		(layers "F.Cu" "B.Cu")
		(net 1)
	)
	(via
		(at 162.56 127)
		(size 0.45)
		(drill 0.1)
		(layers "F.Cu" "B.Cu")
		(net 1)
	)
	(via
		(at 180.6 183.1)
		(size 0.45)
		(drill 0.1)
		(layers "F.Cu" "B.Cu")
		(net 1)
	)
	(via
		(at 141.4 145.127501)
		(size 0.45)
		(drill 0.1)
		(layers "F.Cu" "B.Cu")
		(net 1)
	)
	(via
		(at 148.875001 171.8025)
		(size 0.45)
		(drill 0.1)
		(layers "F.Cu" "B.Cu")
		(net 1)
	)
	(via
		(at 194.627 180.801)
		(size 0.45)
		(drill 0.1)
		(layers "F.Cu" "B.Cu")
		(net 1)
	)
	(via
		(at 90.9 112.1)
		(size 0.45)
		(drill 0.1)
		(layers "F.Cu" "B.Cu")
		(net 1)
	)
	(via
		(at 170.300501 196.476)
		(size 0.45)
		(drill 0.1)
		(layers "F.Cu" "B.Cu")
		(net 1)
	)
	(via
		(at 80.9 150.4)
		(size 0.45)
		(drill 0.1)
		(layers "F.Cu" "B.Cu")
		(net 1)
	)
	(via
		(at 162.56 116.84)
		(size 0.45)
		(drill 0.1)
		(layers "F.Cu" "B.Cu")
		(net 1)
	)
	(via
		(at 152.9 145.127499)
		(size 0.45)
		(drill 0.1)
		(layers "F.Cu" "B.Cu")
		(net 1)
	)
	(via
		(at 131.000501 206.400501)
		(size 0.45)
		(drill 0.1)
		(layers "F.Cu" "B.Cu")
		(net 1)
	)
	(via
		(at 150.15 139.8775)
		(size 0.45)
		(drill 0.1)
		(layers "F.Cu" "B.Cu")
		(net 1)
	)
	(via
		(at 168.150002 137.727499)
		(size 0.45)
		(drill 0.1)
		(layers "F.Cu" "B.Cu")
		(net 1)
	)
	(via
		(at 158.650003 137.727499)
		(size 0.45)
		(drill 0.1)
		(layers "F.Cu" "B.Cu")
		(net 1)
	)
	(via
		(at 133.900501 174.776)
		(size 0.45)
		(drill 0.1)
		(layers "F.Cu" "B.Cu")
		(net 1)
	)
	(via
		(at 197.9705 168.1515)
		(size 0.45)
		(drill 0.1)
		(layers "F.Cu" "B.Cu")
		(net 1)
	)
	(via
		(at 80.9 151.6)
		(size 0.45)
		(drill 0.1)
		(layers "F.Cu" "B.Cu")
		(net 1)
	)
	(via
		(at 157.7 112.1)
		(size 0.45)
		(drill 0.1)
		(layers "F.Cu" "B.Cu")
		(net 1)
	)
	(via
		(at 95 164.4515)
		(size 0.45)
		(drill 0.1)
		(layers "F.Cu" "B.Cu")
		(net 1)
	)
	(via
		(at 150.906783 159.906783)
		(size 0.45)
		(drill 0.1)
		(layers "F.Cu" "B.Cu")
		(net 1)
	)
	(via
		(at 198.3 188.451)
		(size 0.45)
		(drill 0.1)
		(layers "F.Cu" "B.Cu")
		(net 1)
	)
	(via
		(at 182.88 179.07)
		(size 0.45)
		(drill 0.1)
		(layers "F.Cu" "B.Cu")
		(net 1)
	)
	(via
		(at 128.875501 174.801)
		(size 0.45)
		(drill 0.1)
		(layers "F.Cu" "B.Cu")
		(net 1)
	)
	(via
		(at 158.900002 145.127501)
		(size 0.45)
		(drill 0.1)
		(layers "F.Cu" "B.Cu")
		(net 1)
	)
	(via
		(at 111.76 127)
		(size 0.45)
		(drill 0.1)
		(layers "F.Cu" "B.Cu")
		(net 1)
	)
	(via
		(at 132.877001 178.8005)
		(size 0.45)
		(drill 0.1)
		(layers "F.Cu" "B.Cu")
		(net 1)
	)
	(via
		(at 90.435 192.611)
		(size 0.45)
		(drill 0.1)
		(layers "F.Cu" "B.Cu")
		(net 1)
	)
	(via
		(at 86.36 198.12)
		(size 0.45)
		(drill 0.1)
		(layers "F.Cu" "B.Cu")
		(net 1)
	)
	(via
		(at 79.980501 187.315)
		(size 0.45)
		(drill 0.1)
		(layers "F.Cu" "B.Cu")
		(net 1)
	)
	(via
		(at 185.4 126.2)
		(size 0.45)
		(drill 0.1)
		(layers "F.Cu" "B.Cu")
		(net 1)
	)
	(via
		(at 87.7 112.1)
		(size 0.45)
		(drill 0.1)
		(layers "F.Cu" "B.Cu")
		(net 1)
	)
	(via
		(at 190.88 145.14)
		(size 0.45)
		(drill 0.1)
		(layers "F.Cu" "B.Cu")
		(net 1)
	)
	(via
		(at 199 162.7)
		(size 0.45)
		(drill 0.1)
		(layers "F.Cu" "B.Cu")
		(net 1)
	)
	(via
		(at 201.05 193.05)
		(size 0.45)
		(drill 0.1)
		(layers "F.Cu" "B.Cu")
		(net 1)
	)
	(via
		(at 101.616501 167.061)
		(size 0.45)
		(drill 0.1)
		(layers "F.Cu" "B.Cu")
		(net 1)
	)
	(via
		(at 102.240501 157.646)
		(size 0.45)
		(drill 0.1)
		(layers "F.Cu" "B.Cu")
		(net 1)
	)
	(via
		(at 148.1 112.1)
		(size 0.45)
		(drill 0.1)
		(layers "F.Cu" "B.Cu")
		(net 1)
	)
	(via
		(at 140.875001 173.8025)
		(size 0.45)
		(drill 0.1)
		(layers "F.Cu" "B.Cu")
		(net 1)
	)
	(via
		(at 78.17 158.3)
		(size 0.45)
		(drill 0.1)
		(layers "F.Cu" "B.Cu")
		(net 1)
	)
	(via
		(at 74.7 177.1)
		(size 0.45)
		(drill 0.1)
		(layers "F.Cu" "B.Cu")
		(net 1)
	)
	(via
		(at 128.200501 196.901)
		(size 0.45)
		(drill 0.1)
		(layers "F.Cu" "B.Cu")
		(net 1)
	)
	(via
		(at 141.875002 171.8025)
		(size 0.45)
		(drill 0.1)
		(layers "F.Cu" "B.Cu")
		(net 1)
	)
	(via
		(at 129.650001 137.7275)
		(size 0.45)
		(drill 0.1)
		(layers "F.Cu" "B.Cu")
		(net 1)
	)
	(via
		(at 125.73 199.39)
		(size 0.45)
		(drill 0.1)
		(layers "F.Cu" "B.Cu")
		(net 1)
	)
	(via
		(at 196.6975 184.3025)
		(size 0.45)
		(drill 0.1)
		(layers "F.Cu" "B.Cu")
		(net 1)
	)
	(via
		(at 74.7 185.8)
		(size 0.45)
		(drill 0.1)
		(layers "F.Cu" "B.Cu")
		(net 1)
	)
	(via
		(at 162.650002 137.727499)
		(size 0.45)
		(drill 0.1)
		(layers "F.Cu" "B.Cu")
		(net 1)
	)
	(via
		(at 92.800501 159.626)
		(size 0.45)
		(drill 0.1)
		(layers "F.Cu" "B.Cu")
		(net 1)
	)
	(via
		(at 163.8 200.6)
		(size 0.45)
		(drill 0.1)
		(layers "F.Cu" "B.Cu")
		(net 1)
	)
	(via
		(at 127 132.08)
		(size 0.45)
		(drill 0.1)
		(layers "F.Cu" "B.Cu")
		(net 1)
	)
	(via
		(at 136.877001 180.8005)
		(size 0.45)
		(drill 0.1)
		(layers "F.Cu" "B.Cu")
		(net 1)
	)
	(via
		(at 193.9 167.8)
		(size 0.45)
		(drill 0.1)
		(layers "F.Cu" "B.Cu")
		(net 1)
	)
	(via
		(at 96.15 157)
		(size 0.45)
		(drill 0.1)
		(layers "F.Cu" "B.Cu")
		(net 1)
	)
	(via
		(at 193.927 185.251)
		(size 0.45)
		(drill 0.1)
		(layers "F.Cu" "B.Cu")
		(net 1)
	)
	(via
		(at 111.76 116.84)
		(size 0.45)
		(drill 0.1)
		(layers "F.Cu" "B.Cu")
		(net 1)
	)
	(via
		(at 182.6 116.85)
		(size 0.45)
		(drill 0.1)
		(layers "F.Cu" "B.Cu")
		(net 1)
	)
	(via
		(at 206.0795 151.8035)
		(size 0.45)
		(drill 0.1)
		(layers "F.Cu" "B.Cu")
		(net 1)
	)
	(via
		(at 121.950501 196.876)
		(size 0.45)
		(drill 0.1)
		(layers "F.Cu" "B.Cu")
		(net 1)
	)
	(via
		(at 129.900501 174.801)
		(size 0.45)
		(drill 0.1)
		(layers "F.Cu" "B.Cu")
		(net 1)
	)
	(via
		(at 149.650501 145.076)
		(size 0.45)
		(drill 0.1)
		(layers "F.Cu" "B.Cu")
		(net 1)
	)
	(via
		(at 104.14 139.7)
		(size 0.45)
		(drill 0.1)
		(layers "F.Cu" "B.Cu")
		(net 1)
	)
	(via
		(at 122.600501 196.876)
		(size 0.45)
		(drill 0.1)
		(layers "F.Cu" "B.Cu")
		(net 1)
	)
	(via
		(at 147.7 201.1)
		(size 0.45)
		(drill 0.1)
		(layers "F.Cu" "B.Cu")
		(net 1)
	)
	(via
		(at 205.8 187.95)
		(size 0.45)
		(drill 0.1)
		(layers "F.Cu" "B.Cu")
		(net 1)
	)
	(via
		(at 76.702001 155.3)
		(size 0.45)
		(drill 0.1)
		(layers "F.Cu" "B.Cu")
		(net 1)
	)
	(via
		(at 76.2 162.56)
		(size 0.45)
		(drill 0.1)
		(layers "F.Cu" "B.Cu")
		(net 1)
	)
	(via
		(at 121.45 173.1)
		(size 0.45)
		(drill 0.1)
		(layers "F.Cu" "B.Cu")
		(net 1)
	)
	(via
		(at 76.723501 151.5)
		(size 0.45)
		(drill 0.1)
		(layers "F.Cu" "B.Cu")
		(net 1)
	)
	(via
		(at 95.5 197.9)
		(size 0.45)
		(drill 0.1)
		(layers "F.Cu" "B.Cu")
		(net 1)
	)
	(via
		(at 91.689501 177.069)
		(size 0.45)
		(drill 0.1)
		(layers "F.Cu" "B.Cu")
		(net 1)
	)
	(via
		(at 181.082 155.740998)
		(size 0.45)
		(drill 0.1)
		(layers "F.Cu" "B.Cu")
		(net 1)
	)
	(via
		(at 203.752 147.7)
		(size 0.45)
		(drill 0.1)
		(layers "F.Cu" "B.Cu")
		(net 1)
	)
	(via
		(at 115.55 191.15)
		(size 0.45)
		(drill 0.1)
		(layers "F.Cu" "B.Cu")
		(net 1)
	)
	(via
		(at 118.900001 145.1275)
		(size 0.45)
		(drill 0.1)
		(layers "F.Cu" "B.Cu")
		(net 1)
	)
	(via
		(at 136.877001 176.8005)
		(size 0.45)
		(drill 0.1)
		(layers "F.Cu" "B.Cu")
		(net 1)
	)
	(via
		(at 161.650002 137.7275)
		(size 0.45)
		(drill 0.1)
		(layers "F.Cu" "B.Cu")
		(net 1)
	)
	(via
		(at 169.15 137.727499)
		(size 0.45)
		(drill 0.1)
		(layers "F.Cu" "B.Cu")
		(net 1)
	)
	(via
		(at 149.15 139.877499)
		(size 0.45)
		(drill 0.1)
		(layers "F.Cu" "B.Cu")
		(net 1)
	)
	(via
		(at 119.900001 145.1275)
		(size 0.45)
		(drill 0.1)
		(layers "F.Cu" "B.Cu")
		(net 1)
	)
	(via
		(at 183.330501 131.306)
		(size 0.45)
		(drill 0.1)
		(layers "F.Cu" "B.Cu")
		(net 1)
	)
	(via
		(at 171.200501 195.776)
		(size 0.45)
		(drill 0.1)
		(layers "F.Cu" "B.Cu")
		(net 1)
	)
	(via
		(at 158.084 141.916)
		(size 0.45)
		(drill 0.1)
		(layers "F.Cu" "B.Cu")
		(net 1)
	)
	(via
		(at 154.400501 137.676)
		(size 0.45)
		(drill 0.1)
		(layers "F.Cu" "B.Cu")
		(net 1)
	)
	(via
		(at 101.375251 160.2955)
		(size 0.45)
		(drill 0.1)
		(layers "F.Cu" "B.Cu")
		(net 1)
	)
	(via
		(at 79.980501 194.816)
		(size 0.45)
		(drill 0.1)
		(layers "F.Cu" "B.Cu")
		(net 1)
	)
	(via
		(at 147.32 132.08)
		(size 0.45)
		(drill 0.1)
		(layers "F.Cu" "B.Cu")
		(net 1)
	)
	(via
		(at 97.4 193.1)
		(size 0.45)
		(drill 0.1)
		(layers "F.Cu" "B.Cu")
		(net 1)
	)
	(via
		(at 159.4355 182.693)
		(size 0.45)
		(drill 0.1)
		(layers "F.Cu" "B.Cu")
		(net 1)
	)
	(via
		(at 191.95 199.3)
		(size 0.45)
		(drill 0.1)
		(layers "F.Cu" "B.Cu")
		(net 1)
	)
	(via
		(at 116.1 112.1)
		(size 0.45)
		(drill 0.1)
		(layers "F.Cu" "B.Cu")
		(net 1)
	)
	(via
		(at 157.48 132.08)
		(size 0.45)
		(drill 0.1)
		(layers "F.Cu" "B.Cu")
		(net 1)
	)
	(via
		(at 171.800501 194.976)
		(size 0.45)
		(drill 0.1)
		(layers "F.Cu" "B.Cu")
		(net 1)
	)
	(via
		(at 136.877001 169.8025)
		(size 0.45)
		(drill 0.1)
		(layers "F.Cu" "B.Cu")
		(net 1)
	)
	(via
		(at 141.7 112.1)
		(size 0.45)
		(drill 0.1)
		(layers "F.Cu" "B.Cu")
		(net 1)
	)
	(via
		(at 189.865 142.165)
		(size 0.45)
		(drill 0.1)
		(layers "F.Cu" "B.Cu")
		(net 1)
	)
	(via
		(at 164.1 112.1)
		(size 0.45)
		(drill 0.1)
		(layers "F.Cu" "B.Cu")
		(net 1)
	)
	(via
		(at 148.875001 182.800499)
		(size 0.45)
		(drill 0.1)
		(layers "F.Cu" "B.Cu")
		(net 1)
	)
	(via
		(at 199 200.6)
		(size 0.45)
		(drill 0.1)
		(layers "F.Cu" "B.Cu")
		(net 1)
	)
	(via
		(at 102.900501 157.636)
		(size 0.45)
		(drill 0.1)
		(layers "F.Cu" "B.Cu")
		(net 1)
	)
	(via
		(at 131.400001 145.1275)
		(size 0.45)
		(drill 0.1)
		(layers "F.Cu" "B.Cu")
		(net 1)
	)
	(via
		(at 101.5 200.2)
		(size 0.45)
		(drill 0.1)
		(layers "F.Cu" "B.Cu")
		(net 1)
	)
	(via
		(at 120.855001 206.340501)
		(size 0.45)
		(drill 0.1)
		(layers "F.Cu" "B.Cu")
		(net 1)
	)
	(via
		(at 102.85 180.95)
		(size 0.45)
		(drill 0.1)
		(layers "F.Cu" "B.Cu")
		(net 1)
	)
	(via
		(at 107.826 180.2)
		(size 0.45)
		(drill 0.1)
		(layers "F.Cu" "B.Cu")
		(net 1)
	)
	(via
		(at 206.3 118.5)
		(size 0.45)
		(drill 0.1)
		(layers "F.Cu" "B.Cu")
		(net 1)
	)
	(via
		(at 175.500501 192.776)
		(size 0.45)
		(drill 0.1)
		(layers "F.Cu" "B.Cu")
		(net 1)
	)
	(via
		(at 171.000501 196.376)
		(size 0.45)
		(drill 0.1)
		(layers "F.Cu" "B.Cu")
		(net 1)
	)
	(via
		(at 145.875001 182.8005)
		(size 0.45)
		(drill 0.1)
		(layers "F.Cu" "B.Cu")
		(net 1)
	)
	(via
		(at 198.45 195.7)
		(size 0.45)
		(drill 0.1)
		(layers "F.Cu" "B.Cu")
		(net 1)
	)
	(via
		(at 129.877001 168.8025)
		(size 0.45)
		(drill 0.1)
		(layers "F.Cu" "B.Cu")
		(net 1)
	)
	(via
		(at 103.780501 114.826)
		(size 0.45)
		(drill 0.1)
		(layers "F.Cu" "B.Cu")
		(net 1)
	)
	(via
		(at 204.85 169.95)
		(size 0.45)
		(drill 0.1)
		(layers "F.Cu" "B.Cu")
		(net 1)
	)
	(via
		(at 89.527244 167.295)
		(size 0.45)
		(drill 0.1)
		(layers "F.Cu" "B.Cu")
		(net 1)
	)
	(via
		(at 125.7 112.1)
		(size 0.45)
		(drill 0.1)
		(layers "F.Cu" "B.Cu")
		(net 1)
	)
	(via
		(at 194.15 194.3)
		(size 0.45)
		(drill 0.1)
		(layers "F.Cu" "B.Cu")
		(net 1)
	)
	(via
		(at 164.470501 183.388001)
		(size 0.45)
		(drill 0.1)
		(layers "F.Cu" "B.Cu")
		(net 1)
	)
	(via
		(at 194.15 193.56)
		(size 0.45)
		(drill 0.1)
		(layers "F.Cu" "B.Cu")
		(net 1)
	)
	(via
		(at 126.877001 180.8005)
		(size 0.45)
		(drill 0.1)
		(layers "F.Cu" "B.Cu")
		(net 1)
	)
	(via
		(at 151.6 141.5)
		(size 0.45)
		(drill 0.1)
		(layers "F.Cu" "B.Cu")
		(net 1)
	)
	(via
		(at 100.7 191.4)
		(size 0.45)
		(drill 0.1)
		(layers "F.Cu" "B.Cu")
		(net 1)
	)
	(via
		(at 198.020501 184.3105)
		(size 0.45)
		(drill 0.1)
		(layers "F.Cu" "B.Cu")
		(net 1)
	)
	(via
		(at 78.74 175.26)
		(size 0.45)
		(drill 0.1)
		(layers "F.Cu" "B.Cu")
		(net 1)
	)
	(via
		(at 157.900001 145.127499)
		(size 0.45)
		(drill 0.1)
		(layers "F.Cu" "B.Cu")
		(net 1)
	)
	(via
		(at 74.7 167.5)
		(size 0.45)
		(drill 0.1)
		(layers "F.Cu" "B.Cu")
		(net 1)
	)
	(via
		(at 111.400001 145.1275)
		(size 0.45)
		(drill 0.1)
		(layers "F.Cu" "B.Cu")
		(net 1)
	)
	(via
		(at 148.875001 180.8005)
		(size 0.45)
		(drill 0.1)
		(layers "F.Cu" "B.Cu")
		(net 1)
	)
	(via
		(at 95.4 131)
		(size 0.45)
		(drill 0.1)
		(layers "F.Cu" "B.Cu")
		(net 1)
	)
	(via
		(at 175.7 131.1)
		(size 0.45)
		(drill 0.1)
		(layers "F.Cu" "B.Cu")
		(net 1)
	)
	(via
		(at 156.9 145.1275)
		(size 0.45)
		(drill 0.1)
		(layers "F.Cu" "B.Cu")
		(net 1)
	)
	(via
		(at 115.57 179.07)
		(size 0.45)
		(drill 0.1)
		(layers "F.Cu" "B.Cu")
		(net 1)
	)
	(via
		(at 138.5 112.1)
		(size 0.45)
		(drill 0.1)
		(layers "F.Cu" "B.Cu")
		(net 1)
	)
	(via
		(at 147.875001 172.8025)
		(size 0.45)
		(drill 0.1)
		(layers "F.Cu" "B.Cu")
		(net 1)
	)
	(via
		(at 182.1 190.65)
		(size 0.45)
		(drill 0.1)
		(layers "F.Cu" "B.Cu")
		(net 1)
	)
	(via
		(at 204.3 192.1)
		(size 0.45)
		(drill 0.1)
		(layers "F.Cu" "B.Cu")
		(net 1)
	)
	(via
		(at 94.8 156.95)
		(size 0.45)
		(drill 0.1)
		(layers "F.Cu" "B.Cu")
		(net 1)
	)
	(via
		(at 90.402877 189.539001)
		(size 0.45)
		(drill 0.1)
		(layers "F.Cu" "B.Cu")
		(net 1)
	)
	(via
		(at 116.150001 137.7275)
		(size 0.45)
		(drill 0.1)
		(layers "F.Cu" "B.Cu")
		(net 1)
	)
	(via
		(at 96.6 141.4)
		(size 0.45)
		(drill 0.1)
		(layers "F.Cu" "B.Cu")
		(net 1)
	)
	(via
		(at 137.16 121.92)
		(size 0.45)
		(drill 0.1)
		(layers "F.Cu" "B.Cu")
		(net 1)
	)
	(via
		(at 110.400001 145.1275)
		(size 0.45)
		(drill 0.1)
		(layers "F.Cu" "B.Cu")
		(net 1)
	)
	(via
		(at 97.75 134.96)
		(size 0.45)
		(drill 0.1)
		(layers "F.Cu" "B.Cu")
		(net 1)
	)
	(via
		(at 105.9 145.2)
		(size 0.45)
		(drill 0.1)
		(layers "F.Cu" "B.Cu")
		(net 1)
	)
	(via
		(at 149.875001 182.8005)
		(size 0.45)
		(drill 0.1)
		(layers "F.Cu" "B.Cu")
		(net 1)
	)
	(via
		(at 125.900001 145.1275)
		(size 0.45)
		(drill 0.1)
		(layers "F.Cu" "B.Cu")
		(net 1)
	)
	(via
		(at 93.8 156.95)
		(size 0.45)
		(drill 0.1)
		(layers "F.Cu" "B.Cu")
		(net 1)
	)
	(via
		(at 199 171)
		(size 0.45)
		(drill 0.1)
		(layers "F.Cu" "B.Cu")
		(net 1)
	)
	(via
		(at 203.7485 134.5285)
		(size 0.45)
		(drill 0.1)
		(layers "F.Cu" "B.Cu")
		(net 1)
	)
	(via
		(at 134.877001 173.8025)
		(size 0.45)
		(drill 0.1)
		(layers "F.Cu" "B.Cu")
		(net 1)
	)
	(via
		(at 206.3 131.3)
		(size 0.45)
		(drill 0.1)
		(layers "F.Cu" "B.Cu")
		(net 1)
	)
	(via
		(at 197.131001 165.999)
		(size 0.45)
		(drill 0.1)
		(layers "F.Cu" "B.Cu")
		(net 1)
	)
	(via
		(at 88.2 194.111)
		(size 0.45)
		(drill 0.1)
		(layers "F.Cu" "B.Cu")
		(net 1)
	)
	(via
		(at 147.400001 147.2775)
		(size 0.45)
		(drill 0.1)
		(layers "F.Cu" "B.Cu")
		(net 1)
	)
	(via
		(at 86.591829 154.583157)
		(size 0.45)
		(drill 0.1)
		(layers "F.Cu" "B.Cu")
		(net 1)
	)
	(via
		(at 206.3 115.3)
		(size 0.45)
		(drill 0.1)
		(layers "F.Cu" "B.Cu")
		(net 1)
	)
	(via
		(at 104.14 198.12)
		(size 0.45)
		(drill 0.1)
		(layers "F.Cu" "B.Cu")
		(net 1)
	)
	(via
		(at 103.910501 154.936)
		(size 0.45)
		(drill 0.1)
		(layers "F.Cu" "B.Cu")
		(net 1)
	)
	(via
		(at 179.505 198.813)
		(size 0.45)
		(drill 0.1)
		(layers "F.Cu" "B.Cu")
		(net 1)
	)
	(via
		(at 123.250501 197.976)
		(size 0.45)
		(drill 0.1)
		(layers "F.Cu" "B.Cu")
		(net 1)
	)
	(via
		(at 130.650001 137.7275)
		(size 0.45)
		(drill 0.1)
		(layers "F.Cu" "B.Cu")
		(net 1)
	)
	(via
		(at 103.875001 148.3025)
		(size 0.45)
		(drill 0.1)
		(layers "F.Cu" "B.Cu")
		(net 1)
	)
	(via
		(at 197.131001 167.722)
		(size 0.45)
		(drill 0.1)
		(layers "F.Cu" "B.Cu")
		(net 1)
	)
	(via
		(at 169.355502 196.35)
		(size 0.45)
		(drill 0.1)
		(layers "F.Cu" "B.Cu")
		(net 1)
	)
	(via
		(at 147.875001 169.8025)
		(size 0.45)
		(drill 0.1)
		(layers "F.Cu" "B.Cu")
		(net 1)
	)
	(via
		(at 85.750501 157.073149)
		(size 0.45)
		(drill 0.1)
		(layers "F.Cu" "B.Cu")
		(net 1)
	)
	(via
		(at 83.502 194.1)
		(size 0.45)
		(drill 0.1)
		(layers "F.Cu" "B.Cu")
		(net 1)
	)
	(via
		(at 115.300001 184.5)
		(size 0.45)
		(drill 0.1)
		(layers "F.Cu" "B.Cu")
		(net 1)
	)
	(via
		(at 191.948 166.774)
		(size 0.45)
		(drill 0.1)
		(layers "F.Cu" "B.Cu")
		(net 1)
	)
	(via
		(at 177.8 146.05)
		(size 0.45)
		(drill 0.1)
		(layers "F.Cu" "B.Cu")
		(net 1)
	)
	(via
		(at 84.300501 124.606)
		(size 0.45)
		(drill 0.1)
		(layers "F.Cu" "B.Cu")
		(net 1)
	)
	(via
		(at 128.877001 165.8025)
		(size 0.45)
		(drill 0.1)
		(layers "F.Cu" "B.Cu")
		(net 1)
	)
	(via
		(at 174.8955 176.3985)
		(size 0.45)
		(drill 0.1)
		(layers "F.Cu" "B.Cu")
		(net 1)
	)
	(via
		(at 204.85 186.6)
		(size 0.45)
		(drill 0.1)
		(layers "F.Cu" "B.Cu")
		(net 1)
	)
	(via
		(at 103.275001 148.9185)
		(size 0.45)
		(drill 0.1)
		(layers "F.Cu" "B.Cu")
		(net 1)
	)
	(via
		(at 121.92 116.84)
		(size 0.45)
		(drill 0.1)
		(layers "F.Cu" "B.Cu")
		(net 1)
	)
	(via
		(at 140.875001 170.8025)
		(size 0.45)
		(drill 0.1)
		(layers "F.Cu" "B.Cu")
		(net 1)
	)
	(via
		(at 173.575002 133.78)
		(size 0.45)
		(drill 0.1)
		(layers "F.Cu" "B.Cu")
		(net 1)
	)
	(via
		(at 87.391829 150.583157)
		(size 0.45)
		(drill 0.1)
		(layers "F.Cu" "B.Cu")
		(net 1)
	)
	(via
		(at 100.1 112.1)
		(size 0.45)
		(drill 0.1)
		(layers "F.Cu" "B.Cu")
		(net 1)
	)
	(via
		(at 154.9 145.127499)
		(size 0.45)
		(drill 0.1)
		(layers "F.Cu" "B.Cu")
		(net 1)
	)
	(via
		(at 203.75 170.9)
		(size 0.45)
		(drill 0.1)
		(layers "F.Cu" "B.Cu")
		(net 1)
	)
	(via
		(at 171.9 156.3)
		(size 0.45)
		(drill 0.1)
		(layers "F.Cu" "B.Cu")
		(net 1)
	)
	(via
		(at 187.2 142.165)
		(size 0.45)
		(drill 0.1)
		(layers "F.Cu" "B.Cu")
		(net 1)
	)
	(via
		(at 144.000501 206.400501)
		(size 0.45)
		(drill 0.1)
		(layers "F.Cu" "B.Cu")
		(net 1)
	)
	(via
		(at 106.5 112.1)
		(size 0.45)
		(drill 0.1)
		(layers "F.Cu" "B.Cu")
		(net 1)
	)
	(via
		(at 161.400001 145.1275)
		(size 0.45)
		(drill 0.1)
		(layers "F.Cu" "B.Cu")
		(net 1)
	)
	(via
		(at 198.881001 183.45)
		(size 0.45)
		(drill 0.1)
		(layers "F.Cu" "B.Cu")
		(net 1)
	)
	(via
		(at 206.3 121.7)
		(size 0.45)
		(drill 0.1)
		(layers "F.Cu" "B.Cu")
		(net 1)
	)
	(via
		(at 191.975 184.225)
		(size 0.45)
		(drill 0.1)
		(layers "F.Cu" "B.Cu")
		(net 1)
	)
	(via
		(at 151 200.6)
		(size 0.45)
		(drill 0.1)
		(layers "F.Cu" "B.Cu")
		(net 1)
	)
	(via
		(at 184.2 169)
		(size 0.45)
		(drill 0.1)
		(layers "F.Cu" "B.Cu")
		(net 1)
	)
	(via
		(at 107.926 183.218)
		(size 0.45)
		(drill 0.1)
		(layers "F.Cu" "B.Cu")
		(net 1)
	)
	(via
		(at 139.875001 176.8005)
		(size 0.45)
		(drill 0.1)
		(layers "F.Cu" "B.Cu")
		(net 1)
	)
	(via
		(at 142.875001 172.8025)
		(size 0.45)
		(drill 0.1)
		(layers "F.Cu" "B.Cu")
		(net 1)
	)
	(via
		(at 183.5 196.15)
		(size 0.45)
		(drill 0.1)
		(layers "F.Cu" "B.Cu")
		(net 1)
	)
	(via
		(at 203.75 187.9)
		(size 0.45)
		(drill 0.1)
		(layers "F.Cu" "B.Cu")
		(net 1)
	)
	(via
		(at 168.4 145.127499)
		(size 0.45)
		(drill 0.1)
		(layers "F.Cu" "B.Cu")
		(net 1)
	)
	(via
		(at 198.85 188.45)
		(size 0.45)
		(drill 0.1)
		(layers "F.Cu" "B.Cu")
		(net 1)
	)
	(via
		(at 190.3 184.9)
		(size 0.45)
		(drill 0.1)
		(layers "F.Cu" "B.Cu")
		(net 1)
	)
	(via
		(at 186.425 126.5)
		(size 0.45)
		(drill 0.1)
		(layers "F.Cu" "B.Cu")
		(net 1)
	)
	(via
		(at 108.1 131.1)
		(size 0.45)
		(drill 0.1)
		(layers "F.Cu" "B.Cu")
		(net 1)
	)
	(via
		(at 137.877002 175.8005)
		(size 0.45)
		(drill 0.1)
		(layers "F.Cu" "B.Cu")
		(net 1)
	)
	(via
		(at 135.877001 187.8005)
		(size 0.45)
		(drill 0.1)
		(layers "F.Cu" "B.Cu")
		(net 1)
	)
	(via
		(at 167.150001 137.7275)
		(size 0.45)
		(drill 0.1)
		(layers "F.Cu" "B.Cu")
		(net 1)
	)
	(via
		(at 140.875001 172.8025)
		(size 0.45)
		(drill 0.1)
		(layers "F.Cu" "B.Cu")
		(net 1)
	)
	(via
		(at 144.875001 181.800501)
		(size 0.45)
		(drill 0.1)
		(layers "F.Cu" "B.Cu")
		(net 1)
	)
	(via
		(at 166 168.7)
		(size 0.45)
		(drill 0.1)
		(layers "F.Cu" "B.Cu")
		(net 1)
	)
	(via
		(at 105.975002 133.78)
		(size 0.45)
		(drill 0.1)
		(layers "F.Cu" "B.Cu")
		(net 1)
	)
	(via
		(at 203.7 169.075)
		(size 0.45)
		(drill 0.1)
		(layers "F.Cu" "B.Cu")
		(net 1)
	)
	(via
		(at 193.3 166.8)
		(size 0.45)
		(drill 0.1)
		(layers "F.Cu" "B.Cu")
		(net 1)
	)
	(via
		(at 200.8 162.7)
		(size 0.45)
		(drill 0.1)
		(layers "F.Cu" "B.Cu")
		(net 1)
	)
	(via
		(at 144.875001 172.8025)
		(size 0.45)
		(drill 0.1)
		(layers "F.Cu" "B.Cu")
		(net 1)
	)
	(via
		(at 91.899 197.9)
		(size 0.45)
		(drill 0.1)
		(layers "F.Cu" "B.Cu")
		(net 1)
	)
	(via
		(at 154.075001 167.5025)
		(size 0.45)
		(drill 0.1)
		(layers "F.Cu" "B.Cu")
		(net 1)
	)
	(via
		(at 189.775 139.4)
		(size 0.45)
		(drill 0.1)
		(layers "F.Cu" "B.Cu")
		(net 1)
	)
	(via
		(at 122.675001 205.800501)
		(size 0.45)
		(drill 0.1)
		(layers "F.Cu" "B.Cu")
		(net 1)
	)
	(via
		(at 84.75 129.05)
		(size 0.45)
		(drill 0.1)
		(layers "F.Cu" "B.Cu")
		(net 1)
	)
	(via
		(at 127.650001 137.7275)
		(size 0.45)
		(drill 0.1)
		(layers "F.Cu" "B.Cu")
		(net 1)
	)
	(via
		(at 90.928157 152.143165)
		(size 0.45)
		(drill 0.1)
		(layers "F.Cu" "B.Cu")
		(net 1)
	)
	(via
		(at 205.4 192.1)
		(size 0.45)
		(drill 0.1)
		(layers "F.Cu" "B.Cu")
		(net 1)
	)
	(via
		(at 197.027 180.151)
		(size 0.45)
		(drill 0.1)
		(layers "F.Cu" "B.Cu")
		(net 1)
	)
	(via
		(at 170.150001 137.727499)
		(size 0.45)
		(drill 0.1)
		(layers "F.Cu" "B.Cu")
		(net 1)
	)
	(via
		(at 151.875001 177.8005)
		(size 0.45)
		(drill 0.1)
		(layers "F.Cu" "B.Cu")
		(net 1)
	)
	(via
		(at 135.877002 177.8005)
		(size 0.45)
		(drill 0.1)
		(layers "F.Cu" "B.Cu")
		(net 1)
	)
	(via
		(at 195.375 141.225)
		(size 0.45)
		(drill 0.1)
		(layers "F.Cu" "B.Cu")
		(net 1)
	)
	(via
		(at 136.877001 171.8025)
		(size 0.45)
		(drill 0.1)
		(layers "F.Cu" "B.Cu")
		(net 1)
	)
	(via
		(at 198.714499 146.801)
		(size 0.45)
		(drill 0.1)
		(layers "F.Cu" "B.Cu")
		(net 1)
	)
	(via
		(at 189.125 184.925)
		(size 0.45)
		(drill 0.1)
		(layers "F.Cu" "B.Cu")
		(net 1)
	)
	(via
		(at 103.875001 147.7025)
		(size 0.45)
		(drill 0.1)
		(layers "F.Cu" "B.Cu")
		(net 1)
	)
	(via
		(at 121 191.1)
		(size 0.45)
		(drill 0.1)
		(layers "F.Cu" "B.Cu")
		(net 1)
	)
	(via
		(at 166.1 183.9)
		(size 0.45)
		(drill 0.1)
		(layers "F.Cu" "B.Cu")
		(net 1)
	)
	(via
		(at 203.75 169.95)
		(size 0.45)
		(drill 0.1)
		(layers "F.Cu" "B.Cu")
		(net 1)
	)
	(via
		(at 120.19 154.72)
		(size 0.45)
		(drill 0.1)
		(layers "F.Cu" "B.Cu")
		(net 1)
	)
	(via
		(at 202.251001 188.15)
		(size 0.45)
		(drill 0.1)
		(layers "F.Cu" "B.Cu")
		(net 1)
	)
	(via
		(at 172.72 162.56)
		(size 0.45)
		(drill 0.1)
		(layers "F.Cu" "B.Cu")
		(net 1)
	)
	(via
		(at 152.4 194.31)
		(size 0.45)
		(drill 0.1)
		(layers "F.Cu" "B.Cu")
		(net 1)
	)
	(via
		(at 98.3 131)
		(size 0.45)
		(drill 0.1)
		(layers "F.Cu" "B.Cu")
		(net 1)
	)
	(via
		(at 170.600501 195.876)
		(size 0.45)
		(drill 0.1)
		(layers "F.Cu" "B.Cu")
		(net 1)
	)
	(via
		(at 190.15 166.275)
		(size 0.45)
		(drill 0.1)
		(layers "F.Cu" "B.Cu")
		(net 1)
	)
	(via
		(at 122.925501 197.426)
		(size 0.45)
		(drill 0.1)
		(layers "F.Cu" "B.Cu")
		(net 1)
	)
	(via
		(at 156.650002 137.7275)
		(size 0.45)
		(drill 0.1)
		(layers "F.Cu" "B.Cu")
		(net 1)
	)
	(via
		(at 163.650003 137.727499)
		(size 0.45)
		(drill 0.1)
		(layers "F.Cu" "B.Cu")
		(net 1)
	)
	(via
		(at 147.32 121.92)
		(size 0.45)
		(drill 0.1)
		(layers "F.Cu" "B.Cu")
		(net 1)
	)
	(via
		(at 154 172.904)
		(size 0.45)
		(drill 0.1)
		(layers "F.Cu" "B.Cu")
		(net 1)
	)
	(via
		(at 183.057 147.984002)
		(size 0.45)
		(drill 0.1)
		(layers "F.Cu" "B.Cu")
		(net 1)
	)
	(via
		(at 113.150001 137.7275)
		(size 0.45)
		(drill 0.1)
		(layers "F.Cu" "B.Cu")
		(net 1)
	)
	(via
		(at 164.400001 145.127499)
		(size 0.45)
		(drill 0.1)
		(layers "F.Cu" "B.Cu")
		(net 1)
	)
	(via
		(at 116.84 132.08)
		(size 0.45)
		(drill 0.1)
		(layers "F.Cu" "B.Cu")
		(net 1)
	)
	(via
		(at 79.085 160.6)
		(size 0.45)
		(drill 0.1)
		(layers "F.Cu" "B.Cu")
		(net 1)
	)
	(via
		(at 133.900001 147.2775)
		(size 0.45)
		(drill 0.1)
		(layers "F.Cu" "B.Cu")
		(net 1)
	)
	(via
		(at 118.150501 173.426)
		(size 0.45)
		(drill 0.1)
		(layers "F.Cu" "B.Cu")
		(net 1)
	)
	(via
		(at 152.374503 185.301)
		(size 0.45)
		(drill 0.1)
		(layers "F.Cu" "B.Cu")
		(net 1)
	)
	(via
		(at 184.431 128.2)
		(size 0.45)
		(drill 0.1)
		(layers "F.Cu" "B.Cu")
		(net 1)
	)
	(via
		(at 203.75 187.25)
		(size 0.45)
		(drill 0.1)
		(layers "F.Cu" "B.Cu")
		(net 1)
	)
	(via
		(at 172.150001 137.7275)
		(size 0.45)
		(drill 0.1)
		(layers "F.Cu" "B.Cu")
		(net 1)
	)
	(via
		(at 121 195.25)
		(size 0.45)
		(drill 0.1)
		(layers "F.Cu" "B.Cu")
		(net 1)
	)
	(via
		(at 193.527 179.401)
		(size 0.45)
		(drill 0.1)
		(layers "F.Cu" "B.Cu")
		(net 1)
	)
	(via
		(at 85 118.6)
		(size 0.45)
		(drill 0.1)
		(layers "F.Cu" "B.Cu")
		(net 1)
	)
	(via
		(at 167.64 132.08)
		(size 0.45)
		(drill 0.1)
		(layers "F.Cu" "B.Cu")
		(net 1)
	)
	(via
		(at 189.125 183.675)
		(size 0.45)
		(drill 0.1)
		(layers "F.Cu" "B.Cu")
		(net 1)
	)
	(via
		(at 142.875001 175.8005)
		(size 0.45)
		(drill 0.1)
		(layers "F.Cu" "B.Cu")
		(net 1)
	)
	(via
		(at 183 200.6)
		(size 0.45)
		(drill 0.1)
		(layers "F.Cu" "B.Cu")
		(net 1)
	)
	(via
		(at 163.502 174.2)
		(size 0.45)
		(drill 0.1)
		(layers "F.Cu" "B.Cu")
		(net 1)
	)
	(via
		(at 108.400001 145.1275)
		(size 0.45)
		(drill 0.1)
		(layers "F.Cu" "B.Cu")
		(net 1)
	)
	(via
		(at 185.152 123.346)
		(size 0.45)
		(drill 0.1)
		(layers "F.Cu" "B.Cu")
		(net 1)
	)
	(via
		(at 125.650001 137.7275)
		(size 0.45)
		(drill 0.1)
		(layers "F.Cu" "B.Cu")
		(net 1)
	)
	(via
		(at 103.850002 131.105)
		(size 0.45)
		(drill 0.1)
		(layers "F.Cu" "B.Cu")
		(net 1)
	)
	(via
		(at 204.85 187.2)
		(size 0.45)
		(drill 0.1)
		(layers "F.Cu" "B.Cu")
		(net 1)
	)
	(via
		(at 112.9 112.1)
		(size 0.45)
		(drill 0.1)
		(layers "F.Cu" "B.Cu")
		(net 1)
	)
	(via
		(at 156.002501 175.976)
		(size 0.45)
		(drill 0.1)
		(layers "F.Cu" "B.Cu")
		(net 1)
	)
	(via
		(at 148.875001 162.8025)
		(size 0.45)
		(drill 0.1)
		(layers "F.Cu" "B.Cu")
		(net 1)
	)
	(via
		(at 119.150001 137.7275)
		(size 0.45)
		(drill 0.1)
		(layers "F.Cu" "B.Cu")
		(net 1)
	)
	(via
		(at 150.875002 179.8005)
		(size 0.45)
		(drill 0.1)
		(layers "F.Cu" "B.Cu")
		(net 1)
	)
	(via
		(at 140.875001 175.8005)
		(size 0.45)
		(drill 0.1)
		(layers "F.Cu" "B.Cu")
		(net 1)
	)
	(via
		(at 162.56 198.755)
		(size 0.45)
		(drill 0.1)
		(layers "F.Cu" "B.Cu")
		(net 1)
	)
	(via
		(at 122 177.4265)
		(size 0.45)
		(drill 0.1)
		(layers "F.Cu" "B.Cu")
		(net 1)
	)
	(via
		(at 205.8 170)
		(size 0.45)
		(drill 0.1)
		(layers "F.Cu" "B.Cu")
		(net 1)
	)
	(via
		(at 145.875001 184.8005)
		(size 0.45)
		(drill 0.1)
		(layers "F.Cu" "B.Cu")
		(net 1)
	)
	(via
		(at 196.5975 185.7025)
		(size 0.45)
		(drill 0.1)
		(layers "F.Cu" "B.Cu")
		(net 1)
	)
	(via
		(at 140.050501 206.400501)
		(size 0.45)
		(drill 0.1)
		(layers "F.Cu" "B.Cu")
		(net 1)
	)
	(via
		(at 152.374503 183.301)
		(size 0.45)
		(drill 0.1)
		(layers "F.Cu" "B.Cu")
		(net 1)
	)
	(via
		(at 130.400001 145.1275)
		(size 0.45)
		(drill 0.1)
		(layers "F.Cu" "B.Cu")
		(net 1)
	)
	(via
		(at 206.3 147.3)
		(size 0.45)
		(drill 0.1)
		(layers "F.Cu" "B.Cu")
		(net 1)
	)
	(via
		(at 128 194)
		(size 0.45)
		(drill 0.1)
		(layers "F.Cu" "B.Cu")
		(net 1)
	)
	(via
		(at 122.600501 197.976)
		(size 0.45)
		(drill 0.1)
		(layers "F.Cu" "B.Cu")
		(net 1)
	)
	(via
		(at 88.7 200.2)
		(size 0.45)
		(drill 0.1)
		(layers "F.Cu" "B.Cu")
		(net 1)
	)
	(via
		(at 83.6 151.7)
		(size 0.45)
		(drill 0.1)
		(layers "F.Cu" "B.Cu")
		(net 1)
	)
	(via
		(at 103.780501 117.526)
		(size 0.45)
		(drill 0.1)
		(layers "F.Cu" "B.Cu")
		(net 1)
	)
	(via
		(at 129.877 179.8005)
		(size 0.45)
		(drill 0.1)
		(layers "F.Cu" "B.Cu")
		(net 1)
	)
	(via
		(at 110.650001 137.7275)
		(size 0.45)
		(drill 0.1)
		(layers "F.Cu" "B.Cu")
		(net 1)
	)
	(via
		(at 181.6 136.575)
		(size 0.45)
		(drill 0.1)
		(layers "F.Cu" "B.Cu")
		(net 1)
	)
	(via
		(at 205.299998 148.802)
		(size 0.45)
		(drill 0.1)
		(layers "F.Cu" "B.Cu")
		(net 1)
	)
	(via
		(at 87.000501 124.606)
		(size 0.45)
		(drill 0.1)
		(layers "F.Cu" "B.Cu")
		(net 1)
	)
	(via
		(at 155.399501 137.676)
		(size 0.45)
		(drill 0.1)
		(layers "F.Cu" "B.Cu")
		(net 1)
	)
	(via
		(at 127.550501 198.001)
		(size 0.45)
		(drill 0.1)
		(layers "F.Cu" "B.Cu")
		(net 1)
	)
	(via
		(at 145.875001 175.8005)
		(size 0.45)
		(drill 0.1)
		(layers "F.Cu" "B.Cu")
		(net 1)
	)
	(via
		(at 184.9 184.4)
		(size 0.45)
		(drill 0.1)
		(layers "F.Cu" "B.Cu")
		(net 1)
	)
	(via
		(at 134.725 143.5)
		(size 0.45)
		(drill 0.1)
		(layers "F.Cu" "B.Cu")
		(net 1)
	)
	(via
		(at 74.420501 164.236)
		(size 0.45)
		(drill 0.1)
		(layers "F.Cu" "B.Cu")
		(net 1)
	)
	(via
		(at 202.5 112.1)
		(size 0.45)
		(drill 0.1)
		(layers "F.Cu" "B.Cu")
		(net 1)
	)
	(via
		(at 202.127 184.651)
		(size 0.45)
		(drill 0.1)
		(layers "F.Cu" "B.Cu")
		(net 1)
	)
	(via
		(at 145.9 145.127499)
		(size 0.45)
		(drill 0.1)
		(layers "F.Cu" "B.Cu")
		(net 1)
	)
	(via
		(at 95.550501 164.451)
		(size 0.45)
		(drill 0.1)
		(layers "F.Cu" "B.Cu")
		(net 1)
	)
	(via
		(at 198.799499 139.214)
		(size 0.45)
		(drill 0.1)
		(layers "F.Cu" "B.Cu")
		(net 1)
	)
	(via
		(at 151.900001 145.1275)
		(size 0.45)
		(drill 0.1)
		(layers "F.Cu" "B.Cu")
		(net 1)
	)
	(via
		(at 194.15 195.35)
		(size 0.45)
		(drill 0.1)
		(layers "F.Cu" "B.Cu")
		(net 1)
	)
	(via
		(at 183.5 192.4)
		(size 0.45)
		(drill 0.1)
		(layers "F.Cu" "B.Cu")
		(net 1)
	)
	(via
		(at 126.900501 198.001)
		(size 0.45)
		(drill 0.1)
		(layers "F.Cu" "B.Cu")
		(net 1)
	)
	(via
		(at 196.5975 182.9025)
		(size 0.45)
		(drill 0.1)
		(layers "F.Cu" "B.Cu")
		(net 1)
	)
	(via
		(at 78.74 170.18)
		(size 0.45)
		(drill 0.1)
		(layers "F.Cu" "B.Cu")
		(net 1)
	)
	(via
		(at 171.200501 198.376)
		(size 0.45)
		(drill 0.1)
		(layers "F.Cu" "B.Cu")
		(net 1)
	)
	(via
		(at 188.95 166.25)
		(size 0.45)
		(drill 0.1)
		(layers "F.Cu" "B.Cu")
		(net 1)
	)
	(via
		(at 131.928228 194.128228)
		(size 0.45)
		(drill 0.1)
		(layers "F.Cu" "B.Cu")
		(net 1)
	)
	(via
		(at 146.875001 187.8005)
		(size 0.45)
		(drill 0.1)
		(layers "F.Cu" "B.Cu")
		(net 1)
	)
	(via
		(at 148.875001 173.802501)
		(size 0.45)
		(drill 0.1)
		(layers "F.Cu" "B.Cu")
		(net 1)
	)
	(via
		(at 172.900001 145.1275)
		(size 0.45)
		(drill 0.1)
		(layers "F.Cu" "B.Cu")
		(net 1)
	)
	(via
		(at 135.400001 145.1275)
		(size 0.45)
		(drill 0.1)
		(layers "F.Cu" "B.Cu")
		(net 1)
	)
	(via
		(at 197.158001 183.45)
		(size 0.45)
		(drill 0.1)
		(layers "F.Cu" "B.Cu")
		(net 1)
	)
	(via
		(at 103.3 112.1)
		(size 0.45)
		(drill 0.1)
		(layers "F.Cu" "B.Cu")
		(net 1)
	)
	(via
		(at 170.000501 198.376)
		(size 0.45)
		(drill 0.1)
		(layers "F.Cu" "B.Cu")
		(net 1)
	)
	(via
		(at 196.5705 168.2515)
		(size 0.45)
		(drill 0.1)
		(layers "F.Cu" "B.Cu")
		(net 1)
	)
	(via
		(at 97.3 181.6)
		(size 0.45)
		(drill 0.1)
		(layers "F.Cu" "B.Cu")
		(net 1)
	)
	(via
		(at 132.08 127)
		(size 0.45)
		(drill 0.1)
		(layers "F.Cu" "B.Cu")
		(net 1)
	)
	(via
		(at 181.725 133.2)
		(size 0.45)
		(drill 0.1)
		(layers "F.Cu" "B.Cu")
		(net 1)
	)
	(via
		(at 196.45 116.8)
		(size 0.45)
		(drill 0.1)
		(layers "F.Cu" "B.Cu")
		(net 1)
	)
	(via
		(at 133.877001 170.8025)
		(size 0.45)
		(drill 0.1)
		(layers "F.Cu" "B.Cu")
		(net 1)
	)
	(via
		(at 145.875001 186.8005)
		(size 0.45)
		(drill 0.1)
		(layers "F.Cu" "B.Cu")
		(net 1)
	)
	(via
		(at 150.875001 187.800501)
		(size 0.45)
		(drill 0.1)
		(layers "F.Cu" "B.Cu")
		(net 1)
	)
	(via
		(at 112.400001 145.1275)
		(size 0.45)
		(drill 0.1)
		(layers "F.Cu" "B.Cu")
		(net 1)
	)
	(via
		(at 131.877 164.8025)
		(size 0.45)
		(drill 0.1)
		(layers "F.Cu" "B.Cu")
		(net 1)
	)
	(via
		(at 143.875001 171.8025)
		(size 0.45)
		(drill 0.1)
		(layers "F.Cu" "B.Cu")
		(net 1)
	)
	(via
		(at 127.875501 197.451)
		(size 0.45)
		(drill 0.1)
		(layers "F.Cu" "B.Cu")
		(net 1)
	)
	(via
		(at 161.8 172.3)
		(size 0.45)
		(drill 0.1)
		(layers "F.Cu" "B.Cu")
		(net 1)
	)
	(via
		(at 160.9 112.1)
		(size 0.45)
		(drill 0.1)
		(layers "F.Cu" "B.Cu")
		(net 1)
	)
	(via
		(at 69.5 115.3)
		(size 0.45)
		(drill 0.1)
		(layers "F.Cu" "B.Cu")
		(net 1)
	)
	(via
		(at 124.85 178.3)
		(size 0.45)
		(drill 0.1)
		(layers "F.Cu" "B.Cu")
		(net 1)
	)
	(via
		(at 174.8955 174.3985)
		(size 0.45)
		(drill 0.1)
		(layers "F.Cu" "B.Cu")
		(net 1)
	)
	(via
		(at 152.4 127)
		(size 0.45)
		(drill 0.1)
		(layers "F.Cu" "B.Cu")
		(net 1)
	)
	(via
		(at 205.8 169.05)
		(size 0.45)
		(drill 0.1)
		(layers "F.Cu" "B.Cu")
		(net 1)
	)
	(via
		(at 130.8 195.5)
		(size 0.45)
		(drill 0.1)
		(layers "F.Cu" "B.Cu")
		(net 1)
	)
	(via
		(at 134.000501 206.375501)
		(size 0.45)
		(drill 0.1)
		(layers "F.Cu" "B.Cu")
		(net 1)
	)
	(via
		(at 197.9705 165.6515)
		(size 0.45)
		(drill 0.1)
		(layers "F.Cu" "B.Cu")
		(net 1)
	)
	(via
		(at 127.877001 162.8025)
		(size 0.45)
		(drill 0.1)
		(layers "F.Cu" "B.Cu")
		(net 1)
	)
	(via
		(at 153.9 169.8)
		(size 0.45)
		(drill 0.1)
		(layers "F.Cu" "B.Cu")
		(net 1)
	)
	(via
		(at 92.3 149.55)
		(size 0.45)
		(drill 0.1)
		(layers "F.Cu" "B.Cu")
		(net 1)
	)
	(via
		(at 150.875001 188.900501)
		(size 0.45)
		(drill 0.1)
		(layers "F.Cu" "B.Cu")
		(net 1)
	)
	(via
		(at 165.400001 145.1275)
		(size 0.45)
		(drill 0.1)
		(layers "F.Cu" "B.Cu")
		(net 1)
	)
	(via
		(at 202.15 170.675)
		(size 0.45)
		(drill 0.1)
		(layers "F.Cu" "B.Cu")
		(net 1)
	)
	(via
		(at 109.7 112.1)
		(size 0.45)
		(drill 0.1)
		(layers "F.Cu" "B.Cu")
		(net 1)
	)
	(via
		(at 121.92 127)
		(size 0.45)
		(drill 0.1)
		(layers "F.Cu" "B.Cu")
		(net 1)
	)
	(via
		(at 134.875 159.701384)
		(size 0.45)
		(drill 0.1)
		(layers "F.Cu" "B.Cu")
		(net 1)
	)
	(via
		(at 123.650001 137.7275)
		(size 0.45)
		(drill 0.1)
		(layers "F.Cu" "B.Cu")
		(net 1)
	)
	(via
		(at 90.683501 177.089)
		(size 0.45)
		(drill 0.1)
		(layers "F.Cu" "B.Cu")
		(net 1)
	)
	(via
		(at 155.9 145.1275)
		(size 0.45)
		(drill 0.1)
		(layers "F.Cu" "B.Cu")
		(net 1)
	)
	(via
		(at 180.3 186.7)
		(size 0.45)
		(drill 0.1)
		(layers "F.Cu" "B.Cu")
		(net 1)
	)
	(via
		(at 199.4975 185.7025)
		(size 0.45)
		(drill 0.1)
		(layers "F.Cu" "B.Cu")
		(net 1)
	)
	(via
		(at 139.875001 186.800501)
		(size 0.45)
		(drill 0.1)
		(layers "F.Cu" "B.Cu")
		(net 1)
	)
	(via
		(at 78.225 161.275)
		(size 0.45)
		(drill 0.1)
		(layers "F.Cu" "B.Cu")
		(net 1)
	)
	(via
		(at 115.400001 145.1275)
		(size 0.45)
		(drill 0.1)
		(layers "F.Cu" "B.Cu")
		(net 1)
	)
	(via
		(at 186.55 125.65)
		(size 0.45)
		(drill 0.1)
		(layers "F.Cu" "B.Cu")
		(net 1)
	)
	(via
		(at 89.882344 173.382328)
		(size 0.45)
		(drill 0.1)
		(layers "F.Cu" "B.Cu")
		(net 1)
	)
	(via
		(at 82.723038 164.316)
		(size 0.45)
		(drill 0.1)
		(layers "F.Cu" "B.Cu")
		(net 1)
	)
	(via
		(at 109.650001 137.7275)
		(size 0.45)
		(drill 0.1)
		(layers "F.Cu" "B.Cu")
		(net 1)
	)
	(via
		(at 204.825 170.9)
		(size 0.45)
		(drill 0.1)
		(layers "F.Cu" "B.Cu")
		(net 1)
	)
	(via
		(at 177.945999 192.230502)
		(size 0.45)
		(drill 0.1)
		(layers "F.Cu" "B.Cu")
		(net 1)
	)
	(via
		(at 193.753499 136.32)
		(size 0.45)
		(drill 0.1)
		(layers "F.Cu" "B.Cu")
		(net 1)
	)
	(via
		(at 91.75 156.95)
		(size 0.45)
		(drill 0.1)
		(layers "F.Cu" "B.Cu")
		(net 1)
	)
	(via
		(at 173.7 112.1)
		(size 0.45)
		(drill 0.1)
		(layers "F.Cu" "B.Cu")
		(net 1)
	)
	(via
		(at 174.8955 172.3995)
		(size 0.45)
		(drill 0.1)
		(layers "F.Cu" "B.Cu")
		(net 1)
	)
	(via
		(at 151.875001 179.8005)
		(size 0.45)
		(drill 0.1)
		(layers "F.Cu" "B.Cu")
		(net 1)
	)
	(via
		(at 141.875001 178.8005)
		(size 0.45)
		(drill 0.1)
		(layers "F.Cu" "B.Cu")
		(net 1)
	)
	(via
		(at 100.960501 157.356)
		(size 0.45)
		(drill 0.1)
		(layers "F.Cu" "B.Cu")
		(net 1)
	)
	(via
		(at 128.650001 137.7275)
		(size 0.45)
		(drill 0.1)
		(layers "F.Cu" "B.Cu")
		(net 1)
	)
	(via
		(at 169.400501 198.276)
		(size 0.45)
		(drill 0.1)
		(layers "F.Cu" "B.Cu")
		(net 1)
	)
	(via
		(at 187.96 147.32)
		(size 0.45)
		(drill 0.1)
		(layers "F.Cu" "B.Cu")
		(net 1)
	)
	(via
		(at 138.050501 206.400501)
		(size 0.45)
		(drill 0.1)
		(layers "F.Cu" "B.Cu")
		(net 1)
	)
	(via
		(at 206.3 124.9)
		(size 0.45)
		(drill 0.1)
		(layers "F.Cu" "B.Cu")
		(net 1)
	)
	(via
		(at 169.4 194.85)
		(size 0.45)
		(drill 0.1)
		(layers "F.Cu" "B.Cu")
		(net 1)
	)
	(via
		(at 170.900501 199.876)
		(size 0.45)
		(drill 0.1)
		(layers "F.Cu" "B.Cu")
		(net 1)
	)
	(via
		(at 150.875001 168.8025)
		(size 0.45)
		(drill 0.1)
		(layers "F.Cu" "B.Cu")
		(net 1)
	)
	(via
		(at 184.070501 130.456)
		(size 0.45)
		(drill 0.1)
		(layers "F.Cu" "B.Cu")
		(net 1)
	)
	(via
		(at 194.627 188.851)
		(size 0.45)
		(drill 0.1)
		(layers "F.Cu" "B.Cu")
		(net 1)
	)
	(via
		(at 183.605107 181.1745)
		(size 0.45)
		(drill 0.1)
		(layers "F.Cu" "B.Cu")
		(net 1)
	)
	(via
		(at 142.875001 185.8005)
		(size 0.45)
		(drill 0.1)
		(layers "F.Cu" "B.Cu")
		(net 1)
	)
	(via
		(at 80.9 152.8)
		(size 0.45)
		(drill 0.1)
		(layers "F.Cu" "B.Cu")
		(net 1)
	)
	(via
		(at 170.1 194.9)
		(size 0.45)
		(drill 0.1)
		(layers "F.Cu" "B.Cu")
		(net 1)
	)
	(via
		(at 84.455 180.975)
		(size 0.45)
		(drill 0.1)
		(layers "F.Cu" "B.Cu")
		(net 1)
	)
	(via
		(at 74.7 189)
		(size 0.45)
		(drill 0.1)
		(layers "F.Cu" "B.Cu")
		(net 1)
	)
	(via
		(at 143.875001 167.8025)
		(size 0.45)
		(drill 0.1)
		(layers "F.Cu" "B.Cu")
		(net 1)
	)
	(via
		(at 92.8 156.95)
		(size 0.45)
		(drill 0.1)
		(layers "F.Cu" "B.Cu")
		(net 1)
	)
	(via
		(at 121.150001 137.7275)
		(size 0.45)
		(drill 0.1)
		(layers "F.Cu" "B.Cu")
		(net 1)
	)
	(via
		(at 204.825 187.9)
		(size 0.45)
		(drill 0.1)
		(layers "F.Cu" "B.Cu")
		(net 1)
	)
	(via
		(at 127 121.92)
		(size 0.45)
		(drill 0.1)
		(layers "F.Cu" "B.Cu")
		(net 1)
	)
	(via
		(at 160.400001 145.1275)
		(size 0.45)
		(drill 0.1)
		(layers "F.Cu" "B.Cu")
		(net 1)
	)
	(via
		(at 150.875002 175.8005)
		(size 0.45)
		(drill 0.1)
		(layers "F.Cu" "B.Cu")
		(net 1)
	)
	(via
		(at 171.450002 131.105)
		(size 0.45)
		(drill 0.1)
		(layers "F.Cu" "B.Cu")
		(net 1)
	)
	(via
		(at 160.650002 137.7275)
		(size 0.45)
		(drill 0.1)
		(layers "F.Cu" "B.Cu")
		(net 1)
	)
	(via
		(at 132.08 116.84)
		(size 0.45)
		(drill 0.1)
		(layers "F.Cu" "B.Cu")
		(net 1)
	)
	(via
		(at 137.000501 194.176)
		(size 0.45)
		(drill 0.1)
		(layers "F.Cu" "B.Cu")
		(net 1)
	)
	(via
		(at 99.103157 150.793165)
		(size 0.45)
		(drill 0.1)
		(layers "F.Cu" "B.Cu")
		(net 1)
	)
	(via
		(at 109.400001 145.1275)
		(size 0.45)
		(drill 0.1)
		(layers "F.Cu" "B.Cu")
		(net 1)
	)
	(via
		(at 179.350001 123.546001)
		(size 0.45)
		(drill 0.1)
		(layers "F.Cu" "B.Cu")
		(net 1)
	)
	(via
		(at 124.650001 137.7275)
		(size 0.45)
		(drill 0.1)
		(layers "F.Cu" "B.Cu")
		(net 1)
	)
	(via
		(at 198.881001 185.173)
		(size 0.45)
		(drill 0.1)
		(layers "F.Cu" "B.Cu")
		(net 1)
	)
	(via
		(at 196.75 193)
		(size 0.45)
		(drill 0.1)
		(layers "F.Cu" "B.Cu")
		(net 1)
	)
	(via
		(at 129.54 197.485)
		(size 0.45)
		(drill 0.1)
		(layers "F.Cu" "B.Cu")
		(net 1)
	)
	(via
		(at 119.3 112.1)
		(size 0.45)
		(drill 0.1)
		(layers "F.Cu" "B.Cu")
		(net 1)
	)
	(via
		(at 183.140501 135.906)
		(size 0.45)
		(drill 0.1)
		(layers "F.Cu" "B.Cu")
		(net 1)
	)
	(via
		(at 81.3 194.1)
		(size 0.45)
		(drill 0.1)
		(layers "F.Cu" "B.Cu")
		(net 1)
	)
	(via
		(at 139.900001 145.127499)
		(size 0.45)
		(drill 0.1)
		(layers "F.Cu" "B.Cu")
		(net 1)
	)
	(via
		(at 94.059829 165.647157)
		(size 0.45)
		(drill 0.1)
		(layers "F.Cu" "B.Cu")
		(net 1)
	)
	(via
		(at 91 170.3)
		(size 0.45)
		(drill 0.1)
		(layers "F.Cu" "B.Cu")
		(net 1)
	)
	(via
		(at 143.875001 178.8005)
		(size 0.45)
		(drill 0.1)
		(layers "F.Cu" "B.Cu")
		(net 1)
	)
	(via
		(at 199.4705 165.4515)
		(size 0.45)
		(drill 0.1)
		(layers "F.Cu" "B.Cu")
		(net 1)
	)
	(via
		(at 165.165502 178.656)
		(size 0.45)
		(drill 0.1)
		(layers "F.Cu" "B.Cu")
		(net 1)
	)
	(via
		(at 125.877001 177.8005)
		(size 0.45)
		(drill 0.1)
		(layers "F.Cu" "B.Cu")
		(net 1)
	)
	(via
		(at 165.165501 182.655)
		(size 0.45)
		(drill 0.1)
		(layers "F.Cu" "B.Cu")
		(net 1)
	)
	(via
		(at 204.775499 142.748499)
		(size 0.45)
		(drill 0.1)
		(layers "F.Cu" "B.Cu")
		(net 1)
	)
	(via
		(at 189.7 112.1)
		(size 0.45)
		(drill 0.1)
		(layers "F.Cu" "B.Cu")
		(net 1)
	)
	(via
		(at 164.65 137.7275)
		(size 0.45)
		(drill 0.1)
		(layers "F.Cu" "B.Cu")
		(net 1)
	)
	(via
		(at 138.870501 183.806)
		(size 0.45)
		(drill 0.1)
		(layers "F.Cu" "B.Cu")
		(net 1)
	)
	(via
		(at 132.150001 137.7275)
		(size 0.45)
		(drill 0.1)
		(layers "F.Cu" "B.Cu")
		(net 1)
	)
	(via
		(at 125.877001 166.8025)
		(size 0.45)
		(drill 0.1)
		(layers "F.Cu" "B.Cu")
		(net 1)
	)
	(via
		(at 192.6 200.6)
		(size 0.45)
		(drill 0.1)
		(layers "F.Cu" "B.Cu")
		(net 1)
	)
	(via
		(at 145.875001 176.8005)
		(size 0.45)
		(drill 0.1)
		(layers "F.Cu" "B.Cu")
		(net 1)
	)
	(via
		(at 134.150001 137.7275)
		(size 0.45)
		(drill 0.1)
		(layers "F.Cu" "B.Cu")
		(net 1)
	)
	(via
		(at 103.325501 172.385)
		(size 0.45)
		(drill 0.1)
		(layers "F.Cu" "B.Cu")
		(net 1)
	)
	(via
		(at 174.8955 178.3985)
		(size 0.45)
		(drill 0.1)
		(layers "F.Cu" "B.Cu")
		(net 1)
	)
	(via
		(at 122.900001 145.1275)
		(size 0.45)
		(drill 0.1)
		(layers "F.Cu" "B.Cu")
		(net 1)
	)
	(via
		(at 177.8 173.99)
		(size 0.45)
		(drill 0.1)
		(layers "F.Cu" "B.Cu")
		(net 1)
	)
	(via
		(at 83.7 182.4)
		(size 0.45)
		(drill 0.1)
		(layers "F.Cu" "B.Cu")
		(net 1)
	)
	(via
		(at 181.5 130.1)
		(size 0.45)
		(drill 0.1)
		(layers "F.Cu" "B.Cu")
		(net 1)
	)
	(via
		(at 95.100501 124.606)
		(size 0.45)
		(drill 0.1)
		(layers "F.Cu" "B.Cu")
		(net 1)
	)
	(via
		(at 167.3 112.1)
		(size 0.45)
		(drill 0.1)
		(layers "F.Cu" "B.Cu")
		(net 1)
	)
	(via
		(at 198.65 193.85)
		(size 0.45)
		(drill 0.1)
		(layers "F.Cu" "B.Cu")
		(net 1)
	)
	(via
		(at 147.875001 179.8005)
		(size 0.45)
		(drill 0.1)
		(layers "F.Cu" "B.Cu")
		(net 1)
	)
	(via
		(at 199.4705 168.2515)
		(size 0.45)
		(drill 0.1)
		(layers "F.Cu" "B.Cu")
		(net 1)
	)
	(via
		(at 89.090501 148.576)
		(size 0.45)
		(drill 0.1)
		(layers "F.Cu" "B.Cu")
		(net 1)
	)
	(via
		(at 135.730501 189.266)
		(size 0.45)
		(drill 0.1)
		(layers "F.Cu" "B.Cu")
		(net 1)
	)
	(via
		(at 171.800501 193.976)
		(size 0.45)
		(drill 0.1)
		(layers "F.Cu" "B.Cu")
		(net 1)
	)
	(via
		(at 193.45 189.225)
		(size 0.45)
		(drill 0.1)
		(layers "F.Cu" "B.Cu")
		(net 1)
	)
	(via
		(at 87.4 184.9)
		(size 0.45)
		(drill 0.1)
		(layers "F.Cu" "B.Cu")
		(net 1)
	)
	(via
		(at 151.875001 175.8005)
		(size 0.45)
		(drill 0.1)
		(layers "F.Cu" "B.Cu")
		(net 1)
	)
	(via
		(at 170.400501 199.776)
		(size 0.45)
		(drill 0.1)
		(layers "F.Cu" "B.Cu")
		(net 1)
	)
	(via
		(at 179.505 195.063)
		(size 0.45)
		(drill 0.1)
		(layers "F.Cu" "B.Cu")
		(net 1)
	)
	(via
		(at 203.751498 140.673501)
		(size 0.45)
		(drill 0.1)
		(layers "F.Cu" "B.Cu")
		(net 1)
	)
	(via
		(at 94.9 149.55)
		(size 0.45)
		(drill 0.1)
		(layers "F.Cu" "B.Cu")
		(net 1)
	)
	(via
		(at 107.9 200.2)
		(size 0.45)
		(drill 0.1)
		(layers "F.Cu" "B.Cu")
		(net 1)
	)
	(via
		(at 75.9 200.2)
		(size 0.45)
		(drill 0.1)
		(layers "F.Cu" "B.Cu")
		(net 1)
	)
	(via
		(at 93.5 197.9)
		(size 0.45)
		(drill 0.1)
		(layers "F.Cu" "B.Cu")
		(net 1)
	)
	(via
		(at 97.271658 166.455157)
		(size 0.45)
		(drill 0.1)
		(layers "F.Cu" "B.Cu")
		(net 1)
	)
	(via
		(at 119.73 206.300501)
		(size 0.45)
		(drill 0.1)
		(layers "F.Cu" "B.Cu")
		(net 1)
	)
	(via
		(at 198.4 171)
		(size 0.45)
		(drill 0.1)
		(layers "F.Cu" "B.Cu")
		(net 1)
	)
	(via
		(at 139.875001 178.8005)
		(size 0.45)
		(drill 0.1)
		(layers "F.Cu" "B.Cu")
		(net 1)
	)
	(via
		(at 132.877001 167.8025)
		(size 0.45)
		(drill 0.1)
		(layers "F.Cu" "B.Cu")
		(net 1)
	)
	(via
		(at 124.46 200.025)
		(size 0.45)
		(drill 0.1)
		(layers "F.Cu" "B.Cu")
		(net 1)
	)
	(via
		(at 142.075001 206.400501)
		(size 0.45)
		(drill 0.1)
		(layers "F.Cu" "B.Cu")
		(net 1)
	)
	(via
		(at 176.9 112.1)
		(size 0.45)
		(drill 0.1)
		(layers "F.Cu" "B.Cu")
		(net 1)
	)
	(via
		(at 141.65 139.8775)
		(size 0.45)
		(drill 0.1)
		(layers "F.Cu" "B.Cu")
		(net 1)
	)
	(via
		(at 145.875001 178.8005)
		(size 0.45)
		(drill 0.1)
		(layers "F.Cu" "B.Cu")
		(net 1)
	)
	(via
		(at 128.877001 186.8005)
		(size 0.45)
		(drill 0.1)
		(layers "F.Cu" "B.Cu")
		(net 1)
	)
	(via
		(at 182.034 149.009001)
		(size 0.45)
		(drill 0.1)
		(layers "F.Cu" "B.Cu")
		(net 1)
	)
	(via
		(at 167.64 121.92)
		(size 0.45)
		(drill 0.1)
		(layers "F.Cu" "B.Cu")
		(net 1)
	)
	(via
		(at 140.875001 168.8025)
		(size 0.45)
		(drill 0.1)
		(layers "F.Cu" "B.Cu")
		(net 1)
	)
	(via
		(at 104.0745 162.7745)
		(size 0.45)
		(drill 0.1)
		(layers "F.Cu" "B.Cu")
		(net 1)
	)
	(via
		(at 144.649999 137.727499)
		(size 0.45)
		(drill 0.1)
		(layers "F.Cu" "B.Cu")
		(net 1)
	)
	(via
		(at 116.84 121.92)
		(size 0.45)
		(drill 0.1)
		(layers "F.Cu" "B.Cu")
		(net 1)
	)
	(via
		(at 105.975 128.425)
		(size 0.45)
		(drill 0.1)
		(layers "F.Cu" "B.Cu")
		(net 1)
	)
	(via
		(at 174.888 170.447)
		(size 0.45)
		(drill 0.1)
		(layers "F.Cu" "B.Cu")
		(net 1)
	)
	(via
		(at 138.875501 173.801)
		(size 0.45)
		(drill 0.1)
		(layers "F.Cu" "B.Cu")
		(net 1)
	)
	(via
		(at 98.301 179.2)
		(size 0.45)
		(drill 0.1)
		(layers "F.Cu" "B.Cu")
		(net 1)
	)
	(via
		(at 95.1 200.2)
		(size 0.45)
		(drill 0.1)
		(layers "F.Cu" "B.Cu")
		(net 1)
	)
	(via
		(at 97.125 180.182)
		(size 0.45)
		(drill 0.1)
		(layers "F.Cu" "B.Cu")
		(net 1)
	)
	(via
		(at 180.2 169.1)
		(size 0.45)
		(drill 0.1)
		(layers "F.Cu" "B.Cu")
		(net 1)
	)
	(via
		(at 121.900001 145.1275)
		(size 0.45)
		(drill 0.1)
		(layers "F.Cu" "B.Cu")
		(net 1)
	)
	(via
		(at 121.950501 197.976)
		(size 0.45)
		(drill 0.1)
		(layers "F.Cu" "B.Cu")
		(net 1)
	)
	(via
		(at 93.820501 175.635)
		(size 0.45)
		(drill 0.1)
		(layers "F.Cu" "B.Cu")
		(net 1)
	)
	(via
		(at 105.922344 173.132328)
		(size 0.45)
		(drill 0.1)
		(layers "F.Cu" "B.Cu")
		(net 1)
	)
	(via
		(at 86 168.5)
		(size 0.45)
		(drill 0.1)
		(layers "F.Cu" "B.Cu")
		(net 1)
	)
	(via
		(at 130.877001 182.8005)
		(size 0.45)
		(drill 0.1)
		(layers "F.Cu" "B.Cu")
		(net 1)
	)
	(via
		(at 86.536829 151.433157)
		(size 0.45)
		(drill 0.1)
		(layers "F.Cu" "B.Cu")
		(net 1)
	)
	(via
		(at 126.877001 169.802499)
		(size 0.45)
		(drill 0.1)
		(layers "F.Cu" "B.Cu")
		(net 1)
	)
	(via
		(at 169.35 193.35)
		(size 0.45)
		(drill 0.1)
		(layers "F.Cu" "B.Cu")
		(net 1)
	)
	(via
		(at 159.650001 137.727499)
		(size 0.45)
		(drill 0.1)
		(layers "F.Cu" "B.Cu")
		(net 1)
	)
	(via
		(at 193.927 180.201)
		(size 0.45)
		(drill 0.1)
		(layers "F.Cu" "B.Cu")
		(net 1)
	)
	(via
		(at 179.375 190.9)
		(size 0.45)
		(drill 0.1)
		(layers "F.Cu" "B.Cu")
		(net 1)
	)
	(via
		(at 111.1 156.56)
		(size 0.45)
		(drill 0.1)
		(layers "F.Cu" "B.Cu")
		(net 1)
	)
	(via
		(at 93.6 154.8)
		(size 0.45)
		(drill 0.1)
		(layers "F.Cu" "B.Cu")
		(net 1)
	)
	(via
		(at 126.2 201.825)
		(size 0.45)
		(drill 0.1)
		(layers "F.Cu" "B.Cu")
		(net 1)
	)
	(via
		(at 85.5 129.7)
		(size 0.45)
		(drill 0.1)
		(layers "F.Cu" "B.Cu")
		(net 1)
	)
	(via
		(at 78.7 155.3)
		(size 0.45)
		(drill 0.1)
		(layers "F.Cu" "B.Cu")
		(net 1)
	)
	(via
		(at 193.7 161.95)
		(size 0.45)
		(drill 0.1)
		(layers "F.Cu" "B.Cu")
		(net 1)
	)
	(via
		(at 137.877002 162.8025)
		(size 0.45)
		(drill 0.1)
		(layers "F.Cu" "B.Cu")
		(net 1)
	)
	(via
		(at 157.4 200.6)
		(size 0.45)
		(drill 0.1)
		(layers "F.Cu" "B.Cu")
		(net 1)
	)
	(via
		(at 103.780501 120.226)
		(size 0.45)
		(drill 0.1)
		(layers "F.Cu" "B.Cu")
		(net 1)
	)
	(via
		(at 148.875001 178.8005)
		(size 0.45)
		(drill 0.1)
		(layers "F.Cu" "B.Cu")
		(net 1)
	)
	(via
		(at 143.15 139.8775)
		(size 0.45)
		(drill 0.1)
		(layers "F.Cu" "B.Cu")
		(net 1)
	)
	(via
		(at 166.400001 145.1275)
		(size 0.45)
		(drill 0.1)
		(layers "F.Cu" "B.Cu")
		(net 1)
	)
	(via
		(at 120.475001 205.700501)
		(size 0.45)
		(drill 0.1)
		(layers "F.Cu" "B.Cu")
		(net 1)
	)
	(via
		(at 136.877001 173.8025)
		(size 0.45)
		(drill 0.1)
		(layers "F.Cu" "B.Cu")
		(net 1)
	)
	(via
		(at 190.125 167.475)
		(size 0.45)
		(drill 0.1)
		(layers "F.Cu" "B.Cu")
		(net 1)
	)
	(via
		(at 89.700501 124.606)
		(size 0.45)
		(drill 0.1)
		(layers "F.Cu" "B.Cu")
		(net 1)
	)
	(via
		(at 199.3 112.1)
		(size 0.45)
		(drill 0.1)
		(layers "F.Cu" "B.Cu")
		(net 1)
	)
	(via
		(at 198.854001 167.722)
		(size 0.45)
		(drill 0.1)
		(layers "F.Cu" "B.Cu")
		(net 1)
	)
	(via
		(at 131.7 195.5)
		(size 0.45)
		(drill 0.1)
		(layers "F.Cu" "B.Cu")
		(net 1)
	)
	(via
		(at 127.8 199.2)
		(size 0.45)
		(drill 0.1)
		(layers "F.Cu" "B.Cu")
		(net 1)
	)
	(via
		(at 183.607608 163.021999)
		(size 0.45)
		(drill 0.1)
		(layers "F.Cu" "B.Cu")
		(net 1)
	)
	(via
		(at 119.675001 205.600501)
		(size 0.45)
		(drill 0.1)
		(layers "F.Cu" "B.Cu")
		(net 1)
	)
	(via
		(at 127 200.025)
		(size 0.45)
		(drill 0.1)
		(layers "F.Cu" "B.Cu")
		(net 1)
	)
	(via
		(at 147.875001 175.8005)
		(size 0.45)
		(drill 0.1)
		(layers "F.Cu" "B.Cu")
		(net 1)
	)
	(via
		(at 182.153608 164.356694)
		(size 0.45)
		(drill 0.1)
		(layers "F.Cu" "B.Cu")
		(net 1)
	)
	(via
		(at 115.6 195.3)
		(size 0.45)
		(drill 0.1)
		(layers "F.Cu" "B.Cu")
		(net 1)
	)
	(via
		(at 127.8 202.4)
		(size 0.45)
		(drill 0.1)
		(layers "F.Cu" "B.Cu")
		(net 1)
	)
	(via
		(at 109.8 195.4)
		(size 0.45)
		(drill 0.1)
		(layers "F.Cu" "B.Cu")
		(net 1)
	)
	(via
		(at 111.1 200.2)
		(size 0.45)
		(drill 0.1)
		(layers "F.Cu" "B.Cu")
		(net 1)
	)
	(via
		(at 118.150001 137.7275)
		(size 0.45)
		(drill 0.1)
		(layers "F.Cu" "B.Cu")
		(net 1)
	)
	(via
		(at 148.875001 186.800501)
		(size 0.45)
		(drill 0.1)
		(layers "F.Cu" "B.Cu")
		(net 1)
	)
	(via
		(at 196.1 112.1)
		(size 0.45)
		(drill 0.1)
		(layers "F.Cu" "B.Cu")
		(net 1)
	)
	(via
		(at 151.875001 161.8025)
		(size 0.45)
		(drill 0.1)
		(layers "F.Cu" "B.Cu")
		(net 1)
	)
	(via
		(at 147.875001 185.8005)
		(size 0.45)
		(drill 0.1)
		(layers "F.Cu" "B.Cu")
		(net 1)
	)
	(via
		(at 97.225 183.2)
		(size 0.45)
		(drill 0.1)
		(layers "F.Cu" "B.Cu")
		(net 1)
	)
	(via
		(at 186.2 200.6)
		(size 0.45)
		(drill 0.1)
		(layers "F.Cu" "B.Cu")
		(net 1)
	)
	(via
		(at 152.4 116.84)
		(size 0.45)
		(drill 0.1)
		(layers "F.Cu" "B.Cu")
		(net 1)
	)
	(via
		(at 206.3 134.5)
		(size 0.45)
		(drill 0.1)
		(layers "F.Cu" "B.Cu")
		(net 1)
	)
	(via
		(at 120.150501 175.426)
		(size 0.45)
		(drill 0.1)
		(layers "F.Cu" "B.Cu")
		(net 1)
	)
	(via
		(at 83.4 169.2)
		(size 0.45)
		(drill 0.1)
		(layers "F.Cu" "B.Cu")
		(net 1)
	)
	(via
		(at 99.827658 166.413157)
		(size 0.45)
		(drill 0.1)
		(layers "F.Cu" "B.Cu")
		(net 1)
	)
	(via
		(at 160.168501 183.388001)
		(size 0.45)
		(drill 0.1)
		(layers "F.Cu" "B.Cu")
		(net 1)
	)
	(via
		(at 131.877001 185.8005)
		(size 0.45)
		(drill 0.1)
		(layers "F.Cu" "B.Cu")
		(net 1)
	)
	(via
		(at 69.5 118.5)
		(size 0.45)
		(drill 0.1)
		(layers "F.Cu" "B.Cu")
		(net 1)
	)
	(via
		(at 177.8 142.24)
		(size 0.45)
		(drill 0.1)
		(layers "F.Cu" "B.Cu")
		(net 1)
	)
	(via
		(at 193.9 162.75)
		(size 0.45)
		(drill 0.1)
		(layers "F.Cu" "B.Cu")
		(net 1)
	)
	(via
		(at 206.3 137.7)
		(size 0.45)
		(drill 0.1)
		(layers "F.Cu" "B.Cu")
		(net 1)
	)
	(via
		(at 180.1 112.1)
		(size 0.45)
		(drill 0.1)
		(layers "F.Cu" "B.Cu")
		(net 1)
	)
	(via
		(at 133.877001 181.8005)
		(size 0.45)
		(drill 0.1)
		(layers "F.Cu" "B.Cu")
		(net 1)
	)
	(via
		(at 205.8 170.9)
		(size 0.45)
		(drill 0.1)
		(layers "F.Cu" "B.Cu")
		(net 1)
	)
	(via
		(at 152.374503 187.301)
		(size 0.45)
		(drill 0.1)
		(layers "F.Cu" "B.Cu")
		(net 1)
	)
	(via
		(at 206.3 140.9)
		(size 0.45)
		(drill 0.1)
		(layers "F.Cu" "B.Cu")
		(net 1)
	)
	(via
		(at 98.981513 162.984502)
		(size 0.45)
		(drill 0.1)
		(layers "F.Cu" "B.Cu")
		(net 1)
	)
	(via
		(at 194.6 171.4)
		(size 0.45)
		(drill 0.1)
		(layers "F.Cu" "B.Cu")
		(net 1)
	)
	(via
		(at 162.400001 145.127499)
		(size 0.45)
		(drill 0.1)
		(layers "F.Cu" "B.Cu")
		(net 1)
	)
	(via
		(at 169.400001 145.127499)
		(size 0.45)
		(drill 0.1)
		(layers "F.Cu" "B.Cu")
		(net 1)
	)
	(via
		(at 97.1 197.9)
		(size 0.45)
		(drill 0.1)
		(layers "F.Cu" "B.Cu")
		(net 1)
	)
	(via
		(at 166.8 184.2)
		(size 0.45)
		(drill 0.1)
		(layers "F.Cu" "B.Cu")
		(net 1)
	)
	(via
		(at 169.200501 199.776)
		(size 0.45)
		(drill 0.1)
		(layers "F.Cu" "B.Cu")
		(net 1)
	)
	(via
		(at 171.150001 137.7275)
		(size 0.45)
		(drill 0.1)
		(layers "F.Cu" "B.Cu")
		(net 1)
	)
	(via
		(at 183.3 112.1)
		(size 0.45)
		(drill 0.1)
		(layers "F.Cu" "B.Cu")
		(net 1)
	)
	(via
		(at 202.075 182.7)
		(size 0.45)
		(drill 0.1)
		(layers "F.Cu" "B.Cu")
		(net 1)
	)
	(via
		(at 114.150001 137.7275)
		(size 0.45)
		(drill 0.1)
		(layers "F.Cu" "B.Cu")
		(net 1)
	)
	(via
		(at 151.15 139.8775)
		(size 0.45)
		(drill 0.1)
		(layers "F.Cu" "B.Cu")
		(net 1)
	)
	(via
		(at 170.600501 198.276)
		(size 0.45)
		(drill 0.1)
		(layers "F.Cu" "B.Cu")
		(net 1)
	)
	(via
		(at 129.9 195.5)
		(size 0.45)
		(drill 0.1)
		(layers "F.Cu" "B.Cu")
		(net 1)
	)
	(via
		(at 127.550501 196.901)
		(size 0.45)
		(drill 0.1)
		(layers "F.Cu" "B.Cu")
		(net 1)
	)
	(via
		(at 140.875001 177.8005)
		(size 0.45)
		(drill 0.1)
		(layers "F.Cu" "B.Cu")
		(net 1)
	)
	(via
		(at 174.888 168.422)
		(size 0.45)
		(drill 0.1)
		(layers "F.Cu" "B.Cu")
		(net 1)
	)
	(via
		(at 193.4 184.2)
		(size 0.45)
		(drill 0.1)
		(layers "F.Cu" "B.Cu")
		(net 1)
	)
	(via
		(at 182.88 142.24)
		(size 0.45)
		(drill 0.1)
		(layers "F.Cu" "B.Cu")
		(net 1)
	)
	(via
		(at 151.875001 171.8025)
		(size 0.45)
		(drill 0.1)
		(layers "F.Cu" "B.Cu")
		(net 1)
	)
	(via
		(at 117.150001 137.7275)
		(size 0.45)
		(drill 0.1)
		(layers "F.Cu" "B.Cu")
		(net 1)
	)
	(via
		(at 171.800501 198.376)
		(size 0.45)
		(drill 0.1)
		(layers "F.Cu" "B.Cu")
		(net 1)
	)
	(via
		(at 103.117344 171.630157)
		(size 0.45)
		(drill 0.1)
		(layers "F.Cu" "B.Cu")
		(net 1)
	)
	(via
		(at 127.175501 197.451)
		(size 0.45)
		(drill 0.1)
		(layers "F.Cu" "B.Cu")
		(net 1)
	)
	(via
		(at 92.5 191)
		(size 0.45)
		(drill 0.1)
		(layers "F.Cu" "B.Cu")
		(net 1)
	)
	(via
		(at 69.5 121.7)
		(size 0.45)
		(drill 0.1)
		(layers "F.Cu" "B.Cu")
		(net 1)
	)
	(via
		(at 150.649501 145.076)
		(size 0.45)
		(drill 0.1)
		(layers "F.Cu" "B.Cu")
		(net 1)
	)
	(via
		(at 83 181.8)
		(size 0.45)
		(drill 0.1)
		(layers "F.Cu" "B.Cu")
		(net 1)
	)
	(via
		(at 193.927 188.151)
		(size 0.45)
		(drill 0.1)
		(layers "F.Cu" "B.Cu")
		(net 1)
	)
	(via
		(at 196.227 188.351)
		(size 0.45)
		(drill 0.1)
		(layers "F.Cu" "B.Cu")
		(net 1)
	)
	(via
		(at 130.877001 161.8025)
		(size 0.45)
		(drill 0.1)
		(layers "F.Cu" "B.Cu")
		(net 1)
	)
	(via
		(at 116.900001 145.1275)
		(size 0.45)
		(drill 0.1)
		(layers "F.Cu" "B.Cu")
		(net 1)
	)
	(via
		(at 136.900001 147.2775)
		(size 0.45)
		(drill 0.1)
		(layers "F.Cu" "B.Cu")
		(net 1)
	)
	(via
		(at 166.150001 137.7275)
		(size 0.45)
		(drill 0.1)
		(layers "F.Cu" "B.Cu")
		(net 1)
	)
	(via
		(at 172.72 116.84)
		(size 0.45)
		(drill 0.1)
		(layers "F.Cu" "B.Cu")
		(net 1)
	)
	(via
		(at 141.875001 172.8025)
		(size 0.45)
		(drill 0.1)
		(layers "F.Cu" "B.Cu")
		(net 1)
	)
	(via
		(at 179.3 200.5)
		(size 0.45)
		(drill 0.1)
		(layers "F.Cu" "B.Cu")
		(net 1)
	)
	(via
		(at 104.14 144.78)
		(size 0.45)
		(drill 0.1)
		(layers "F.Cu" "B.Cu")
		(net 1)
	)
	(via
		(at 95.268501 166.465)
		(size 0.45)
		(drill 0.1)
		(layers "F.Cu" "B.Cu")
		(net 1)
	)
	(via
		(at 93 130.9)
		(size 0.45)
		(drill 0.1)
		(layers "F.Cu" "B.Cu")
		(net 1)
	)
	(via
		(at 197.993501 166.8595)
		(size 0.45)
		(drill 0.1)
		(layers "F.Cu" "B.Cu")
		(net 1)
	)
	(via
		(at 194.627 179.501)
		(size 0.45)
		(drill 0.1)
		(layers "F.Cu" "B.Cu")
		(net 1)
	)
	(via
		(at 91.9 200.2)
		(size 0.45)
		(drill 0.1)
		(layers "F.Cu" "B.Cu")
		(net 1)
	)
	(via
		(at 135.650001 139.8775)
		(size 0.45)
		(drill 0.1)
		(layers "F.Cu" "B.Cu")
		(net 1)
	)
	(via
		(at 137.877001 170.8025)
		(size 0.45)
		(drill 0.1)
		(layers "F.Cu" "B.Cu")
		(net 1)
	)
	(via
		(at 157.650002 137.7275)
		(size 0.45)
		(drill 0.1)
		(layers "F.Cu" "B.Cu")
		(net 1)
	)
	(via
		(at 198.955 148.804999)
		(size 0.45)
		(drill 0.1)
		(layers "F.Cu" "B.Cu")
		(net 1)
	)
	(via
		(at 90.402877 191.039001)
		(size 0.45)
		(drill 0.1)
		(layers "F.Cu" "B.Cu")
		(net 1)
	)
	(via
		(at 202.1 167.2)
		(size 0.45)
		(drill 0.1)
		(layers "F.Cu" "B.Cu")
		(net 1)
	)
	(via
		(at 173.2 181.9)
		(size 0.45)
		(drill 0.1)
		(layers "F.Cu" "B.Cu")
		(net 1)
	)
	(via
		(at 198.955 157.803)
		(size 0.45)
		(drill 0.1)
		(layers "F.Cu" "B.Cu")
		(net 1)
	)
	(via
		(at 144.9 112.1)
		(size 0.45)
		(drill 0.1)
		(layers "F.Cu" "B.Cu")
		(net 1)
	)
	(via
		(at 145.875001 180.8005)
		(size 0.45)
		(drill 0.1)
		(layers "F.Cu" "B.Cu")
		(net 1)
	)
	(via
		(at 113.400001 145.1275)
		(size 0.45)
		(drill 0.1)
		(layers "F.Cu" "B.Cu")
		(net 1)
	)
	(via
		(at 135.875501 174.801)
		(size 0.45)
		(drill 0.1)
		(layers "F.Cu" "B.Cu")
		(net 1)
	)
	(via
		(at 163.400002 145.127499)
		(size 0.45)
		(drill 0.1)
		(layers "F.Cu" "B.Cu")
		(net 1)
	)
	(via
		(at 96.9 112.1)
		(size 0.45)
		(drill 0.1)
		(layers "F.Cu" "B.Cu")
		(net 1)
	)
	(via
		(at 189.4 200.6)
		(size 0.45)
		(drill 0.1)
		(layers "F.Cu" "B.Cu")
		(net 1)
	)
	(via
		(at 132.400001 145.1275)
		(size 0.45)
		(drill 0.1)
		(layers "F.Cu" "B.Cu")
		(net 1)
	)
	(via
		(at 137.877001 172.8025)
		(size 0.45)
		(drill 0.1)
		(layers "F.Cu" "B.Cu")
		(net 1)
	)
	(via
		(at 194.05 197.65)
		(size 0.45)
		(drill 0.1)
		(layers "F.Cu" "B.Cu")
		(net 1)
	)
	(via
		(at 93.7 112.1)
		(size 0.45)
		(drill 0.1)
		(layers "F.Cu" "B.Cu")
		(net 1)
	)
	(via
		(at 193.6 171.8)
		(size 0.45)
		(drill 0.1)
		(layers "F.Cu" "B.Cu")
		(net 1)
	)
	(via
		(at 127.400001 145.1275)
		(size 0.45)
		(drill 0.1)
		(layers "F.Cu" "B.Cu")
		(net 1)
	)
	(via
		(at 115.150001 137.7275)
		(size 0.45)
		(drill 0.1)
		(layers "F.Cu" "B.Cu")
		(net 1)
	)
	(via
		(at 83.502 191)
		(size 0.45)
		(drill 0.1)
		(layers "F.Cu" "B.Cu")
		(net 1)
	)
	(via
		(at 125.877001 187.8005)
		(size 0.45)
		(drill 0.1)
		(layers "F.Cu" "B.Cu")
		(net 1)
	)
	(via
		(at 143.875002 173.8025)
		(size 0.45)
		(drill 0.1)
		(layers "F.Cu" "B.Cu")
		(net 1)
	)
	(via
		(at 98.220501 138.226)
		(size 0.45)
		(drill 0.1)
		(layers "F.Cu" "B.Cu")
		(net 1)
	)
	(via
		(at 173.150001 137.7275)
		(size 0.45)
		(drill 0.1)
		(layers "F.Cu" "B.Cu")
		(net 1)
	)
	(via
		(at 128.200501 198.001)
		(size 0.45)
		(drill 0.1)
		(layers "F.Cu" "B.Cu")
		(net 1)
	)
	(via
		(at 171.900001 145.1275)
		(size 0.45)
		(drill 0.1)
		(layers "F.Cu" "B.Cu")
		(net 1)
	)
	(via
		(at 134.877001 163.8025)
		(size 0.45)
		(drill 0.1)
		(layers "F.Cu" "B.Cu")
		(net 1)
	)
	(via
		(at 198.854001 165.999)
		(size 0.45)
		(drill 0.1)
		(layers "F.Cu" "B.Cu")
		(net 1)
	)
	(via
		(at 126.900501 196.901)
		(size 0.45)
		(drill 0.1)
		(layers "F.Cu" "B.Cu")
		(net 1)
	)
	(via
		(at 192.9 112.1)
		(size 0.45)
		(drill 0.1)
		(layers "F.Cu" "B.Cu")
		(net 1)
	)
	(via
		(at 154.5 112.1)
		(size 0.45)
		(drill 0.1)
		(layers "F.Cu" "B.Cu")
		(net 1)
	)
	(via
		(at 205.8 187.25)
		(size 0.45)
		(drill 0.1)
		(layers "F.Cu" "B.Cu")
		(net 1)
	)
	(via
		(at 123.900001 145.1275)
		(size 0.45)
		(drill 0.1)
		(layers "F.Cu" "B.Cu")
		(net 1)
	)
	(via
		(at 74.7 192.2)
		(size 0.45)
		(drill 0.1)
		(layers "F.Cu" "B.Cu")
		(net 1)
	)
	(via
		(at 76.773501 158.521)
		(size 0.45)
		(drill 0.1)
		(layers "F.Cu" "B.Cu")
		(net 1)
	)
	(via
		(at 128.9 112.1)
		(size 0.45)
		(drill 0.1)
		(layers "F.Cu" "B.Cu")
		(net 1)
	)
	(via
		(at 140.875001 179.8005)
		(size 0.45)
		(drill 0.1)
		(layers "F.Cu" "B.Cu")
		(net 1)
	)
	(via
		(at 174.8955 180.3985)
		(size 0.45)
		(drill 0.1)
		(layers "F.Cu" "B.Cu")
		(net 1)
	)
	(via
		(at 110 189.6)
		(size 0.45)
		(drill 0.1)
		(layers "F.Cu" "B.Cu")
		(net 1)
	)
	(via
		(at 91.048501 169.15)
		(size 0.45)
		(drill 0.1)
		(layers "F.Cu" "B.Cu")
		(net 1)
	)
	(via
		(at 128.877001 176.8005)
		(size 0.45)
		(drill 0.1)
		(layers "F.Cu" "B.Cu")
		(net 1)
	)
	(via
		(at 202.1 165.2)
		(size 0.45)
		(drill 0.1)
		(layers "F.Cu" "B.Cu")
		(net 1)
	)
	(via
		(at 103.9 190.9)
		(size 0.45)
		(drill 0.1)
		(layers "F.Cu" "B.Cu")
		(net 1)
	)
	(via
		(at 104.09 176.55)
		(size 0.45)
		(drill 0.1)
		(layers "F.Cu" "B.Cu")
		(net 1)
	)
	(via
		(at 199.2705 166.8515)
		(size 0.45)
		(drill 0.1)
		(layers "F.Cu" "B.Cu")
		(net 1)
	)
	(via
		(at 155.0015 178.126)
		(size 0.45)
		(drill 0.1)
		(layers "F.Cu" "B.Cu")
		(net 1)
	)
	(via
		(at 193.9 170.7)
		(size 0.45)
		(drill 0.1)
		(layers "F.Cu" "B.Cu")
		(net 1)
	)
	(via
		(at 137.45 144)
		(size 0.45)
		(drill 0.1)
		(layers "F.Cu" "B.Cu")
		(net 1)
	)
	(via
		(at 205.3 157.8)
		(size 0.45)
		(drill 0.1)
		(layers "F.Cu" "B.Cu")
		(net 1)
	)
	(via
		(at 122.225501 197.426)
		(size 0.45)
		(drill 0.1)
		(layers "F.Cu" "B.Cu")
		(net 1)
	)
	(via
		(at 163.9 184.2)
		(size 0.45)
		(drill 0.1)
		(layers "F.Cu" "B.Cu")
		(net 1)
	)
	(via
		(at 143.875001 176.8005)
		(size 0.45)
		(drill 0.1)
		(layers "F.Cu" "B.Cu")
		(net 1)
	)
	(via
		(at 159.3835 178.694)
		(size 0.45)
		(drill 0.1)
		(layers "F.Cu" "B.Cu")
		(net 1)
	)
	(via
		(at 146.978001 206.400501)
		(size 0.45)
		(drill 0.1)
		(layers "F.Cu" "B.Cu")
		(net 1)
	)
	(via
		(at 81.28 162.56)
		(size 0.45)
		(drill 0.1)
		(layers "F.Cu" "B.Cu")
		(net 1)
	)
	(via
		(at 106.68 152.4)
		(size 0.45)
		(drill 0.1)
		(layers "F.Cu" "B.Cu")
		(net 1)
	)
	(via
		(at 206.3 144.1)
		(size 0.45)
		(drill 0.1)
		(layers "F.Cu" "B.Cu")
		(net 1)
	)
	(via
		(at 185 166.2)
		(size 0.45)
		(drill 0.1)
		(layers "F.Cu" "B.Cu")
		(net 1)
	)
	(via
		(at 151.875001 172.8025)
		(size 0.45)
		(drill 0.1)
		(layers "F.Cu" "B.Cu")
		(net 1)
	)
	(via
		(at 84.5 112.1)
		(size 0.45)
		(drill 0.1)
		(layers "F.Cu" "B.Cu")
		(net 1)
	)
	(via
		(at 199.4975 182.9025)
		(size 0.45)
		(drill 0.1)
		(layers "F.Cu" "B.Cu")
		(net 1)
	)
	(via
		(at 109.22 198.12)
		(size 0.45)
		(drill 0.1)
		(layers "F.Cu" "B.Cu")
		(net 1)
	)
	(via
		(at 149.875001 171.8025)
		(size 0.45)
		(drill 0.1)
		(layers "F.Cu" "B.Cu")
		(net 1)
	)
	(via
		(at 107.96 163.76)
		(size 0.45)
		(drill 0.1)
		(layers "F.Cu" "B.Cu")
		(net 1)
	)
	(via
		(at 122.650001 137.7275)
		(size 0.45)
		(drill 0.1)
		(layers "F.Cu" "B.Cu")
		(net 1)
	)
	(via
		(at 147.6 204.3)
		(size 0.45)
		(drill 0.1)
		(layers "F.Cu" "B.Cu")
		(net 1)
	)
	(via
		(at 74.7 173.9)
		(size 0.45)
		(drill 0.1)
		(layers "F.Cu" "B.Cu")
		(net 1)
	)
	(via
		(at 127.877001 183.8005)
		(size 0.45)
		(drill 0.1)
		(layers "F.Cu" "B.Cu")
		(net 1)
	)
	(via
		(at 193.325 195.975)
		(size 0.45)
		(drill 0.1)
		(layers "F.Cu" "B.Cu")
		(net 1)
	)
	(via
		(at 88.84536 138.645487)
		(size 0.45)
		(drill 0.1)
		(layers "F.Cu" "B.Cu")
		(net 1)
	)
	(via
		(at 170.5 112.1)
		(size 0.45)
		(drill 0.1)
		(layers "F.Cu" "B.Cu")
		(net 1)
	)
	(via
		(at 188 157)
		(size 0.45)
		(drill 0.1)
		(layers "F.Cu" "B.Cu")
		(net 1)
	)
	(via
		(at 104.510501 154.386)
		(size 0.45)
		(drill 0.1)
		(layers "F.Cu" "B.Cu")
		(net 1)
	)
	(via
		(at 91.75 181.15)
		(size 0.45)
		(drill 0.1)
		(layers "F.Cu" "B.Cu")
		(net 1)
	)
	(via
		(at 152.15 139.8775)
		(size 0.45)
		(drill 0.1)
		(layers "F.Cu" "B.Cu")
		(net 1)
	)
	(via
		(at 152.2 181.3)
		(size 0.45)
		(drill 0.1)
		(layers "F.Cu" "B.Cu")
		(net 1)
	)
	(via
		(at 194.6 163.35)
		(size 0.45)
		(drill 0.1)
		(layers "F.Cu" "B.Cu")
		(net 1)
	)
	(via
		(at 148.875001 184.8005)
		(size 0.45)
		(drill 0.1)
		(layers "F.Cu" "B.Cu")
		(net 1)
	)
	(via
		(at 132.7 142.4)
		(size 0.45)
		(drill 0.1)
		(layers "F.Cu" "B.Cu")
		(net 1)
	)
	(via
		(at 197 162.7)
		(size 0.45)
		(drill 0.1)
		(layers "F.Cu" "B.Cu")
		(net 1)
	)
	(via
		(at 123.275001 206.300501)
		(size 0.45)
		(drill 0.1)
		(layers "F.Cu" "B.Cu")
		(net 1)
	)
	(via
		(at 118.575001 206.300501)
		(size 0.45)
		(drill 0.1)
		(layers "F.Cu" "B.Cu")
		(net 1)
	)
	(via
		(at 142.875001 170.8025)
		(size 0.45)
		(drill 0.1)
		(layers "F.Cu" "B.Cu")
		(net 1)
	)
	(via
		(at 121.42 205.800501)
		(size 0.45)
		(drill 0.1)
		(layers "F.Cu" "B.Cu")
		(net 1)
	)
	(via
		(at 199.2975 184.3025)
		(size 0.45)
		(drill 0.1)
		(layers "F.Cu" "B.Cu")
		(net 1)
	)
	(via
		(at 141.875001 182.8005)
		(size 0.45)
		(drill 0.1)
		(layers "F.Cu" "B.Cu")
		(net 1)
	)
	(via
		(at 206.0795 156.8025)
		(size 0.45)
		(drill 0.1)
		(layers "F.Cu" "B.Cu")
		(net 1)
	)
	(via
		(at 206.3 128.1)
		(size 0.45)
		(drill 0.1)
		(layers "F.Cu" "B.Cu")
		(net 1)
	)
	(via
		(at 135.3 112.1)
		(size 0.45)
		(drill 0.1)
		(layers "F.Cu" "B.Cu")
		(net 1)
	)
	(via
		(at 195.227 188.151)
		(size 0.45)
		(drill 0.1)
		(layers "F.Cu" "B.Cu")
		(net 1)
	)
	(via
		(at 149.875001 173.8025)
		(size 0.45)
		(drill 0.1)
		(layers "F.Cu" "B.Cu")
		(net 1)
	)
	(via
		(at 165.4 183.9)
		(size 0.45)
		(drill 0.1)
		(layers "F.Cu" "B.Cu")
		(net 1)
	)
	(via
		(at 145.875001 187.8005)
		(size 0.45)
		(drill 0.1)
		(layers "F.Cu" "B.Cu")
		(net 1)
	)
	(via
		(at 199.027 180.151)
		(size 0.45)
		(drill 0.1)
		(layers "F.Cu" "B.Cu")
		(net 1)
	)
	(via
		(at 133.000501 206.375501)
		(size 0.45)
		(drill 0.1)
		(layers "F.Cu" "B.Cu")
		(net 1)
	)
	(via
		(at 104.7 200.2)
		(size 0.45)
		(drill 0.1)
		(layers "F.Cu" "B.Cu")
		(net 1)
	)
	(via
		(at 194.6 162.05)
		(size 0.45)
		(drill 0.1)
		(layers "F.Cu" "B.Cu")
		(net 1)
	)
	(via
		(at 128.000501 206.400501)
		(size 0.45)
		(drill 0.1)
		(layers "F.Cu" "B.Cu")
		(net 1)
	)
	(via
		(at 195.8 200.6)
		(size 0.45)
		(drill 0.1)
		(layers "F.Cu" "B.Cu")
		(net 1)
	)
	(via
		(at 106.69 153.94)
		(size 0.45)
		(drill 0.1)
		(layers "F.Cu" "B.Cu")
		(net 1)
	)
	(via
		(at 163 184.2)
		(size 0.45)
		(drill 0.1)
		(layers "F.Cu" "B.Cu")
		(net 1)
	)
	(via
		(at 79.980501 190.316)
		(size 0.45)
		(drill 0.1)
		(layers "F.Cu" "B.Cu")
		(net 1)
	)
	(via
		(at 69.5 112.1)
		(size 0.45)
		(drill 0.1)
		(layers "F.Cu" "B.Cu")
		(net 1)
	)
	(via
		(at 150.875001 172.8025)
		(size 0.45)
		(drill 0.1)
		(layers "F.Cu" "B.Cu")
		(net 1)
	)
	(via
		(at 123.649499 179.980999)
		(size 0.45)
		(drill 0.1)
		(layers "F.Cu" "B.Cu")
		(net 1)
	)
	(via
		(at 126.650001 137.7275)
		(size 0.45)
		(drill 0.1)
		(layers "F.Cu" "B.Cu")
		(net 1)
	)
	(via
		(at 149.875001 178.8005)
		(size 0.45)
		(drill 0.1)
		(layers "F.Cu" "B.Cu")
		(net 1)
	)
	(via
		(at 199.213499 136.55)
		(size 0.45)
		(drill 0.1)
		(layers "F.Cu" "B.Cu")
		(net 1)
	)
	(via
		(at 154.2 200.6)
		(size 0.45)
		(drill 0.1)
		(layers "F.Cu" "B.Cu")
		(net 1)
	)
	(via
		(at 206.3 112.1)
		(size 0.45)
		(drill 0.1)
		(layers "F.Cu" "B.Cu")
		(net 1)
	)
	(via
		(at 75.150501 180.816)
		(size 0.45)
		(drill 0.1)
		(layers "F.Cu" "B.Cu")
		(net 1)
	)
	(via
		(at 136.000501 206.400501)
		(size 0.45)
		(drill 0.1)
		(layers "F.Cu" "B.Cu")
		(net 1)
	)
	(via
		(at 78.149 152.151)
		(size 0.45)
		(drill 0.1)
		(layers "F.Cu" "B.Cu")
		(net 1)
	)
	(via
		(at 139.875001 165.8025)
		(size 0.45)
		(drill 0.1)
		(layers "F.Cu" "B.Cu")
		(net 1)
	)
	(via
		(at 108.650001 137.7275)
		(size 0.45)
		(drill 0.1)
		(layers "F.Cu" "B.Cu")
		(net 1)
	)
	(via
		(at 124.900001 145.1275)
		(size 0.45)
		(drill 0.1)
		(layers "F.Cu" "B.Cu")
		(net 1)
	)
	(via
		(at 141.875001 161.8025)
		(size 0.45)
		(drill 0.1)
		(layers "F.Cu" "B.Cu")
		(net 1)
	)
	(via
		(at 196.6705 166.8515)
		(size 0.45)
		(drill 0.1)
		(layers "F.Cu" "B.Cu")
		(net 1)
	)
	(via
		(at 116.150501 177.426)
		(size 0.45)
		(drill 0.1)
		(layers "F.Cu" "B.Cu")
		(net 1)
	)
	(via
		(at 142.24 127)
		(size 0.45)
		(drill 0.1)
		(layers "F.Cu" "B.Cu")
		(net 1)
	)
	(via
		(at 88.2 191.01)
		(size 0.45)
		(drill 0.1)
		(layers "F.Cu" "B.Cu")
		(net 1)
	)
	(via
		(at 147.875001 183.8005)
		(size 0.45)
		(drill 0.1)
		(layers "F.Cu" "B.Cu")
		(net 1)
	)
	(via
		(at 161.5 156.2)
		(size 0.45)
		(drill 0.1)
		(layers "F.Cu" "B.Cu")
		(net 1)
	)
	(via
		(at 134.877001 184.8005)
		(size 0.45)
		(drill 0.1)
		(layers "F.Cu" "B.Cu")
		(net 1)
	)
	(via
		(at 95.3 165.6)
		(size 0.45)
		(drill 0.1)
		(layers "F.Cu" "B.Cu")
		(net 1)
	)
	(via
		(at 138.875501 175.801)
		(size 0.45)
		(drill 0.1)
		(layers "F.Cu" "B.Cu")
		(net 1)
	)
	(via
		(at 164.432501 177.960999)
		(size 0.45)
		(drill 0.1)
		(layers "F.Cu" "B.Cu")
		(net 1)
	)
	(via
		(at 180.2 164.6)
		(size 0.45)
		(drill 0.1)
		(layers "F.Cu" "B.Cu")
		(net 1)
	)
	(via
		(at 197.9975 183.1025)
		(size 0.45)
		(drill 0.1)
		(layers "F.Cu" "B.Cu")
		(net 1)
	)
	(via
		(at 98.559501 174.386)
		(size 0.45)
		(drill 0.1)
		(layers "F.Cu" "B.Cu")
		(net 1)
	)
	(via
		(at 181.225 151.875)
		(size 0.45)
		(drill 0.1)
		(layers "F.Cu" "B.Cu")
		(net 1)
	)
	(via
		(at 129.400001 145.1275)
		(size 0.45)
		(drill 0.1)
		(layers "F.Cu" "B.Cu")
		(net 1)
	)
	(via
		(at 116.1 172.2)
		(size 0.45)
		(drill 0.1)
		(layers "F.Cu" "B.Cu")
		(net 1)
	)
	(via
		(at 142.875001 177.8005)
		(size 0.45)
		(drill 0.1)
		(layers "F.Cu" "B.Cu")
		(net 1)
	)
	(via
		(at 205.55 194.2)
		(size 0.45)
		(drill 0.1)
		(layers "F.Cu" "B.Cu")
		(net 1)
	)
	(via
		(at 141.875001 176.8005)
		(size 0.45)
		(drill 0.1)
		(layers "F.Cu" "B.Cu")
		(net 1)
	)
	(via
		(at 173.575 128.425)
		(size 0.45)
		(drill 0.1)
		(layers "F.Cu" "B.Cu")
		(net 1)
	)
	(via
		(at 81.3 191)
		(size 0.45)
		(drill 0.1)
		(layers "F.Cu" "B.Cu")
		(net 1)
	)
	(via
		(at 205.8 186.575)
		(size 0.45)
		(drill 0.1)
		(layers "F.Cu" "B.Cu")
		(net 1)
	)
	(via
		(at 169.800501 199.876)
		(size 0.45)
		(drill 0.1)
		(layers "F.Cu" "B.Cu")
		(net 1)
	)
	(via
		(at 177.8 137.16)
		(size 0.45)
		(drill 0.1)
		(layers "F.Cu" "B.Cu")
		(net 1)
	)
	(via
		(at 103.275001 147.7185)
		(size 0.45)
		(drill 0.1)
		(layers "F.Cu" "B.Cu")
		(net 1)
	)
	(via
		(at 100.280501 142.456)
		(size 0.45)
		(drill 0.1)
		(layers "F.Cu" "B.Cu")
		(net 1)
	)
	(via
		(at 98.3 200.2)
		(size 0.45)
		(drill 0.1)
		(layers "F.Cu" "B.Cu")
		(net 1)
	)
	(via
		(at 188.95 167.5)
		(size 0.45)
		(drill 0.1)
		(layers "F.Cu" "B.Cu")
		(net 1)
	)
	(via
		(at 206.0795 152.8035)
		(size 0.45)
		(drill 0.1)
		(layers "F.Cu" "B.Cu")
		(net 1)
	)
	(via
		(at 190.325 183.7)
		(size 0.45)
		(drill 0.1)
		(layers "F.Cu" "B.Cu")
		(net 1)
	)
	(via
		(at 130.877001 171.8025)
		(size 0.45)
		(drill 0.1)
		(layers "F.Cu" "B.Cu")
		(net 1)
	)
	(via
		(at 171.700501 196.276)
		(size 0.45)
		(drill 0.1)
		(layers "F.Cu" "B.Cu")
		(net 1)
	)
	(via
		(at 112.150001 137.7275)
		(size 0.45)
		(drill 0.1)
		(layers "F.Cu" "B.Cu")
		(net 1)
	)
	(via
		(at 170.000501 192.676)
		(size 0.45)
		(drill 0.1)
		(layers "F.Cu" "B.Cu")
		(net 1)
	)
	(via
		(at 146.073001 206.400501)
		(size 0.45)
		(drill 0.1)
		(layers "F.Cu" "B.Cu")
		(net 1)
	)
	(segment
		(start 88.858823 137.897487)
		(end 88.858823 138.632024)
		(width 0.256)
		(layer "B.Cu")
		(net 1)
	)
	(segment
		(start 146.373501 164.301)
		(end 145.875001 163.8025)
		(width 0.4)
		(layer "B.Cu")
		(net 1)
	)
	(segment
		(start 138.277001 170.8025)
		(end 138.877001 170.2025)
		(width 0.4)
		(layer "B.Cu")
		(net 1)
	)
	(segment
		(start 94.848161 149.498161)
		(end 94.9 149.55)
		(width 0.2)
		(layer "B.Cu")
		(net 1)
	)
	(segment
		(start 142.075001 206.400501)
		(end 142.525501 206.851001)
		(width 0.22)
		(layer "B.Cu")
		(net 1)
	)
	(segment
		(start 139.875001 178.8005)
		(end 139.875001 178.8025)
		(width 0.4)
		(layer "B.Cu")
		(net 1)
	)
	(segment
		(start 85.680501 157.003149)
		(end 85.750501 157.073149)
		(width 0.2)
		(layer "B.Cu")
		(net 1)
	)
	(segment
		(start 137.877001 170.8025)
		(end 137.377002 171.3025)
		(width 0.4)
		(layer "B.Cu")
		(net 1)
	)
	(segment
		(start 147.326001 175.2515)
		(end 147.875001 175.8005)
		(width 0.4)
		(layer "B.Cu")
		(net 1)
	)
	(segment
		(start 105.96 172.468)
		(end 105.96 173.094672)
		(width 0.15)
		(layer "B.Cu")
		(net 1)
	)
	(segment
		(start 138.177001 170.8025)
		(end 137.877001 170.8025)
		(width 0.4)
		(layer "B.Cu")
		(net 1)
	)
	(segment
		(start 158.084 141.916)
		(end 157.4 141.916)
		(width 0.256)
		(layer "B.Cu")
		(net 1)
	)
	(segment
		(start 138.877001 170.2025)
		(end 138.877001 170.1025)
		(width 0.4)
		(layer "B.Cu")
		(net 1)
	)
	(segment
		(start 138.177001 170.8025)
		(end 138.277001 170.8025)
		(width 0.4)
		(layer "B.Cu")
		(net 1)
	)
	(segment
		(start 195.4 141.25)
		(end 195.375 141.225)
		(width 0.256)
		(layer "B.Cu")
		(net 1)
	)
	(segment
		(start 141.375001 182.3005)
		(end 141.875001 182.8005)
		(width 0.4)
		(layer "B.Cu")
		(net 1)
	)
	(segment
		(start 82.75 169.766)
		(end 82.834 169.766)
		(width 0.4)
		(layer "B.Cu")
		(net 1)
	)
	(segment
		(start 146.375501 164.301)
		(end 146.373501 164.301)
		(width 0.4)
		(layer "B.Cu")
		(net 1)
	)
	(segment
		(start 134.725 142.885)
		(end 134.725 143.5)
		(width 0.256)
		(layer "B.Cu")
		(net 1)
	)
	(segment
		(start 140.375001 173.3025)
		(end 140.875001 172.8025)
		(width 0.4)
		(layer "B.Cu")
		(net 1)
	)
	(segment
		(start 202.15 170.675)
		(end 202.849001 170.675)
		(width 0.256)
		(layer "B.Cu")
		(net 1)
	)
	(segment
		(start 92.308672 157.441328)
		(end 92.8 156.95)
		(width 0.4)
		(layer "B.Cu")
		(net 1)
	)
	(segment
		(start 145.875001 178.8005)
		(end 146.375001 179.3005)
		(width 0.4)
		(layer "B.Cu")
		(net 1)
	)
	(segment
		(start 141.377001 171.3025)
		(end 141.375001 171.3025)
		(width 0.4)
		(layer "B.Cu")
		(net 1)
	)
	(segment
		(start 108.4 142.885)
		(end 108.400001 145.1275)
		(width 0.256)
		(layer "B.Cu")
		(net 1)
	)
	(segment
		(start 142.875001 175.8005)
		(end 142.875001 174.8015)
		(width 0.4)
		(layer "B.Cu")
		(net 1)
	)
	(segment
		(start 149.377001 183.3005)
		(end 149.377001 183.2985)
		(width 0.4)
		(layer "B.Cu")
		(net 1)
	)
	(segment
		(start 137.375001 173.3025)
		(end 137.375001 173.3045)
		(width 0.4)
		(layer "B.Cu")
		(net 1)
	)
	(segment
		(start 140.375501 177.303)
		(end 140.377501 177.303)
		(width 0.256)
		(layer "B.Cu")
		(net 1)
	)
	(segment
		(start 144.373001 176.3025)
		(end 143.875001 176.8005)
		(width 0.4)
		(layer "B.Cu")
		(net 1)
	)
	(segment
		(start 202.809 184.725)
		(end 202.201 184.725)
		(width 0.256)
		(layer "B.Cu")
		(net 1)
	)
	(segment
		(start 128.000501 206.400501)
		(end 127.525501 206.875501)
		(width 0.22)
		(layer "B.Cu")
		(net 1)
	)
	(segment
		(start 94.308672 157.441328)
		(end 94.8 156.95)
		(width 0.4)
		(layer "B.Cu")
		(net 1)
	)
	(segment
		(start 197.18 145.801)
		(end 197.18 145.931)
		(width 0.256)
		(layer "B.Cu")
		(net 1)
	)
	(segment
		(start 142.875001 177.8005)
		(end 142.875001 177.8015)
		(width 0.4)
		(layer "B.Cu")
		(net 1)
	)
	(segment
		(start 196.215 188.363)
		(end 196.227 188.351)
		(width 0.256)
		(layer "B.Cu")
		(net 1)
	)
	(segment
		(start 146.073001 206.400501)
		(end 146.073001 207.9485)
		(width 0.22)
		(layer "B.Cu")
		(net 1)
	)
	(segment
		(start 146.373001 182.3025)
		(end 145.875001 182.8005)
		(width 0.4)
		(layer "B.Cu")
		(net 1)
	)
	(segment
		(start 138.875501 175.801)
		(end 138.875501 174.801)
		(width 0.4)
		(layer "B.Cu")
		(net 1)
	)
	(segment
		(start 138.373001 178.2965)
		(end 137.877001 177.8005)
		(width 0.4)
		(layer "B.Cu")
		(net 1)
	)
	(segment
		(start 148.875001 186.800501)
		(end 148.875001 186.1545)
		(width 0.256)
		(layer "B.Cu")
		(net 1)
	)
	(segment
		(start 105.96 176.684)
		(end 105.96 177.880984)
		(width 0.15)
		(layer "B.Cu")
		(net 1)
	)
	(segment
		(start 137.375501 184.301)
		(end 137.376501 184.301)
		(width 0.4)
		(layer "B.Cu")
		(net 1)
	)
	(segment
		(start 138.525501 206.875501)
		(end 138.525501 210.801)
		(width 0.22)
		(layer "B.Cu")
		(net 1)
	)
	(segment
		(start 140.374502 186.301)
		(end 139.875001 186.800501)
		(width 0.4)
		(layer "B.Cu")
		(net 1)
	)
	(segment
		(start 144.399998 142.885)
		(end 144.399998 143.784998)
		(width 0.256)
		(layer "B.Cu")
		(net 1)
	)
	(segment
		(start 151.184 141.916)
		(end 151.6 141.5)
		(width 0.256)
		(layer "B.Cu")
		(net 1)
	)
	(segment
		(start 137.375001 177.2985)
		(end 136.877001 176.8005)
		(width 0.4)
		(layer "B.Cu")
		(net 1)
	)
	(segment
		(start 139.875001 178.8025)
		(end 139.375001 179.3025)
		(width 0.4)
		(layer "B.Cu")
		(net 1)
	)
	(segment
		(start 141.372501 177.303)
		(end 140.875001 177.8005)
		(width 0.4)
		(layer "B.Cu")
		(net 1)
	)
	(segment
		(start 140.050501 206.400501)
		(end 139.525501 206.925501)
		(width 0.22)
		(layer "B.Cu")
		(net 1)
	)
	(segment
		(start 105.96 173.094672)
		(end 105.922344 173.132328)
		(width 0.15)
		(layer "B.Cu")
		(net 1)
	)
	(segment
		(start 202.95 184.866)
		(end 202.809 184.725)
		(width 0.256)
		(layer "B.Cu")
		(net 1)
	)
	(segment
		(start 130.378501 162.301)
		(end 130.877001 161.8025)
		(width 0.4)
		(layer "B.Cu")
		(net 1)
	)
	(segment
		(start 143.375501 167.303)
		(end 143.875001 167.8025)
		(width 0.4)
		(layer "B.Cu")
		(net 1)
	)
	(segment
		(start 98.776501 138.226)
		(end 98.786501 138.236)
		(width 0.256)
		(layer "B.Cu")
		(net 1)
	)
	(segment
		(start 139.377001 173.304501)
		(end 139.875001 173.802501)
		(width 0.4)
		(layer "B.Cu")
		(net 1)
	)
	(segment
		(start 86.536829 151.133157)
		(end 86.271821 150.868149)
		(width 0.2)
		(layer "B.Cu")
		(net 1)
	)
	(segment
		(start 146.375001 183.3005)
		(end 145.875001 183.8005)
		(width 0.4)
		(layer "B.Cu")
		(net 1)
	)
	(segment
		(start 139.875001 171.8025)
		(end 139.375001 171.3025)
		(width 0.4)
		(layer "B.Cu")
		(net 1)
	)
	(segment
		(start 128.375501 172.304)
		(end 127.877001 172.8025)
		(width 0.4)
		(layer "B.Cu")
		(net 1)
	)
	(segment
		(start 144.075501 174.002999)
		(end 143.875002 173.8025)
		(width 0.4)
		(layer "B.Cu")
		(net 1)
	)
	(segment
		(start 144.375001 176.3025)
		(end 144.373001 176.3025)
		(width 0.4)
		(layer "B.Cu")
		(net 1)
	)
	(segment
		(start 142.375001 176.3005)
		(end 141.875001 175.8005)
		(width 0.4)
		(layer "B.Cu")
		(net 1)
	)
	(segment
		(start 147.3735 167.301)
		(end 146.875001 166.802501)
		(width 0.4)
		(layer "B.Cu")
		(net 1)
	)
	(segment
		(start 198.763499 139.25)
		(end 198.1 139.25)
		(width 0.256)
		(layer "B.Cu")
		(net 1)
	)
	(segment
		(start 101.4 159.766)
		(end 101.616 159.55)
		(width 0.256)
		(layer "B.Cu")
		(net 1)
	)
	(segment
		(start 142.375001 170.3025)
		(end 142.875001 170.8025)
		(width 0.256)
		(layer "B.Cu")
		(net 1)
	)
	(segment
		(start 142.875001 172.8015)
		(end 143.375501 172.301)
		(width 0.4)
		(layer "B.Cu")
		(net 1)
	)
	(segment
		(start 87.4 184.9)
		(end 88.9 184.9)
		(width 0.15)
		(layer "B.Cu")
		(net 1)
	)
	(segment
		(start 126.2 201.825)
		(end 125.485 201.825)
		(width 0.177)
		(layer "B.Cu")
		(net 1)
	)
	(segment
		(start 156.002501 175.976)
		(end 156.002501 175.29)
		(width 0.4)
		(layer "B.Cu")
		(net 1)
	)
	(segment
		(start 144.075501 174.801)
		(end 144.075501 174.002999)
		(width 0.4)
		(layer "B.Cu")
		(net 1)
	)
	(segment
		(start 198.799499 139.214)
		(end 198.763499 139.25)
		(width 0.182)
		(layer "B.Cu")
		(net 1)
	)
	(segment
		(start 141.377501 173.301)
		(end 141.376501 173.301)
		(width 0.4)
		(layer "B.Cu")
		(net 1)
	)
	(segment
		(start 139.377001 173.3025)
		(end 139.377001 173.304501)
		(width 0.4)
		(layer "B.Cu")
		(net 1)
	)
	(segment
		(start 200.7 157.4)
		(end 200.297 157.803)
		(width 0.15)
		(layer "B.Cu")
		(net 1)
	)
	(segment
		(start 145.375501 170.302)
		(end 144.875001 170.8025)
		(width 0.4)
		(layer "B.Cu")
		(net 1)
	)
	(segment
		(start 133.375501 167.301)
		(end 133.375501 167.304)
		(width 0.4)
		(layer "B.Cu")
		(net 1)
	)
	(segment
		(start 93.6 154.8)
		(end 93.923672 154.8)
		(width 0.256)
		(layer "B.Cu")
		(net 1)
	)
	(segment
		(start 150.375501 169.302)
		(end 150.875001 168.8025)
		(width 0.4)
		(layer "B.Cu")
		(net 1)
	)
	(segment
		(start 202.875 165.335)
		(end 202.74 165.2)
		(width 0.256)
		(layer "B.Cu")
		(net 1)
	)
	(segment
		(start 103.474 176.55)
		(end 103.34 176.684)
		(width 0.15)
		(layer "B.Cu")
		(net 1)
	)
	(segment
		(start 131.3785 165.301)
		(end 131.877 164.8025)
		(width 0.4)
		(layer "B.Cu")
		(net 1)
	)
	(segment
		(start 90.086829 149.149157)
		(end 90.086829 148.5905)
		(width 0.256)
		(layer "B.Cu")
		(net 1)
	)
	(segment
		(start 136.002501 159.575)
		(end 135.001384 159.575)
		(width 0.4)
		(layer "B.Cu")
		(net 1)
	)
	(segment
		(start 88.858823 138.632024)
		(end 88.84536 138.645487)
		(width 0.201)
		(layer "B.Cu")
		(net 1)
	)
	(segment
		(start 202.74 165.2)
		(end 202.1 165.2)
		(width 0.256)
		(layer "B.Cu")
		(net 1)
	)
	(segment
		(start 171.800501 196.376)
		(end 171.700501 196.276)
		(width 0.4)
		(layer "B.Cu")
		(net 1)
	)
	(segment
		(start 140.377501 177.303)
		(end 140.875001 177.8005)
		(width 0.256)
		(layer "B.Cu")
		(net 1)
	)
	(segment
		(start 148.375501 162.301)
		(end 148.375501 162.303)
		(width 0.4)
		(layer "B.Cu")
		(net 1)
	)
	(segment
		(start 142.375501 186.3)
		(end 142.875001 185.8005)
		(width 0.4)
		(layer "B.Cu")
		(net 1)
	)
	(segment
		(start 141.375501 177.303)
		(end 141.372501 177.303)
		(width 0.4)
		(layer "B.Cu")
		(net 1)
	)
	(segment
		(start 84.773 129.7)
		(end 84.773 130.685)
		(width 0.4)
		(layer "B.Cu")
		(net 1)
	)
	(segment
		(start 145.875001 176.8005)
		(end 145.373001 177.3025)
		(width 0.256)
		(layer "B.Cu")
		(net 1)
	)
	(segment
		(start 138.875501 174.801)
		(end 138.875501 173.801)
		(width 0.4)
		(layer "B.Cu")
		(net 1)
	)
	(segment
		(start 127.877001 162.8025)
		(end 127.375501 162.301)
		(width 0.4)
		(layer "B.Cu")
		(net 1)
	)
	(segment
		(start 128.375501 172.301)
		(end 128.375501 172.304)
		(width 0.4)
		(layer "B.Cu")
		(net 1)
	)
	(segment
		(start 137.877002 175.804501)
		(end 138.375001 176.3025)
		(width 0.4)
		(layer "B.Cu")
		(net 1)
	)
	(segment
		(start 138.400501 172.279)
		(end 137.877001 172.8025)
		(width 0.4)
		(layer "B.Cu")
		(net 1)
	)
	(segment
		(start 127.525501 206.875501)
		(end 127.525501 210.801)
		(width 0.22)
		(layer "B.Cu")
		(net 1)
	)
	(segment
		(start 95.0005 164.451)
		(end 95 164.4515)
		(width 0.256)
		(layer "B.Cu")
		(net 1)
	)
	(segment
		(start 144.399998 143.784998)
		(end 144.4 143.785)
		(width 0.256)
		(layer "B.Cu")
		(net 1)
	)
	(segment
		(start 141.373501 169.301)
		(end 140.875001 168.8025)
		(width 0.4)
		(layer "B.Cu")
		(net 1)
	)
	(segment
		(start 202.79 182.75)
		(end 202.125 182.75)
		(width 0.256)
		(layer "B.Cu")
		(net 1)
	)
	(segment
		(start 147.326001 175.2515)
		(end 147.126001 175.2515)
		(width 0.4)
		(layer "B.Cu")
		(net 1)
	)
	(segment
		(start 200.297 157.803)
		(end 198.955 157.803)
		(width 0.15)
		(layer "B.Cu")
		(net 1)
	)
	(segment
		(start 94.053157 149.808165)
		(end 94.138157 149.808165)
		(width 0.2)
		(layer "B.Cu")
		(net 1)
	)
	(segment
		(start 147.375001 170.3005)
		(end 147.377001 170.3005)
		(width 0.4)
		(layer "B.Cu")
		(net 1)
	)
	(segment
		(start 115.285501 181.249999)
		(end 115.750001 180.785502)
		(width 0.256)
		(layer "B.Cu")
		(net 1)
	)
	(segment
		(start 114.275501 177.426)
		(end 115.564501 177.426)
		(width 0.4)
		(layer "B.Cu")
		(net 1)
	)
	(segment
		(start 148.375501 162.303)
		(end 148.875001 162.8025)
		(width 0.4)
		(layer "B.Cu")
		(net 1)
	)
	(segment
		(start 137.877002 175.8005)
		(end 137.877002 175.804501)
		(width 0.4)
		(layer "B.Cu")
		(net 1)
	)
	(segment
		(start 93.308672 157.520992)
		(end 93.308672 157.441328)
		(width 0.4)
		(layer "B.Cu")
		(net 1)
	)
	(segment
		(start 147.875001 175.8005)
		(end 148.375501 176.301)
		(width 0.4)
		(layer "B.Cu")
		(net 1)
	)
	(segment
		(start 150.875002 179.8005)
		(end 150.377002 180.2985)
		(width 0.4)
		(layer "B.Cu")
		(net 1)
	)
	(segment
		(start 88.9 184.9)
		(end 90.1 186.1)
		(width 0.15)
		(layer "B.Cu")
		(net 1)
	)
	(segment
		(start 115.596501 177.426)
		(end 115.580501 177.41)
		(width 0.4)
		(layer "B.Cu")
		(net 1)
	)
	(segment
		(start 133.525501 210.806)
		(end 133.525501 206.900501)
		(width 0.4)
		(layer "B.Cu")
		(net 1)
	)
	(segment
		(start 135.875501 174.801)
		(end 134.950501 174.801)
		(width 0.4)
		(layer "B.Cu")
		(net 1)
	)
	(segment
		(start 145.373001 177.3025)
		(end 144.375001 177.3025)
		(width 0.256)
		(layer "B.Cu")
		(net 1)
	)
	(segment
		(start 146.373501 177.299)
		(end 145.875001 176.8005)
		(width 0.4)
		(layer "B.Cu")
		(net 1)
	)
	(segment
		(start 148.875001 186.1545)
		(end 148.879001 186.1505)
		(width 0.256)
		(layer "B.Cu")
		(net 1)
	)
	(segment
		(start 138.900501 183.836)
		(end 138.870501 183.806)
		(width 0.256)
		(layer "B.Cu")
		(net 1)
	)
	(segment
		(start 144.375501 172.301)
		(end 144.373501 172.301)
		(width 0.4)
		(layer "B.Cu")
		(net 1)
	)
	(segment
		(start 141.376501 173.301)
		(end 140.875001 173.8025)
		(width 0.4)
		(layer "B.Cu")
		(net 1)
	)
	(segment
		(start 151.376501 162.301)
		(end 151.875001 161.8025)
		(width 0.4)
		(layer "B.Cu")
		(net 1)
	)
	(segment
		(start 196.334 128.15)
		(end 198.885501 128.15)
		(width 0.4)
		(layer "B.Cu")
		(net 1)
	)
	(segment
		(start 134.375501 170.3025)
		(end 134.375501 170.304)
		(width 0.4)
		(layer "B.Cu")
		(net 1)
	)
	(segment
		(start 103.850002 130.549998)
		(end 105.975 128.425)
		(width 0.4)
		(layer "B.Cu")
		(net 1)
	)
	(segment
		(start 196.066 141.25)
		(end 195.4 141.25)
		(width 0.256)
		(layer "B.Cu")
		(net 1)
	)
	(segment
		(start 110 181.63)
		(end 108.57 180.2)
		(width 0.15)
		(layer "B.Cu")
		(net 1)
	)
	(segment
		(start 98.220501 138.226)
		(end 98.776501 138.226)
		(width 0.256)
		(layer "B.Cu")
		(net 1)
	)
	(segment
		(start 128.375501 165.301)
		(end 128.877001 165.8025)
		(width 0.4)
		(layer "B.Cu")
		(net 1)
	)
	(segment
		(start 137.375501 162.301)
		(end 137.877002 162.8025)
		(width 0.4)
		(layer "B.Cu")
		(net 1)
	)
	(segment
		(start 84.773 129.073)
		(end 84.75 129.05)
		(width 0.4)
		(layer "B.Cu")
		(net 1)
	)
	(segment
		(start 142.374001 170.3025)
		(end 142.375001 170.3025)
		(width 0.256)
		(layer "B.Cu")
		(net 1)
	)
	(segment
		(start 134.375501 163.301)
		(end 134.877001 163.8025)
		(width 0.4)
		(layer "B.Cu")
		(net 1)
	)
	(segment
		(start 202.925 182.885)
		(end 202.79 182.75)
		(width 0.256)
		(layer "B.Cu")
		(net 1)
	)
	(segment
		(start 131.375501 171.304)
		(end 130.877001 171.8025)
		(width 0.4)
		(layer "B.Cu")
		(net 1)
	)
	(segment
		(start 95.550501 164.451)
		(end 95.0005 164.451)
		(width 0.256)
		(layer "B.Cu")
		(net 1)
	)
	(segment
		(start 142.334 159.6)
		(end 142.334 160.7)
		(width 0.201)
		(layer "B.Cu")
		(net 1)
	)
	(segment
		(start 172.316501 196.376)
		(end 171.800501 196.376)
		(width 0.4)
		(layer "B.Cu")
		(net 1)
	)
	(segment
		(start 145.375001 184.3005)
		(end 145.875001 184.8005)
		(width 0.4)
		(layer "B.Cu")
		(net 1)
	)
	(segment
		(start 126.376501 181.301)
		(end 126.877001 180.8005)
		(width 0.4)
		(layer "B.Cu")
		(net 1)
	)
	(segment
		(start 146.073001 207.9485)
		(end 146.525501 208.401)
		(width 0.22)
		(layer "B.Cu")
		(net 1)
	)
	(segment
		(start 117.850501 204.626)
		(end 117.600501 204.876)
		(width 0.201)
		(layer "B.Cu")
		(net 1)
	)
	(segment
		(start 92.3 149.55)
		(end 91.749157 149.55)
		(width 0.256)
		(layer "B.Cu")
		(net 1)
	)
	(segment
		(start 130.375501 183.3005)
		(end 130.377001 183.3005)
		(width 0.4)
		(layer "B.Cu")
		(net 1)
	)
	(segment
		(start 197.05 162.65)
		(end 197 162.7)
		(width 0.256)
		(layer "B.Cu")
		(net 1)
	)
	(segment
		(start 144.375501 182.300001)
		(end 144.875001 181.800501)
		(width 0.4)
		(layer "B.Cu")
		(net 1)
	)
	(segment
		(start 92.3 149.55)
		(end 92.787672 149.55)
		(width 0.256)
		(layer "B.Cu")
		(net 1)
	)
	(segment
		(start 129.375501 168.301)
		(end 129.877001 168.8025)
		(width 0.4)
		(layer "B.Cu")
		(net 1)
	)
	(segment
		(start 151.375501 162.301)
		(end 151.376501 162.301)
		(width 0.4)
		(layer "B.Cu")
		(net 1)
	)
	(segment
		(start 144.399999 147.277498)
		(end 144.400001 147.2775)
		(width 0.256)
		(layer "B.Cu")
		(net 1)
	)
	(segment
		(start 135.525501 206.875501)
		(end 135.525501 210.801)
		(width 0.22)
		(layer "B.Cu")
		(net 1)
	)
	(segment
		(start 115.564501 177.426)
		(end 115.580501 177.41)
		(width 0.198)
		(layer "B.Cu")
		(net 1)
	)
	(segment
		(start 129.375501 180.301)
		(end 129.3765 180.301)
		(width 0.4)
		(layer "B.Cu")
		(net 1)
	)
	(segment
		(start 139.375001 177.3005)
		(end 139.875001 176.8005)
		(width 0.4)
		(layer "B.Cu")
		(net 1)
	)
	(segment
		(start 85.680501 156.248149)
		(end 85.680501 157.003149)
		(width 0.2)
		(layer "B.Cu")
		(net 1)
	)
	(segment
		(start 86.271821 150.868149)
		(end 85.680501 150.868149)
		(width 0.2)
		(layer "B.Cu")
		(net 1)
	)
	(segment
		(start 138.877001 170.1025)
		(end 138.877001 170.776)
		(width 0.4)
		(layer "B.Cu")
		(net 1)
	)
	(segment
		(start 197.185 179.4)
		(end 197.075 179.51)
		(width 0.256)
		(layer "B.Cu")
		(net 1)
	)
	(segment
		(start 153.975001 166.7025)
		(end 153.975001 167.4025)
		(width 0.4)
		(layer "B.Cu")
		(net 1)
	)
	(segment
		(start 145.375501 170.301)
		(end 145.375501 170.302)
		(width 0.4)
		(layer "B.Cu")
		(net 1)
	)
	(segment
		(start 136.375501 166.304)
		(end 135.877001 166.8025)
		(width 0.4)
		(layer "B.Cu")
		(net 1)
	)
	(segment
		(start 202.125 182.75)
		(end 202.075 182.7)
		(width 0.256)
		(layer "B.Cu")
		(net 1)
	)
	(segment
		(start 139.525501 206.925501)
		(end 139.525501 210.801)
		(width 0.22)
		(layer "B.Cu")
		(net 1)
	)
	(segment
		(start 134.877001 174.7275)
		(end 134.950501 174.801)
		(width 0.4)
		(layer "B.Cu")
		(net 1)
	)
	(segment
		(start 147.377001 170.3005)
		(end 147.875001 169.8025)
		(width 0.4)
		(layer "B.Cu")
		(net 1)
	)
	(segment
		(start 143.875001 178.8005)
		(end 143.375001 178.3005)
		(width 0.4)
		(layer "B.Cu")
		(net 1)
	)
	(segment
		(start 148.375501 176.301)
		(end 148.875001 176.8005)
		(width 0.4)
		(layer "B.Cu")
		(net 1)
	)
	(segment
		(start 117.850501 204.176)
		(end 117.850501 204.626)
		(width 0.201)
		(layer "B.Cu")
		(net 1)
	)
	(segment
		(start 201.8 157.4)
		(end 200.7 157.4)
		(width 0.15)
		(layer "B.Cu")
		(net 1)
	)
	(segment
		(start 124.75 188.335)
		(end 125.342501 188.335)
		(width 0.256)
		(layer "B.Cu")
		(net 1)
	)
	(segment
		(start 91.179008 157.520992)
		(end 91.75 156.95)
		(width 0.4)
		(layer "B.Cu")
		(net 1)
	)
	(segment
		(start 108.1 131.1)
		(end 108.1 130.55)
		(width 0.4)
		(layer "B.Cu")
		(net 1)
	)
	(segment
		(start 130.525501 206.875501)
		(end 130.525501 210.801)
		(width 0.22)
		(layer "B.Cu")
		(net 1)
	)
	(segment
		(start 146.375501 177.299)
		(end 146.373501 177.299)
		(width 0.4)
		(layer "B.Cu")
		(net 1)
	)
	(segment
		(start 82.834 169.766)
		(end 83.4 169.2)
		(width 0.4)
		(layer "B.Cu")
		(net 1)
	)
	(segment
		(start 141.875001 178.8025)
		(end 141.375001 179.3025)
		(width 0.4)
		(layer "B.Cu")
		(net 1)
	)
	(segment
		(start 198.885501 128.15)
		(end 198.889501 128.146)
		(width 0.256)
		(layer "B.Cu")
		(net 1)
	)
	(segment
		(start 151 141.916)
		(end 151.184 141.916)
		(width 0.256)
		(layer "B.Cu")
		(net 1)
	)
	(segment
		(start 197.16 161.95)
		(end 197.05 162.06)
		(width 0.256)
		(layer "B.Cu")
		(net 1)
	)
	(segment
		(start 133.900501 174.776)
		(end 134.925501 174.776)
		(width 0.4)
		(layer "B.Cu")
		(net 1)
	)
	(segment
		(start 94.138157 149.808165)
		(end 94.448161 149.498161)
		(width 0.2)
		(layer "B.Cu")
		(net 1)
	)
	(segment
		(start 141.875001 161.8025)
		(end 141.875001 161.158999)
		(width 0.256)
		(layer "B.Cu")
		(net 1)
	)
	(segment
		(start 131.375501 165.301)
		(end 131.3785 165.301)
		(width 0.4)
		(layer "B.Cu")
		(net 1)
	)
	(segment
		(start 182.88 177.9)
		(end 182.88 179.07)
		(width 0.256)
		(layer "B.Cu")
		(net 1)
	)
	(segment
		(start 134.925501 174.776)
		(end 134.950501 174.801)
		(width 0.4)
		(layer "B.Cu")
		(net 1)
	)
	(segment
		(start 130.375501 162.301)
		(end 130.378501 162.301)
		(width 0.4)
		(layer "B.Cu")
		(net 1)
	)
	(segment
		(start 101.375251 160.2955)
		(end 101.4 160.270751)
		(width 0.256)
		(layer "B.Cu")
		(net 1)
	)
	(segment
		(start 134.877001 173.8025)
		(end 134.877001 174.7275)
		(width 0.4)
		(layer "B.Cu")
		(net 1)
	)
	(segment
		(start 135.001384 159.575)
		(end 134.875 159.701384)
		(width 0.4)
		(layer "B.Cu")
		(net 1)
	)
	(segment
		(start 146.525501 208.401)
		(end 146.525501 210.801)
		(width 0.22)
		(layer "B.Cu")
		(net 1)
	)
	(segment
		(start 137.375001 177.3025)
		(end 137.375001 177.2985)
		(width 0.4)
		(layer "B.Cu")
		(net 1)
	)
	(segment
		(start 144.075501 174.801)
		(end 142.875501 174.801)
		(width 0.4)
		(layer "B.Cu")
		(net 1)
	)
	(segment
		(start 196.215 170.915)
		(end 196.2 170.9)
		(width 0.256)
		(layer "B.Cu")
		(net 1)
	)
	(segment
		(start 95.308672 157.520992)
		(end 95.829664 157)
		(width 0.4)
		(layer "B.Cu")
		(net 1)
	)
	(segment
		(start 91.749157 149.55)
		(end 91.5 149.799157)
		(width 0.256)
		(layer "B.Cu")
		(net 1)
	)
	(segment
		(start 136.377001 172.3025)
		(end 136.877001 171.8025)
		(width 0.4)
		(layer "B.Cu")
		(net 1)
	)
	(segment
		(start 98.584 155.2)
		(end 98.584 155.934)
		(width 0.256)
		(layer "B.Cu")
		(net 1)
	)
	(segment
		(start 94.284 164.4515)
		(end 95 164.4515)
		(width 0.256)
		(layer "B.Cu")
		(net 1)
	)
	(segment
		(start 149.375 182.3005)
		(end 148.875001 182.800499)
		(width 0.4)
		(layer "B.Cu")
		(net 1)
	)
	(segment
		(start 152.375001 177.3005)
		(end 151.875001 177.8005)
		(width 0.4)
		(layer "B.Cu")
		(net 1)
	)
	(segment
		(start 133.375501 167.304)
		(end 132.877001 167.8025)
		(width 0.4)
		(layer "B.Cu")
		(net 1)
	)
	(segment
		(start 138.050501 206.400501)
		(end 138.525501 206.875501)
		(width 0.22)
		(layer "B.Cu")
		(net 1)
	)
	(segment
		(start 202.251001 188.15)
		(end 202.91 188.15)
		(width 0.256)
		(layer "B.Cu")
		(net 1)
	)
	(segment
		(start 115.284502 183.799999)
		(end 115.284502 184.484501)
		(width 0.256)
		(layer "B.Cu")
		(net 1)
	)
	(segment
		(start 142.875001 172.8025)
		(end 142.875001 172.8015)
		(width 0.4)
		(layer "B.Cu")
		(net 1)
	)
	(segment
		(start 150.375501 166.301)
		(end 150.373501 166.301)
		(width 0.4)
		(layer "B.Cu")
		(net 1)
	)
	(segment
		(start 99.078157 150.818165)
		(end 99.103157 150.793165)
		(width 0.2)
		(layer "B.Cu")
		(net 1)
	)
	(segment
		(start 141.874001 171.8025)
		(end 141.375501 172.301)
		(width 0.4)
		(layer "B.Cu")
		(net 1)
	)
	(segment
		(start 135.084501 189.276)
		(end 135.720501 189.276)
		(width 0.4)
		(layer "B.Cu")
		(net 1)
	)
	(segment
		(start 145.377001 180.3025)
		(end 145.875001 180.8005)
		(width 0.4)
		(layer "B.Cu")
		(net 1)
	)
	(segment
		(start 145.875001 178.8005)
		(end 145.875001 178.8015)
		(width 0.4)
		(layer "B.Cu")
		(net 1)
	)
	(segment
		(start 143.525501 206.875501)
		(end 143.525501 210.801)
		(width 0.22)
		(layer "B.Cu")
		(net 1)
	)
	(segment
		(start 144.375001 177.3025)
		(end 144.375001 177.3005)
		(width 0.4)
		(layer "B.Cu")
		(net 1)
	)
	(segment
		(start 141.875001 161.158999)
		(end 142.334 160.7)
		(width 0.256)
		(layer "B.Cu")
		(net 1)
	)
	(segment
		(start 96.375501 164.436)
		(end 95.565501 164.436)
		(width 0.256)
		(layer "B.Cu")
		(net 1)
	)
	(segment
		(start 135.720501 189.276)
		(end 135.730501 189.266)
		(width 0.1)
		(layer "B.Cu")
		(net 1)
	)
	(segment
		(start 144.375501 182.301)
		(end 144.375501 182.300001)
		(width 0.4)
		(layer "B.Cu")
		(net 1)
	)
	(segment
		(start 84.773 129.7)
		(end 85.5 129.7)
		(width 0.4)
		(layer "B.Cu")
		(net 1)
	)
	(segment
		(start 98.584 155.934)
		(end 98.65 156)
		(width 0.256)
		(layer "B.Cu")
		(net 1)
	)
	(segment
		(start 149.377001 182.3005)
		(end 149.375 182.3005)
		(width 0.4)
		(layer "B.Cu")
		(net 1)
	)
	(segment
		(start 131.376501 186.301)
		(end 131.877001 185.8005)
		(width 0.4)
		(layer "B.Cu")
		(net 1)
	)
	(segment
		(start 136.375501 166.301)
		(end 136.375501 166.304)
		(width 0.4)
		(layer "B.Cu")
		(net 1)
	)
	(segment
		(start 136.148001 159.5755)
		(end 136.075001 159.5025)
		(width 0.4)
		(layer "B.Cu")
		(net 1)
	)
	(segment
		(start 98.220501 138.326)
		(end 98.696501 138.326)
		(width 0.1)
		(layer "B.Cu")
		(net 1)
	)
	(segment
		(start 132.65 142.4)
		(end 132.166 141.916)
		(width 0.256)
		(layer "B.Cu")
		(net 1)
	)
	(segment
		(start 127.375501 184.301)
		(end 127.376501 184.301)
		(width 0.4)
		(layer "B.Cu")
		(net 1)
	)
	(segment
		(start 137.375001 180.3025)
		(end 136.877001 180.8005)
		(width 0.4)
		(layer "B.Cu")
		(net 1)
	)
	(segment
		(start 115.750001 180.785502)
		(end 115.750001 180.65)
		(width 0.256)
		(layer "B.Cu")
		(net 1)
	)
	(segment
		(start 148.377001 178.3025)
		(end 147.875001 177.8005)
		(width 0.4)
		(layer "B.Cu")
		(net 1)
	)
	(segment
		(start 90.086829 148.5905)
		(end 90.091329 148.586)
		(width 0.256)
		(layer "B.Cu")
		(net 1)
	)
	(segment
		(start 115.284502 184.484501)
		(end 115.300001 184.5)
		(width 0.256)
		(layer "B.Cu")
		(net 1)
	)
	(segment
		(start 202.15 167.25)
		(end 202.1 167.2)
		(width 0.256)
		(layer "B.Cu")
		(net 1)
	)
	(segment
		(start 202.734 167.25)
		(end 202.15 167.25)
		(width 0.256)
		(layer "B.Cu")
		(net 1)
	)
	(segment
		(start 146.375001 182.3025)
		(end 146.373001 182.3025)
		(width 0.4)
		(layer "B.Cu")
		(net 1)
	)
	(segment
		(start 104.09 176.55)
		(end 103.474 176.55)
		(width 0.15)
		(layer "B.Cu")
		(net 1)
	)
	(segment
		(start 145.373501 173.301)
		(end 144.875001 172.8025)
		(width 0.4)
		(layer "B.Cu")
		(net 1)
	)
	(segment
		(start 125.342501 188.335)
		(end 125.877001 187.8005)
		(width 0.256)
		(layer "B.Cu")
		(net 1)
	)
	(segment
		(start 198.714499 146.801)
		(end 198.699499 146.816)
		(width 0.182)
		(layer "B.Cu")
		(net 1)
	)
	(segment
		(start 116.150501 177.426)
		(end 115.596501 177.426)
		(width 0.4)
		(layer "B.Cu")
		(net 1)
	)
	(segment
		(start 143.375501 167.301)
		(end 143.375501 167.303)
		(width 0.4)
		(layer "B.Cu")
		(net 1)
	)
	(segment
		(start 145.875001 178.8015)
		(end 145.375501 179.301)
		(width 0.4)
		(layer "B.Cu")
		(net 1)
	)
	(segment
		(start 145.375501 173.301)
		(end 145.373501 173.301)
		(width 0.4)
		(layer "B.Cu")
		(net 1)
	)
	(segment
		(start 131.375501 176.301)
		(end 131.376501 176.301)
		(width 0.4)
		(layer "B.Cu")
		(net 1)
	)
	(segment
		(start 145.875001 186.8005)
		(end 146.374501 186.301)
		(width 0.4)
		(layer "B.Cu")
		(net 1)
	)
	(segment
		(start 137.292001 159.5755)
		(end 136.148001 159.5755)
		(width 0.4)
		(layer "B.Cu")
		(net 1)
	)
	(segment
		(start 142.375001 176.3025)
		(end 142.375001 176.3005)
		(width 0.4)
		(layer "B.Cu")
		(net 1)
	)
	(segment
		(start 172.3 181.9)
		(end 173.2 181.9)
		(width 0.15)
		(layer "B.Cu")
		(net 1)
	)
	(segment
		(start 137.375501 169.304)
		(end 136.877001 169.8025)
		(width 0.4)
		(layer "B.Cu")
		(net 1)
	)
	(segment
		(start 196.215 189.175)
		(end 196.215 188.363)
		(width 0.256)
		(layer "B.Cu")
		(net 1)
	)
	(segment
		(start 197.05 162.06)
		(end 197.05 162.65)
		(width 0.256)
		(layer "B.Cu")
		(net 1)
	)
	(segment
		(start 143.375501 165.301)
		(end 143.373501 165.301)
		(width 0.4)
		(layer "B.Cu")
		(net 1)
	)
	(segment
		(start 142.525501 206.851001)
		(end 142.525501 210.801)
		(width 0.22)
		(layer "B.Cu")
		(net 1)
	)
	(segment
		(start 139.875001 165.8015)
		(end 140.375501 165.301)
		(width 0.4)
		(layer "B.Cu")
		(net 1)
	)
	(segment
		(start 100.280501 143.062)
		(end 100.280501 142.456)
		(width 0.256)
		(layer "B.Cu")
		(net 1)
	)
	(segment
		(start 132.7 142.4)
		(end 132.65 142.4)
		(width 0.256)
		(layer "B.Cu")
		(net 1)
	)
	(segment
		(start 119.580501 175.442)
		(end 120.134501 175.442)
		(width 0.4)
		(layer "B.Cu")
		(net 1)
	)
	(segment
		(start 82.831897 137.18)
		(end 82.09736 137.18)
		(width 0.256)
		(layer "B.Cu")
		(net 1)
	)
	(segment
		(start 150.375501 169.3025)
		(end 150.375501 169.302)
		(width 0.4)
		(layer "B.Cu")
		(net 1)
	)
	(segment
		(start 117.525501 210.801)
		(end 117.525501 207.851)
		(width 0.4)
		(layer "B.Cu")
		(net 1)
	)
	(segment
		(start 98.363157 150.818165)
		(end 99.078157 150.818165)
		(width 0.2)
		(layer "B.Cu")
		(net 1)
	)
	(segment
		(start 138 143.45)
		(end 137.45 144)
		(width 0.256)
		(layer "B.Cu")
		(net 1)
	)
	(segment
		(start 104.95 172.468)
		(end 105.96 172.468)
		(width 0.15)
		(layer "B.Cu")
		(net 1)
	)
	(segment
		(start 118.150501 173.426)
		(end 118.150501 172.882)
		(width 0.4)
		(layer "B.Cu")
		(net 1)
	)
	(segment
		(start 128.852994 174.801)
		(end 127.775501 174.801)
		(width 0.4)
		(layer "B.Cu")
		(net 1)
	)
	(segment
		(start 91.15 157.520992)
		(end 91.179008 157.520992)
		(width 0.4)
		(layer "B.Cu")
		(net 1)
	)
	(segment
		(start 144.4 143.785)
		(end 144.399999 147.277498)
		(width 0.256)
		(layer "B.Cu")
		(net 1)
	)
	(segment
		(start 197.18 145.931)
		(end 198.065 146.816)
		(width 0.256)
		(layer "B.Cu")
		(net 1)
	)
	(segment
		(start 95.334 149.55)
		(end 95.6 149.816)
		(width 0.2)
		(layer "B.Cu")
		(net 1)
	)
	(segment
		(start 136.075001 159.5025)
		(end 136.002501 159.575)
		(width 0.4)
		(layer "B.Cu")
		(net 1)
	)
	(segment
		(start 138 142.885)
		(end 138 143.45)
		(width 0.256)
		(layer "B.Cu")
		(net 1)
	)
	(segment
		(start 132.800501 174.776)
		(end 133.900501 174.776)
		(width 0.4)
		(layer "B.Cu")
		(net 1)
	)
	(segment
		(start 202.201 184.725)
		(end 202.127 184.651)
		(width 0.256)
		(layer "B.Cu")
		(net 1)
	)
	(segment
		(start 148.375001 179.3005)
		(end 148.875001 178.8005)
		(width 0.256)
		(layer "B.Cu")
		(net 1)
	)
	(segment
		(start 144.375001 177.3005)
		(end 143.875001 176.8005)
		(width 0.4)
		(layer "B.Cu")
		(net 1)
	)
	(segment
		(start 171.450002 130.549998)
		(end 173.575 128.425)
		(width 0.4)
		(layer "B.Cu")
		(net 1)
	)
	(segment
		(start 117.600501 204.876)
		(end 117.600501 205.392)
		(width 0.201)
		(layer "B.Cu")
		(net 1)
	)
	(segment
		(start 142.875001 177.8015)
		(end 142.375501 178.301)
		(width 0.4)
		(layer "B.Cu")
		(net 1)
	)
	(segment
		(start 137.376501 184.301)
		(end 137.877001 183.8005)
		(width 0.4)
		(layer "B.Cu")
		(net 1)
	)
	(segment
		(start 95.565501 164.436)
		(end 95.550501 164.451)
		(width 0.256)
		(layer "B.Cu")
		(net 1)
	)
	(segment
		(start 144.000501 206.400501)
		(end 143.525501 206.875501)
		(width 0.22)
		(layer "B.Cu")
		(net 1)
	)
	(segment
		(start 98.696501 138.326)
		(end 98.786501 138.236)
		(width 0.1)
		(layer "B.Cu")
		(net 1)
	)
	(segment
		(start 140.375501 176.301)
		(end 140.375501 176.3)
		(width 0.4)
		(layer "B.Cu")
		(net 1)
	)
	(segment
		(start 150.373501 166.301)
		(end 149.875001 165.8025)
		(width 0.4)
		(layer "B.Cu")
		(net 1)
	)
	(segment
		(start 139.875001 165.8025)
		(end 139.875001 165.8015)
		(width 0.256)
		(layer "B.Cu")
		(net 1)
	)
	(segment
		(start 92.787672 149.55)
		(end 93.036829 149.799157)
		(width 0.256)
		(layer "B.Cu")
		(net 1)
	)
	(segment
		(start 92.308672 157.520992)
		(end 92.308672 157.441328)
		(width 0.4)
		(layer "B.Cu")
		(net 1)
	)
	(segment
		(start 131.375501 186.301)
		(end 131.376501 186.301)
		(width 0.4)
		(layer "B.Cu")
		(net 1)
	)
	(segment
		(start 90.108672 157.520992)
		(end 91.15 157.520992)
		(width 0.4)
		(layer "B.Cu")
		(net 1)
	)
	(segment
		(start 108.1 130.55)
		(end 105.975 128.425)
		(width 0.4)
		(layer "B.Cu")
		(net 1)
	)
	(segment
		(start 93.923672 154.8)
		(end 94.258672 154.465)
		(width 0.256)
		(layer "B.Cu")
		(net 1)
	)
	(segment
		(start 134.000501 206.375501)
		(end 133.525501 206.850501)
		(width 0.22)
		(layer "B.Cu")
		(net 1)
	)
	(segment
		(start 89.086829 149.149157)
		(end 89.086829 148.579672)
		(width 0.256)
		(layer "B.Cu")
		(net 1)
	)
	(segment
		(start 127.376501 184.301)
		(end 127.877001 183.8005)
		(width 0.4)
		(layer "B.Cu")
		(net 1)
	)
	(segment
		(start 137.375501 169.301)
		(end 137.375501 169.304)
		(width 0.4)
		(layer "B.Cu")
		(net 1)
	)
	(segment
		(start 142.875001 174.8015)
		(end 142.875501 174.801)
		(width 0.4)
		(layer "B.Cu")
		(net 1)
	)
	(segment
		(start 94.308672 157.520992)
		(end 94.308672 157.441328)
		(width 0.4)
		(layer "B.Cu")
		(net 1)
	)
	(segment
		(start 198.699499 146.816)
		(end 198.065 146.816)
		(width 0.182)
		(layer "B.Cu")
		(net 1)
	)
	(segment
		(start 145.377001 186.3005)
		(end 145.377001 186.2985)
		(width 0.4)
		(layer "B.Cu")
		(net 1)
	)
	(segment
		(start 143.373501 165.301)
		(end 142.875001 164.8025)
		(width 0.4)
		(layer "B.Cu")
		(net 1)
	)
	(segment
		(start 147.375501 167.301)
		(end 147.3735 167.301)
		(width 0.4)
		(layer "B.Cu")
		(net 1)
	)
	(segment
		(start 138.900501 184.576)
		(end 138.900501 183.836)
		(width 0.256)
		(layer "B.Cu")
		(net 1)
	)
	(segment
		(start 202.849001 170.675)
		(end 202.881001 170.707)
		(width 0.256)
		(layer "B.Cu")
		(net 1)
	)
	(segment
		(start 197.075 180.103)
		(end 197.027 180.151)
		(width 0.256)
		(layer "B.Cu")
		(net 1)
	)
	(segment
		(start 138.877001 170.776)
		(end 138.850501 170.8025)
		(width 0.4)
		(layer "B.Cu")
		(net 1)
	)
	(segment
		(start 94.9 149.55)
		(end 95.334 149.55)
		(width 0.2)
		(layer "B.Cu")
		(net 1)
	)
	(segment
		(start 136.000501 206.400501)
		(end 135.525501 206.875501)
		(width 0.22)
		(layer "B.Cu")
		(net 1)
	)
	(segment
		(start 202.91 188.15)
		(end 202.925 188.135)
		(width 0.256)
		(layer "B.Cu")
		(net 1)
	)
	(segment
		(start 105.96 177.880984)
		(end 105.981344 177.902328)
		(width 0.15)
		(layer "B.Cu")
		(net 1)
	)
	(segment
		(start 103.850002 131.105)
		(end 103.850002 130.549998)
		(width 0.4)
		(layer "B.Cu")
		(net 1)
	)
	(segment
		(start 141.875002 171.8025)
		(end 141.874001 171.8025)
		(width 0.4)
		(layer "B.Cu")
		(net 1)
	)
	(segment
		(start 93.308672 157.441328)
		(end 93.8 156.95)
		(width 0.4)
		(layer "B.Cu")
		(net 1)
	)
	(segment
		(start 197.075 179.51)
		(end 197.075 180.103)
		(width 0.256)
		(layer "B.Cu")
		(net 1)
	)
	(segment
		(start 133.525501 206.900501)
		(end 133.000501 206.375501)
		(width 0.22)
		(layer "B.Cu")
		(net 1)
	)
	(segment
		(start 140.375501 186.301)
		(end 140.374502 186.301)
		(width 0.4)
		(layer "B.Cu")
		(net 1)
	)
	(segment
		(start 120.134501 175.442)
		(end 120.150501 175.426)
		(width 0.4)
		(layer "B.Cu")
		(net 1)
	)
	(segment
		(start 156.002501 175.29)
		(end 156.016501 175.276)
		(width 0.4)
		(layer "B.Cu")
		(net 1)
	)
	(segment
		(start 149.377001 183.2985)
		(end 149.875001 182.8005)
		(width 0.4)
		(layer "B.Cu")
		(net 1)
	)
	(segment
		(start 131.375501 171.301)
		(end 131.375501 171.304)
		(width 0.4)
		(layer "B.Cu")
		(net 1)
	)
	(segment
		(start 101.4 160.270751)
		(end 101.4 159.766)
		(width 0.256)
		(layer "B.Cu")
		(net 1)
	)
	(segment
		(start 141.375001 171.3025)
		(end 140.875001 170.8025)
		(width 0.4)
		(layer "B.Cu")
		(net 1)
	)
	(segment
		(start 131.000501 206.400501)
		(end 130.525501 206.875501)
		(width 0.22)
		(layer "B.Cu")
		(net 1)
	)
	(segment
		(start 149.375001 176.3005)
		(end 148.875001 176.8005)
		(width 0.4)
		(layer "B.Cu")
		(net 1)
	)
	(segment
		(start 132.166 141.916)
		(end 132.05 141.916)
		(width 0.256)
		(layer "B.Cu")
		(net 1)
	)
	(segment
		(start 137.375001 173.3045)
		(end 136.877001 173.8025)
		(width 0.4)
		(layer "B.Cu")
		(net 1)
	)
	(segment
		(start 142.375501 186.301)
		(end 142.375501 186.3)
		(width 0.4)
		(layer "B.Cu")
		(net 1)
	)
	(segment
		(start 95.829664 157)
		(end 96.15 157)
		(width 0.4)
		(layer "B.Cu")
		(net 1)
	)
	(segment
		(start 89.086829 148.579672)
		(end 89.090501 148.576)
		(width 0.256)
		(layer "B.Cu")
		(net 1)
	)
	(segment
		(start 145.377001 186.2985)
		(end 145.875001 185.8005)
		(width 0.4)
		(layer "B.Cu")
		(net 1)
	)
	(segment
		(start 86.536829 151.433157)
		(end 86.536829 151.133157)
		(width 0.2)
		(layer "B.Cu")
		(net 1)
	)
	(segment
		(start 144.373501 172.301)
		(end 143.875001 171.8025)
		(width 0.4)
		(layer "B.Cu")
		(net 1)
	)
	(segment
		(start 171.450002 131.105)
		(end 171.450002 130.549998)
		(width 0.4)
		(layer "B.Cu")
		(net 1)
	)
	(segment
		(start 118.150501 172.882)
		(end 118.134501 172.866)
		(width 0.4)
		(layer "B.Cu")
		(net 1)
	)
	(segment
		(start 108.57 180.2)
		(end 107.826 180.2)
		(width 0.15)
		(layer "B.Cu")
		(net 1)
	)
	(segment
		(start 153.975001 167.4025)
		(end 154.075001 167.5025)
		(width 0.4)
		(layer "B.Cu")
		(net 1)
	)
	(segment
		(start 129.3765 180.301)
		(end 129.877 179.8005)
		(width 0.4)
		(layer "B.Cu")
		(net 1)
	)
	(segment
		(start 139.375001 177.3025)
		(end 139.375001 177.3005)
		(width 0.4)
		(layer "B.Cu")
		(net 1)
	)
	(segment
		(start 196.215 171.725)
		(end 196.215 170.915)
		(width 0.256)
		(layer "B.Cu")
		(net 1)
	)
	(segment
		(start 130.377001 183.3005)
		(end 130.877001 182.8005)
		(width 0.4)
		(layer "B.Cu")
		(net 1)
	)
	(segment
		(start 141.375501 180.301)
		(end 140.875001 179.8005)
		(width 0.4)
		(layer "B.Cu")
		(net 1)
	)
	(segment
		(start 101.625501 164.436)
		(end 96.375501 164.436)
		(width 0.256)
		(layer "B.Cu")
		(net 1)
	)
	(segment
		(start 126.375501 181.301)
		(end 126.376501 181.301)
		(width 0.4)
		(layer "B.Cu")
		(net 1)
	)
	(segment
		(start 138.373001 178.3025)
		(end 138.373001 178.2965)
		(width 0.4)
		(layer "B.Cu")
		(net 1)
	)
	(segment
		(start 134.375501 170.304)
		(end 133.877001 170.8025)
		(width 0.4)
		(layer "B.Cu")
		(net 1)
	)
	(segment
		(start 141.65 141.895)
		(end 141.67 141.915)
		(width 0.201)
		(layer "B.Cu")
		(net 1)
	)
	(segment
		(start 147.126001 175.2515)
		(end 146.675501 174.801)
		(width 0.4)
		(layer "B.Cu")
		(net 1)
	)
	(segment
		(start 131.376501 176.301)
		(end 131.877001 175.8005)
		(width 0.4)
		(layer "B.Cu")
		(net 1)
	)
	(segment
		(start 117.600501 205.392)
		(end 117.634501 205.426)
		(width 0.201)
		(layer "B.Cu")
		(net 1)
	)
	(segment
		(start 84.773 130.685)
		(end 84.758 130.7)
		(width 0.4)
		(layer "B.Cu")
		(net 1)
	)
	(segment
		(start 141.65 139.8775)
		(end 141.65 141.895)
		(width 0.201)
		(layer "B.Cu")
		(net 1)
	)
	(segment
		(start 140.375501 176.3)
		(end 140.875001 175.8005)
		(width 0.4)
		(layer "B.Cu")
		(net 1)
	)
	(segment
		(start 84.773 129.7)
		(end 84.773 129.073)
		(width 0.4)
		(layer "B.Cu")
		(net 1)
	)
	(segment
		(start 145.375001 180.3025)
		(end 145.377001 180.3025)
		(width 0.4)
		(layer "B.Cu")
		(net 1)
	)
	(segment
		(start 141.875001 178.8005)
		(end 141.875001 178.8025)
		(width 0.4)
		(layer "B.Cu")
		(net 1)
	)
	(segment
		(start 94.448161 149.498161)
		(end 94.848161 149.498161)
		(width 0.2)
		(layer "B.Cu")
		(net 1)
	)
	(segment
		(start 142.376501 162.304)
		(end 141.875001 161.8025)
		(width 0.4)
		(layer "B.Cu")
		(net 1)
	)
	(segment
		(start 141.375501 169.301)
		(end 141.373501 169.301)
		(width 0.4)
		(layer "B.Cu")
		(net 1)
	)
	(segment
		(start 202.9 167.416)
		(end 202.734 167.25)
		(width 0.256)
		(layer "B.Cu")
		(net 1)
	)
	(segment
		(start 138.850501 170.8025)
		(end 138.177001 170.8025)
		(width 0.4)
		(layer "B.Cu")
		(net 1)
	)
	(segment
		(start 75.0395 157.552999)
		(end 73.952999 157.552999)
		(width 0.256)
		(layer "F.Cu")
		(net 2)
	)
	(segment
		(start 73.952999 157.552999)
		(end 73.2 156.8)
		(width 0.256)
		(layer "F.Cu")
		(net 2)
	)
	(segment
		(start 76.384 152.916)
		(end 77.1 152.2)
		(width 0.4)
		(layer "F.Cu")
		(net 2)
	)
	(segment
		(start 77.4 152.6)
		(end 78.8 152.6)
		(width 0.182)
		(layer "F.Cu")
		(net 2)
	)
	(segment
		(start 75.530501 152.916)
		(end 76.384 152.916)
		(width 0.4)
		(layer "F.Cu")
		(net 2)
	)
	(segment
		(start 73.2 153.6)
		(end 73.721999 153.078001)
		(width 0.256)
		(layer "F.Cu")
		(net 2)
	)
	(segment
		(start 78.15 150.149)
		(end 78.149 150.15)
		(width 0.15)
		(layer "F.Cu")
		(net 2)
	)
	(segment
		(start 79.648 150.15)
		(end 79.649 150.149)
		(width 0.4)
		(layer "F.Cu")
		(net 2)
	)
	(segment
		(start 78.15 149)
		(end 78.15 150.149)
		(width 0.15)
		(layer "F.Cu")
		(net 2)
	)
	(segment
		(start 73.721999 153.078001)
		(end 75.0385 153.078001)
		(width 0.256)
		(layer "F.Cu")
		(net 2)
	)
	(segment
		(start 77.1 152.2)
		(end 77.3 152)
		(width 0.4)
		(layer "F.Cu")
		(net 2)
	)
	(segment
		(start 77.1 152.3)
		(end 77.4 152.6)
		(width 0.182)
		(layer "F.Cu")
		(net 2)
	)
	(segment
		(start 73.2 156.8)
		(end 73.2 153.6)
		(width 0.256)
		(layer "F.Cu")
		(net 2)
	)
	(segment
		(start 77.95 150.15)
		(end 78.149 150.15)
		(width 0.4)
		(layer "F.Cu")
		(net 2)
	)
	(segment
		(start 79.351 152.049)
		(end 78.8 152.6)
		(width 0.182)
		(layer "F.Cu")
		(net 2)
	)
	(segment
		(start 75.200501 157.714)
		(end 75.0395 157.552999)
		(width 0.256)
		(layer "F.Cu")
		(net 2)
	)
	(segment
		(start 78.149 150.15)
		(end 79.648 150.15)
		(width 0.4)
		(layer "F.Cu")
		(net 2)
	)
	(segment
		(start 77.3 152)
		(end 77.3 150.8)
		(width 0.4)
		(layer "F.Cu")
		(net 2)
	)
	(segment
		(start 77.1 152.2)
		(end 77.1 152.3)
		(width 0.182)
		(layer "F.Cu")
		(net 2)
	)
	(segment
		(start 79.649 152.049)
		(end 79.351 152.049)
		(width 0.182)
		(layer "F.Cu")
		(net 2)
	)
	(segment
		(start 77.3 150.8)
		(end 77.95 150.15)
		(width 0.4)
		(layer "F.Cu")
		(net 2)
	)
	(segment
		(start 75.0385 153.078001)
		(end 75.200501 152.916)
		(width 0.256)
		(layer "F.Cu")
		(net 2)
	)
	(segment
		(start 92.982501 175.551)
		(end 91.689001 175.551)
		(width 0.256)
		(layer "F.Cu")
		(net 3)
	)
	(segment
		(start 93.398501 175.135)
		(end 92.982501 175.551)
		(width 0.256)
		(layer "F.Cu")
		(net 3)
	)
	(segment
		(start 90.691501 175.551)
		(end 90.690501 175.552)
		(width 0.256)
		(layer "F.Cu")
		(net 3)
	)
	(segment
		(start 91.689001 175.551)
		(end 90.691501 175.551)
		(width 0.256)
		(layer "F.Cu")
		(net 3)
	)
	(segment
		(start 94.621501 175.135)
		(end 93.398501 175.135)
		(width 0.256)
		(layer "F.Cu")
		(net 3)
	)
	(segment
		(start 89.405501 175.552)
		(end 89.310501 175.647)
		(width 0.256)
		(layer "F.Cu")
		(net 3)
	)
	(segment
		(start 90.690501 175.552)
		(end 89.405501 175.552)
		(width 0.256)
		(layer "F.Cu")
		(net 3)
	)
	(segment
		(start 94.622001 172.136)
		(end 93.426016 172.136)
		(width 0.15)
		(layer "F.Cu")
		(net 4)
	)
	(segment
		(start 94.055986 168.035)
		(end 92.858501 168.035)
		(width 0.15)
		(layer "F.Cu")
		(net 4)
	)
	(segment
		(start 92.848501 171.558485)
		(end 92.848501 168.025)
		(width 0.15)
		(layer "F.Cu")
		(net 4)
	)
	(segment
		(start 93.426016 172.136)
		(end 92.848501 171.558485)
		(width 0.15)
		(layer "F.Cu")
		(net 4)
	)
	(segment
		(start 91.689001 172.019)
		(end 91.769 172.019)
		(width 0.256)
		(layer "F.Cu")
		(net 5)
	)
	(segment
		(start 92.886 173.136)
		(end 94.622001 173.136)
		(width 0.256)
		(layer "F.Cu")
		(net 5)
	)
	(segment
		(start 89.407501 172.02)
		(end 90.690501 172.02)
		(width 0.256)
		(layer "F.Cu")
		(net 5)
	)
	(segment
		(start 90.691501 172.019)
		(end 90.690501 172.02)
		(width 0.256)
		(layer "F.Cu")
		(net 5)
	)
	(segment
		(start 91.689001 172.019)
		(end 90.691501 172.019)
		(width 0.256)
		(layer "F.Cu")
		(net 5)
	)
	(segment
		(start 91.769 172.019)
		(end 92.886 173.136)
		(width 0.256)
		(layer "F.Cu")
		(net 5)
	)
	(segment
		(start 89.310501 171.923)
		(end 89.407501 172.02)
		(width 0.256)
		(layer "F.Cu")
		(net 5)
	)
	(segment
		(start 97.9 180.116)
		(end 97.9 179.5)
		(width 0.15)
		(layer "F.Cu")
		(net 6)
	)
	(segment
		(start 82.35 150.149)
		(end 83.648 150.149)
		(width 0.4)
		(layer "F.Cu")
		(net 6)
	)
	(segment
		(start 105.24 172.361)
		(end 104.991 172.361)
		(width 0.114)
		(layer "F.Cu")
		(net 6)
	)
	(segment
		(start 97.196799 192.403201)
		(end 96.843598 192.05)
		(width 0.201)
		(layer "F.Cu")
		(net 6)
	)
	(segment
		(start 104.05 173.75)
		(end 104.966016 173.75)
		(width 0.256)
		(layer "F.Cu")
		(net 6)
	)
	(segment
		(start 83.648 150.149)
		(end 83.649 150.15)
		(width 0.4)
		(layer "F.Cu")
		(net 6)
	)
	(segment
		(start 103.93 171.05)
		(end 103.93 170.63)
		(width 0.15)
		(layer "F.Cu")
		(net 6)
	)
	(segment
		(start 104.649 171.309)
		(end 104.38 171.309)
		(width 0.114)
		(layer "F.Cu")
		(net 6)
	)
	(segment
		(start 104.649 175.009)
		(end 104.38 175.009)
		(width 0.114)
		(layer "F.Cu")
		(net 6)
	)
	(segment
		(start 104.966016 173.75)
		(end 104.983344 173.767328)
		(width 0.256)
		(layer "F.Cu")
		(net 6)
	)
	(segment
		(start 99.847344 168.026328)
		(end 99.847344 168.047344)
		(width 0.256)
		(layer "F.Cu")
		(net 6)
	)
	(segment
		(start 104.189 171.309)
		(end 103.93 171.05)
		(width 0.15)
		(layer "F.Cu")
		(net 6)
	)
	(segment
		(start 104.38 171.309)
		(end 104.189 171.309)
		(width 0.15)
		(layer "F.Cu")
		(net 6)
	)
	(segment
		(start 94.699 189.799)
		(end 94.699 190.699)
		(width 0.201)
		(layer "F.Cu")
		(net 6)
	)
	(segment
		(start 104.982344 173.767328)
		(end 104.982344 173.142328)
		(width 0.256)
		(layer "F.Cu")
		(net 6)
	)
	(segment
		(start 89.310501 178.086)
		(end 89.300501 178.096)
		(width 0.256)
		(layer "F.Cu")
		(net 6)
	)
	(segment
		(start 98.309501 170.448)
		(end 98.309501 169.759501)
		(width 0.256)
		(layer "F.Cu")
		(net 6)
	)
	(segment
		(start 107.201 181.152)
		(end 107.835 181.152)
		(width 0.15)
		(layer "F.Cu")
		(net 6)
	)
	(segment
		(start 97.271672 168.037)
		(end 97.272344 168.036328)
		(width 0.256)
		(layer "F.Cu")
		(net 6)
	)
	(segment
		(start 89.300501 178.096)
		(end 90.619 178.096)
		(width 0.256)
		(layer "F.Cu")
		(net 6)
	)
	(segment
		(start 104.81 175.88)
		(end 104.81 175.17)
		(width 0.114)
		(layer "F.Cu")
		(net 6)
	)
	(segment
		(start 97.272344 168.722344)
		(end 97.272344 168.036328)
		(width 0.256)
		(layer "F.Cu")
		(net 6)
	)
	(segment
		(start 92.316 189.516)
		(end 92.3 189.5)
		(width 0.201)
		(layer "F.Cu")
		(net 6)
	)
	(segment
		(start 84.25 150.15)
		(end 83.649 150.15)
		(width 0.4)
		(layer "F.Cu")
		(net 6)
	)
	(segment
		(start 99.847344 168.047344)
		(end 101.308501 169.508501)
		(width 0.256)
		(layer "F.Cu")
		(net 6)
	)
	(segment
		(start 89.310501 177.426)
		(end 89.310501 178.086)
		(width 0.256)
		(layer "F.Cu")
		(net 6)
	)
	(segment
		(start 98.309501 169.759501)
		(end 97.272344 168.722344)
		(width 0.256)
		(layer "F.Cu")
		(net 6)
	)
	(segment
		(start 104.991 172.361)
		(end 104.81 172.18)
		(width 0.114)
		(layer "F.Cu")
		(net 6)
	)
	(segment
		(start 102.496501 174.136)
		(end 103.664 174.136)
		(width 0.256)
		(layer "F.Cu")
		(net 6)
	)
	(segment
		(start 107.835 181.152)
		(end 107.851 181.168)
		(width 0.15)
		(layer "F.Cu")
		(net 6)
	)
	(segment
		(start 101.308501 169.508501)
		(end 101.308501 170.448)
		(width 0.256)
		(layer "F.Cu")
		(net 6)
	)
	(segment
		(start 106.151 181.435)
		(end 106.884 181.435)
		(width 0.15)
		(layer "F.Cu")
		(net 6)
	)
	(segment
		(start 103.93 170.63)
		(end 104.03 170.53)
		(width 0.15)
		(layer "F.Cu")
		(net 6)
	)
	(segment
		(start 104.991 176.061)
		(end 104.81 175.88)
		(width 0.114)
		(layer "F.Cu")
		(net 6)
	)
	(segment
		(start 96.6 168.037)
		(end 97.271672 168.037)
		(width 0.256)
		(layer "F.Cu")
		(net 6)
	)
	(segment
		(start 94.416 189.516)
		(end 94.699 189.799)
		(width 0.201)
		(layer "F.Cu")
		(net 6)
	)
	(segment
		(start 105.24 176.061)
		(end 104.991 176.061)
		(width 0.114)
		(layer "F.Cu")
		(net 6)
	)
	(segment
		(start 84.5 150.4)
		(end 84.5 150.8)
		(width 0.4)
		(layer "F.Cu")
		(net 6)
	)
	(segment
		(start 84.35 150.25)
		(end 84.5 150.4)
		(width 0.4)
		(layer "F.Cu")
		(net 6)
	)
	(segment
		(start 104.81 171.47)
		(end 104.649 171.309)
		(width 0.114)
		(layer "F.Cu")
		(net 6)
	)
	(segment
		(start 93 189.516)
		(end 92.316 189.516)
		(width 0.201)
		(layer "F.Cu")
		(net 6)
	)
	(segment
		(start 103.664 174.136)
		(end 104.05 173.75)
		(width 0.256)
		(layer "F.Cu")
		(net 6)
	)
	(segment
		(start 106.884 181.435)
		(end 107.251 181.068)
		(width 0.15)
		(layer "F.Cu")
		(net 6)
	)
	(segment
		(start 90.238829 170.124672)
		(end 89.299658 170.124672)
		(width 0.256)
		(layer "F.Cu")
		(net 6)
	)
	(segment
		(start 99.3 168.75)
		(end 99.3 168.573672)
		(width 0.256)
		(layer "F.Cu")
		(net 6)
	)
	(segment
		(start 104.03 170.53)
		(end 104.775501 170.53)
		(width 0.15)
		(layer "F.Cu")
		(net 6)
	)
	(segment
		(start 104.81 172.18)
		(end 104.81 171.47)
		(width 0.114)
		(layer "F.Cu")
		(net 6)
	)
	(segment
		(start 93 189.516)
		(end 94.416 189.516)
		(width 0.201)
		(layer "F.Cu")
		(net 6)
	)
	(segment
		(start 95.4 181.45)
		(end 96.184 181.45)
		(width 0.256)
		(layer "F.Cu")
		(net 6)
	)
	(segment
		(start 90.619 178.096)
		(end 90.715 178)
		(width 0.256)
		(layer "F.Cu")
		(net 6)
	)
	(segment
		(start 104.81 175.17)
		(end 104.649 175.009)
		(width 0.114)
		(layer "F.Cu")
		(net 6)
	)
	(segment
		(start 96.45 179.65)
		(end 95.809501 179.009501)
		(width 0.15)
		(layer "F.Cu")
		(net 6)
	)
	(segment
		(start 96.843598 192.05)
		(end 96.447 192.05)
		(width 0.201)
		(layer "F.Cu")
		(net 6)
	)
	(segment
		(start 84.35 150.25)
		(end 84.25 150.15)
		(width 0.4)
		(layer "F.Cu")
		(net 6)
	)
	(segment
		(start 97.9 179.5)
		(end 97.6 179.2)
		(width 0.15)
		(layer "F.Cu")
		(net 6)
	)
	(segment
		(start 97.9 180.116)
		(end 97.434 179.65)
		(width 0.15)
		(layer "F.Cu")
		(net 6)
	)
	(segment
		(start 97.7 190.485)
		(end 97.7 191.1)
		(width 0.201)
		(layer "F.Cu")
		(net 6)
	)
	(segment
		(start 97.434 179.65)
		(end 96.45 179.65)
		(width 0.15)
		(layer "F.Cu")
		(net 6)
	)
	(segment
		(start 95.809501 179.009501)
		(end 95.809501 178.323)
		(width 0.15)
		(layer "F.Cu")
		(net 6)
	)
	(segment
		(start 99.3 168.573672)
		(end 99.847344 168.026328)
		(width 0.256)
		(layer "F.Cu")
		(net 6)
	)
	(segment
		(start 96.184 181.45)
		(end 96.5 181.134)
		(width 0.256)
		(layer "F.Cu")
		(net 6)
	)
	(segment
		(start 104.38 175.009)
		(end 103.354501 175.009)
		(width 0.15)
		(layer "F.Cu")
		(net 6)
	)
	(segment
		(start 96.5 180.9865)
		(end 97.134 180.9865)
		(width 0.15)
		(layer "F.Cu")
		(net 6)
	)
	(segment
		(start 103.354501 175.009)
		(end 103.325501 174.98)
		(width 0.15)
		(layer "F.Cu")
		(net 6)
	)
	(via
		(at 84.5 150.8)
		(size 0.45)
		(drill 0.1)
		(layers "F.Cu" "B.Cu")
		(net 6)
	)
	(via
		(at 96.6 168.037)
		(size 0.45)
		(drill 0.1)
		(layers "F.Cu" "B.Cu")
		(net 6)
	)
	(via
		(at 99.3 168.75)
		(size 0.45)
		(drill 0.1)
		(layers "F.Cu" "B.Cu")
		(net 6)
	)
	(via
		(at 104.962344 173.122328)
		(size 0.45)
		(drill 0.1)
		(layers "F.Cu" "B.Cu")
		(net 6)
	)
	(via
		(at 104.775501 170.53)
		(size 0.45)
		(drill 0.1)
		(layers "F.Cu" "B.Cu")
		(net 6)
	)
	(via
		(at 89.300501 178.096)
		(size 0.45)
		(drill 0.1)
		(layers "F.Cu" "B.Cu")
		(net 6)
	)
	(via
		(at 97.15 181.0025)
		(size 0.45)
		(drill 0.1)
		(layers "F.Cu" "B.Cu")
		(net 6)
	)
	(via
		(at 89.3 172.8)
		(size 0.45)
		(drill 0.1)
		(layers "F.Cu" "B.Cu")
		(net 6)
	)
	(via
		(at 84.35 150.25)
		(size 0.45)
		(drill 0.1)
		(layers "F.Cu" "B.Cu")
		(net 6)
	)
	(via
		(at 103.325501 174.98)
		(size 0.45)
		(drill 0.1)
		(layers "F.Cu" "B.Cu")
		(net 6)
	)
	(via
		(at 91.6 179.4)
		(size 0.45)
		(drill 0.1)
		(layers "F.Cu" "B.Cu")
		(net 6)
	)
	(via
		(at 90.252501 170.111)
		(size 0.45)
		(drill 0.1)
		(layers "F.Cu" "B.Cu")
		(net 6)
	)
	(via
		(at 92.3 189.5)
		(size 0.45)
		(drill 0.1)
		(layers "F.Cu" "B.Cu")
		(net 6)
	)
	(via
		(at 97.6 179.2)
		(size 0.45)
		(drill 0.1)
		(layers "F.Cu" "B.Cu")
		(net 6)
	)
	(via
		(at 97.196799 192.403201)
		(size 0.45)
		(drill 0.1)
		(layers "F.Cu" "B.Cu")
		(net 6)
	)
	(via
		(at 97.7 191.1)
		(size 0.45)
		(drill 0.1)
		(layers "F.Cu" "B.Cu")
		(net 6)
	)
	(via
		(at 107.851 181.168)
		(size 0.45)
		(drill 0.1)
		(layers "F.Cu" "B.Cu")
		(net 6)
	)
	(segment
		(start 97.193598 192.4)
		(end 96 192.4)
		(width 0.4)
		(layer "B.Cu")
		(net 6)
	)
	(segment
		(start 92.3 189.5)
		(end 91.6 188.8)
		(width 0.4)
		(layer "B.Cu")
		(net 6)
	)
	(segment
		(start 82.65 161.45)
		(end 89.3 168.1)
		(width 0.4)
		(layer "B.Cu")
		(net 6)
	)
	(segment
		(start 96 192.4)
		(end 97.2 192.4)
		(width 0.4)
		(layer "B.Cu")
		(net 6)
	)
	(segment
		(start 97.196799 192.403201)
		(end 97.193598 192.4)
		(width 0.4)
		(layer "B.Cu")
		(net 6)
	)
	(segment
		(start 91.225 179.775)
		(end 91.6 179.4)
		(width 0.4)
		(layer "B.Cu")
		(net 6)
	)
	(segment
		(start 84.5 150.8)
		(end 84.5 150.4)
		(width 0.4)
		(layer "B.Cu")
		(net 6)
	)
	(segment
		(start 82.65 151.25)
		(end 82.65 161.45)
		(width 0.4)
		(layer "B.Cu")
		(net 6)
	)
	(segment
		(start 83.1 150.8)
		(end 82.65 151.25)
		(width 0.4)
		(layer "B.Cu")
		(net 6)
	)
	(segment
		(start 104.8 170.554499)
		(end 104.775501 170.53)
		(width 0.15)
		(layer "B.Cu")
		(net 6)
	)
	(segment
		(start 84.15 150.75)
		(end 84.5 150.4)
		(width 0.4)
		(layer "B.Cu")
		(net 6)
	)
	(segment
		(start 97.2 192.4)
		(end 97.7 191.9)
		(width 0.4)
		(layer "B.Cu")
		(net 6)
	)
	(segment
		(start 104.95 171.5)
		(end 104.8 171.35)
		(width 0.15)
		(layer "B.Cu")
		(net 6)
	)
	(segment
		(start 89.3 168.1)
		(end 89.3 172.8)
		(width 0.4)
		(layer "B.Cu")
		(net 6)
	)
	(segment
		(start 91.6 188.8)
		(end 91.6 182.4)
		(width 0.4)
		(layer "B.Cu")
		(net 6)
	)
	(segment
		(start 84.5 150.4)
		(end 84.35 150.25)
		(width 0.4)
		(layer "B.Cu")
		(net 6)
	)
	(segment
		(start 104.8 171.35)
		(end 104.8 170.554499)
		(width 0.15)
		(layer "B.Cu")
		(net 6)
	)
	(segment
		(start 103.34 175.716)
		(end 103.34 174.994499)
		(width 0.15)
		(layer "B.Cu")
		(net 6)
	)
	(segment
		(start 91.6 182.4)
		(end 91.225 182.025)
		(width 0.4)
		(layer "B.Cu")
		(net 6)
	)
	(segment
		(start 84.5 150.8)
		(end 84.15 150.8)
		(width 0.4)
		(layer "B.Cu")
		(net 6)
	)
	(segment
		(start 84.15 150.8)
		(end 83.1 150.8)
		(width 0.4)
		(layer "B.Cu")
		(net 6)
	)
	(segment
		(start 84.15 150.8)
		(end 84.15 150.75)
		(width 0.4)
		(layer "B.Cu")
		(net 6)
	)
	(segment
		(start 91.225 182.025)
		(end 91.225 179.775)
		(width 0.4)
		(layer "B.Cu")
		(net 6)
	)
	(segment
		(start 97.7 191.9)
		(end 97.7 191.1)
		(width 0.4)
		(layer "B.Cu")
		(net 6)
	)
	(segment
		(start 103.34 174.994499)
		(end 103.325501 174.98)
		(width 0.15)
		(layer "B.Cu")
		(net 6)
	)
	(segment
		(start 95.2 192.4)
		(end 92.3 189.5)
		(width 0.4)
		(layer "B.Cu")
		(net 6)
	)
	(segment
		(start 96 192.4)
		(end 95.2 192.4)
		(width 0.4)
		(layer "B.Cu")
		(net 6)
	)
	(segment
		(start 89.523501 165.69)
		(end 91.013501 165.69)
		(width 0.15)
		(layer "F.Cu")
		(net 7)
	)
	(segment
		(start 91.898501 168.765)
		(end 91.898501 166.675)
		(width 0.15)
		(layer "F.Cu")
		(net 7)
	)
	(segment
		(start 91.898501 166.675)
		(end 91.048501 165.825)
		(width 0.15)
		(layer "F.Cu")
		(net 7)
	)
	(segment
		(start 92.468501 171.803485)
		(end 92.468501 169.335)
		(width 0.15)
		(layer "F.Cu")
		(net 7)
	)
	(segment
		(start 94.622001 172.636)
		(end 93.301016 172.636)
		(width 0.15)
		(layer "F.Cu")
		(net 7)
	)
	(segment
		(start 93.301016 172.636)
		(end 92.468501 171.803485)
		(width 0.15)
		(layer "F.Cu")
		(net 7)
	)
	(segment
		(start 92.468501 169.335)
		(end 91.898501 168.765)
		(width 0.15)
		(layer "F.Cu")
		(net 7)
	)
	(segment
		(start 104.982344 177.905179)
		(end 104.982344 177.267328)
		(width 0.256)
		(layer "F.Cu")
		(net 8)
	)
	(segment
		(start 95.272344 168.036328)
		(end 95.163672 168.036328)
		(width 0.256)
		(layer "F.Cu")
		(net 8)
	)
	(segment
		(start 95.163672 168.036328)
		(end 93.35 169.85)
		(width 0.256)
		(layer "F.Cu")
		(net 8)
	)
	(segment
		(start 95.959829 168.036328)
		(end 95.272344 168.036328)
		(width 0.4)
		(layer "F.Cu")
		(net 8)
	)
	(segment
		(start 102.496501 176.635)
		(end 103.41 176.635)
		(width 0.256)
		(layer "F.Cu")
		(net 8)
	)
	(segment
		(start 101.675501 168.033)
		(end 100.934016 168.033)
		(width 0.4)
		(layer "F.Cu")
		(net 8)
	)
	(segment
		(start 100.927344 168.427344)
		(end 100.927344 168.026328)
		(width 0.256)
		(layer "F.Cu")
		(net 8)
	)
	(segment
		(start 94.036 171.636)
		(end 94.621501 171.636)
		(width 0.256)
		(layer "F.Cu")
		(net 8)
	)
	(segment
		(start 101.808501 169.308501)
		(end 100.927344 168.427344)
		(width 0.256)
		(layer "F.Cu")
		(net 8)
	)
	(segment
		(start 100.934016 168.033)
		(end 100.927344 168.026328)
		(width 0.4)
		(layer "F.Cu")
		(net 8)
	)
	(segment
		(start 93.35 170.95)
		(end 94.036 171.636)
		(width 0.256)
		(layer "F.Cu")
		(net 8)
	)
	(segment
		(start 93.35 169.85)
		(end 93.35 170.95)
		(width 0.256)
		(layer "F.Cu")
		(net 8)
	)
	(segment
		(start 104.042328 177.267328)
		(end 104.983344 177.267328)
		(width 0.256)
		(layer "F.Cu")
		(net 8)
	)
	(segment
		(start 101.808501 170.448)
		(end 101.808501 169.308501)
		(width 0.256)
		(layer "F.Cu")
		(net 8)
	)
	(segment
		(start 103.41 176.635)
		(end 104.042328 177.267328)
		(width 0.256)
		(layer "F.Cu")
		(net 8)
	)
	(via
		(at 101.675501 168.033)
		(size 0.45)
		(drill 0.1)
		(layers "F.Cu" "B.Cu")
		(net 8)
	)
	(via
		(at 95.959829 168.036328)
		(size 0.45)
		(drill 0.1)
		(layers "F.Cu" "B.Cu")
		(net 8)
	)
	(via
		(at 104.982344 177.905179)
		(size 0.45)
		(drill 0.1)
		(layers "F.Cu" "B.Cu")
		(net 8)
	)
	(segment
		(start 95.959829 168.036328)
		(end 95.959829 168.259829)
		(width 0.4)
		(layer "B.Cu")
		(net 8)
	)
	(segment
		(start 96.45 168.75)
		(end 98.326501 168.75)
		(width 0.4)
		(layer "B.Cu")
		(net 8)
	)
	(segment
		(start 95.959829 168.259829)
		(end 96.45 168.75)
		(width 0.4)
		(layer "B.Cu")
		(net 8)
	)
	(segment
		(start 104 170.357499)
		(end 104 174.53)
		(width 0.4)
		(layer "B.Cu")
		(net 8)
	)
	(segment
		(start 104 174.53)
		(end 104.982344 175.512344)
		(width 0.4)
		(layer "B.Cu")
		(net 8)
	)
	(segment
		(start 101.675501 168.033)
		(end 104 170.357499)
		(width 0.4)
		(layer "B.Cu")
		(net 8)
	)
	(segment
		(start 99.043501 168.033)
		(end 101.675501 168.033)
		(width 0.4)
		(layer "B.Cu")
		(net 8)
	)
	(segment
		(start 104.982344 175.512344)
		(end 104.982344 177.905179)
		(width 0.4)
		(layer "B.Cu")
		(net 8)
	)
	(segment
		(start 98.326501 168.75)
		(end 99.043501 168.033)
		(width 0.4)
		(layer "B.Cu")
		(net 8)
	)
	(segment
		(start 84.9 184.9005)
		(end 85.743001 184.9005)
		(width 0.2)
		(layer "F.Cu")
		(net 9)
	)
	(segment
		(start 85.65 186.026501)
		(end 85.576001 186.1005)
		(width 0.2)
		(layer "F.Cu")
		(net 9)
	)
	(segment
		(start 82.55 185.2)
		(end 84.6005 185.2)
		(width 0.2)
		(layer "F.Cu")
		(net 9)
	)
	(segment
		(start 85.743001 184.9005)
		(end 85.65 184.993501)
		(width 0.2)
		(layer "F.Cu")
		(net 9)
	)
	(segment
		(start 84.6005 185.2)
		(end 84.9 184.9005)
		(width 0.2)
		(layer "F.Cu")
		(net 9)
	)
	(segment
		(start 85.743001 183.056999)
		(end 85.75 183.05)
		(width 0.2)
		(layer "F.Cu")
		(net 9)
	)
	(segment
		(start 85.743001 184.9005)
		(end 85.743001 183.056999)
		(width 0.2)
		(layer "F.Cu")
		(net 9)
	)
	(segment
		(start 85.65 184.993501)
		(end 85.65 186.026501)
		(width 0.2)
		(layer "F.Cu")
		(net 9)
	)
	(segment
		(start 80.9305 186.8195)
		(end 82.55 185.2)
		(width 0.2)
		(layer "F.Cu")
		(net 9)
	)
	(segment
		(start 78.250501 186.8195)
		(end 80.9305 186.8195)
		(width 0.2)
		(layer "F.Cu")
		(net 9)
	)
	(segment
		(start 144.375502 169.302)
		(end 144.875001 168.8025)
		(width 0.256)
		(layer "F.Cu")
		(net 10)
	)
	(segment
		(start 149.375501 164.302001)
		(end 149.875001 163.8025)
		(width 0.256)
		(layer "F.Cu")
		(net 10)
	)
	(segment
		(start 134.376501 168.302)
		(end 133.877001 167.802499)
		(width 0.256)
		(layer "F.Cu")
		(net 10)
	)
	(segment
		(start 136.376501 163.302)
		(end 135.877001 162.8025)
		(width 0.256)
		(layer "F.Cu")
		(net 10)
	)
	(segment
		(start 141.375501 163.302)
		(end 141.875002 162.8025)
		(width 0.256)
		(layer "F.Cu")
		(net 10)
	)
	(segment
		(start 148.375501 169.302)
		(end 148.875001 168.8025)
		(width 0.256)
		(layer "F.Cu")
		(net 10)
	)
	(via
		(at 148.875001 168.8025)
		(size 0.45)
		(drill 0.1)
		(layers "F.Cu" "B.Cu")
		(net 10)
	)
	(via
		(at 144.875001 168.8025)
		(size 0.45)
		(drill 0.1)
		(layers "F.Cu" "B.Cu")
		(net 10)
	)
	(via
		(at 135.877001 162.8025)
		(size 0.45)
		(drill 0.1)
		(layers "F.Cu" "B.Cu")
		(net 10)
	)
	(via
		(at 141.875002 162.8025)
		(size 0.45)
		(drill 0.1)
		(layers "F.Cu" "B.Cu")
		(net 10)
	)
	(via
		(at 149.875001 163.8025)
		(size 0.45)
		(drill 0.1)
		(layers "F.Cu" "B.Cu")
		(net 10)
	)
	(via
		(at 133.877001 167.802499)
		(size 0.45)
		(drill 0.1)
		(layers "F.Cu" "B.Cu")
		(net 10)
	)
	(segment
		(start 141.366 160.7)
		(end 141.366 162.293498)
		(width 0.256)
		(layer "B.Cu")
		(net 10)
	)
	(segment
		(start 140.302001 159.615)
		(end 141.351 159.615)
		(width 0.4)
		(layer "B.Cu")
		(net 10)
	)
	(segment
		(start 141.366 160.7)
		(end 141.366 159.6)
		(width 0.256)
		(layer "B.Cu")
		(net 10)
	)
	(segment
		(start 141.366 162.293498)
		(end 141.875002 162.8025)
		(width 0.256)
		(layer "B.Cu")
		(net 10)
	)
	(segment
		(start 141.351 159.615)
		(end 141.366 159.6)
		(width 0.256)
		(layer "B.Cu")
		(net 10)
	)
	(segment
		(start 115.551 207.651)
		(end 115.725501 207.651)
		(width 0.4)
		(layer "F.Cu")
		(net 11)
	)
	(segment
		(start 115.5 207.6)
		(end 115.551 207.651)
		(width 0.4)
		(layer "F.Cu")
		(net 11)
	)
	(segment
		(start 117.39 205.29)
		(end 117.4 205.3)
		(width 0.4)
		(layer "F.Cu")
		(net 11)
	)
	(segment
		(start 114.525501 210.801)
		(end 114.525501 207.951)
		(width 0.4)
		(layer "F.Cu")
		(net 11)
	)
	(segment
		(start 115.525501 210.801)
		(end 115.525501 207.851)
		(width 0.4)
		(layer "F.Cu")
		(net 11)
	)
	(segment
		(start 115.5 205.15)
		(end 115.5 207.6)
		(width 0.4)
		(layer "F.Cu")
		(net 11)
	)
	(segment
		(start 115.525501 207.851)
		(end 115.725501 207.651)
		(width 0.4)
		(layer "F.Cu")
		(net 11)
	)
	(segment
		(start 114.825501 207.651)
		(end 115.551 207.651)
		(width 0.4)
		(layer "F.Cu")
		(net 11)
	)
	(segment
		(start 115.5 205.15)
		(end 115.64 205.29)
		(width 0.4)
		(layer "F.Cu")
		(net 11)
	)
	(segment
		(start 116.525501 207.651)
		(end 116.525501 210.801)
		(width 0.4)
		(layer "F.Cu")
		(net 11)
	)
	(segment
		(start 114.525501 207.951)
		(end 114.825501 207.651)
		(width 0.4)
		(layer "F.Cu")
		(net 11)
	)
	(segment
		(start 115.64 205.29)
		(end 117.39 205.29)
		(width 0.4)
		(layer "F.Cu")
		(net 11)
	)
	(segment
		(start 115.725501 207.651)
		(end 116.525501 207.651)
		(width 0.4)
		(layer "F.Cu")
		(net 11)
	)
	(via
		(at 116.85 206.15)
		(size 0.45)
		(drill 0.1)
		(layers "F.Cu" "B.Cu")
		(net 11)
	)
	(via
		(at 116.4 206.4)
		(size 0.45)
		(drill 0.1)
		(layers "F.Cu" "B.Cu")
		(net 11)
	)
	(via
		(at 115.2 206.4)
		(size 0.45)
		(drill 0.1)
		(layers "F.Cu" "B.Cu")
		(net 11)
	)
	(via
		(at 115.85 206.25)
		(size 0.45)
		(drill 0.1)
		(layers "F.Cu" "B.Cu")
		(net 11)
	)
	(segment
		(start 116.450501 204.726)
		(end 116.666501 204.942)
		(width 0.201)
		(layer "B.Cu")
		(net 11)
	)
	(segment
		(start 116.666501 204.942)
		(end 116.666501 205.426)
		(width 0.201)
		(layer "B.Cu")
		(net 11)
	)
	(segment
		(start 116.450501 204.176)
		(end 116.450501 204.726)
		(width 0.201)
		(layer "B.Cu")
		(net 11)
	)
	(segment
		(start 116.525501 210.801)
		(end 116.525501 207.801)
		(width 0.4)
		(layer "B.Cu")
		(net 11)
	)
	(segment
		(start 116.525501 207.801)
		(end 115.575501 207.801)
		(width 0.4)
		(layer "B.Cu")
		(net 11)
	)
	(segment
		(start 115.575501 207.801)
		(end 115.525501 207.851)
		(width 0.4)
		(layer "B.Cu")
		(net 11)
	)
	(segment
		(start 115.525501 207.851)
		(end 115.525501 210.801)
		(width 0.4)
		(layer "B.Cu")
		(net 11)
	)
	(segment
		(start 128.66875 205.42775)
		(end 128.5 205.259)
		(width 0.22)
		(layer "B.Cu")
		(net 12)
	)
	(segment
		(start 128.837501 205.83515)
		(end 128.837501 208.019796)
		(width 0.22)
		(layer "B.Cu")
		(net 12)
	)
	(segment
		(start 128.527501 208.768203)
		(end 128.527501 210.8005)
		(width 0.22)
		(layer "B.Cu")
		(net 12)
	)
	(arc
		(start 128.66875 205.42775)
		(mid 128.793644 205.614666)
		(end 128.837501 205.83515)
		(width 0.22)
		(layer "B.Cu")
		(net 12)
	)
	(arc
		(start 128.682501 208.394)
		(mid 128.567784 208.565685)
		(end 128.527501 208.768203)
		(width 0.22)
		(layer "B.Cu")
		(net 12)
	)
	(arc
		(start 128.837501 208.019796)
		(mid 128.797217 208.222313)
		(end 128.682501 208.394)
		(width 0.22)
		(layer "B.Cu")
		(net 12)
	)
	(segment
		(start 146.875 184.8005)
		(end 146.375501 184.301001)
		(width 0.256)
		(layer "F.Cu")
		(net 13)
	)
	(via
		(at 146.875 184.8005)
		(size 0.45)
		(drill 0.1)
		(layers "F.Cu" "B.Cu")
		(net 13)
	)
	(segment
		(start 128.832501 202.316898)
		(end 128.832501 203.723385)
		(width 0.22)
		(layer "B.Cu")
		(net 13)
	)
	(segment
		(start 147.489439 186.577185)
		(end 147.439629 186.527375)
		(width 0.22)
		(layer "B.Cu")
		(net 13)
	)
	(segment
		(start 129.993287 199.514511)
		(end 138.328006 191.179792)
		(width 0.22)
		(layer "B.Cu")
		(net 13)
	)
	(segment
		(start 147.107703 184.8005)
		(end 146.875 184.8005)
		(width 0.1)
		(layer "B.Cu")
		(net 13)
	)
	(segment
		(start 147.275 186.149284)
		(end 147.275 185.526421)
		(width 0.1)
		(layer "B.Cu")
		(net 13)
	)
	(segment
		(start 147.348179 186.306521)
		(end 147.334439 186.292781)
		(width 0.1)
		(layer "B.Cu")
		(net 13)
	)
	(segment
		(start 147.17929 185.20071)
		(end 147.245711 185.134289)
		(width 0.1)
		(layer "B.Cu")
		(net 13)
	)
	(segment
		(start 147.001972 188.904826)
		(end 146.9529 188.953899)
		(width 0.22)
		(layer "B.Cu")
		(net 13)
	)
	(segment
		(start 147.275 185.063579)
		(end 147.275 184.967796)
		(width 0.1)
		(layer "B.Cu")
		(net 13)
	)
	(segment
		(start 147.585001 187.497273)
		(end 147.585001 186.807892)
		(width 0.22)
		(layer "B.Cu")
		(net 13)
	)
	(segment
		(start 147.15 185.318579)
		(end 147.15 185.271421)
		(width 0.1)
		(layer "B.Cu")
		(net 13)
	)
	(segment
		(start 145.426874 189.586)
		(end 142.175762 189.586)
		(width 0.22)
		(layer "B.Cu")
		(net 13)
	)
	(segment
		(start 147.24571 185.45571)
		(end 147.179289 185.389289)
		(width 0.1)
		(layer "B.Cu")
		(net 13)
	)
	(segment
		(start 128.66625 204.124749)
		(end 128.5 204.291)
		(width 0.22)
		(layer "B.Cu")
		(net 13)
	)
	(arc
		(start 147.275 184.967796)
		(mid 147.262265 184.903774)
		(end 147.226 184.8495)
		(width 0.1)
		(layer "B.Cu")
		(net 13)
	)
	(arc
		(start 147.439629 186.527375)
		(mid 147.415861 186.407815)
		(end 147.348179 186.306521)
		(width 0.1)
		(layer "B.Cu")
		(net 13)
	)
	(arc
		(start 129.993287 199.514511)
		(mid 129.134179 200.800257)
		(end 128.832501 202.316898)
		(width 0.22)
		(layer "B.Cu")
		(net 13)
	)
	(arc
		(start 147.334439 186.292781)
		(mid 147.290448 186.226944)
		(end 147.275 186.149284)
		(width 0.1)
		(layer "B.Cu")
		(net 13)
	)
	(arc
		(start 146.9529 188.953899)
		(mid 146.252753 189.421722)
		(end 145.426874 189.586)
		(width 0.22)
		(layer "B.Cu")
		(net 13)
	)
	(arc
		(start 147.15 185.318579)
		(mid 147.157612 185.356847)
		(end 147.179289 185.389289)
		(width 0.1)
		(layer "B.Cu")
		(net 13)
	)
	(arc
		(start 142.175762 189.586)
		(mid 140.093371 190.000213)
		(end 138.328006 191.179792)
		(width 0.22)
		(layer "B.Cu")
		(net 13)
	)
	(arc
		(start 147.489439 186.577185)
		(mid 147.560165 186.683034)
		(end 147.585001 186.807892)
		(width 0.22)
		(layer "B.Cu")
		(net 13)
	)
	(arc
		(start 147.226 184.8495)
		(mid 147.171724 184.813234)
		(end 147.107703 184.8005)
		(width 0.1)
		(layer "B.Cu")
		(net 13)
	)
	(arc
		(start 147.15 185.271421)
		(mid 147.157612 185.233152)
		(end 147.17929 185.20071)
		(width 0.1)
		(layer "B.Cu")
		(net 13)
	)
	(arc
		(start 128.832501 203.723385)
		(mid 128.789293 203.940601)
		(end 128.66625 204.124749)
		(width 0.22)
		(layer "B.Cu")
		(net 13)
	)
	(arc
		(start 147.275 185.063579)
		(mid 147.267388 185.101847)
		(end 147.245711 185.134289)
		(width 0.1)
		(layer "B.Cu")
		(net 13)
	)
	(arc
		(start 147.585001 187.497273)
		(mid 147.433476 188.259035)
		(end 147.001972 188.904826)
		(width 0.22)
		(layer "B.Cu")
		(net 13)
	)
	(arc
		(start 147.24571 185.45571)
		(mid 147.267388 185.488152)
		(end 147.275 185.526421)
		(width 0.1)
		(layer "B.Cu")
		(net 13)
	)
	(segment
		(start 129.38375 205.425249)
		(end 129.55 205.259)
		(width 0.22)
		(layer "B.Cu")
		(net 14)
	)
	(segment
		(start 129.217501 208.023796)
		(end 129.217501 205.826611)
		(width 0.22)
		(layer "B.Cu")
		(net 14)
	)
	(segment
		(start 129.527501 208.772203)
		(end 129.527501 210.8005)
		(width 0.22)
		(layer "B.Cu")
		(net 14)
	)
	(arc
		(start 129.38375 205.425249)
		(mid 129.260707 205.609395)
		(end 129.217501 205.826611)
		(width 0.22)
		(layer "B.Cu")
		(net 14)
	)
	(arc
		(start 129.217501 208.023796)
		(mid 129.257784 208.226313)
		(end 129.372501 208.398)
		(width 0.22)
		(layer "B.Cu")
		(net 14)
	)
	(arc
		(start 129.372501 208.398)
		(mid 129.487217 208.569685)
		(end 129.527501 208.772203)
		(width 0.22)
		(layer "B.Cu")
		(net 14)
	)
	(segment
		(start 147.875001 184.8005)
		(end 147.375501 184.301001)
		(width 0.256)
		(layer "F.Cu")
		(net 15)
	)
	(via
		(at 147.875001 184.8005)
		(size 0.45)
		(drill 0.1)
		(layers "F.Cu" "B.Cu")
		(net 15)
	)
	(segment
		(start 147.270671 189.173531)
		(end 147.221602 189.222601)
		(width 0.22)
		(layer "B.Cu")
		(net 15)
	)
	(segment
		(start 147.475001 184.974623)
		(end 147.475001 186.066653)
		(width 0.1)
		(layer "B.Cu")
		(net 15)
	)
	(segment
		(start 129.38125 204.12225)
		(end 129.55 204.291)
		(width 0.22)
		(layer "B.Cu")
		(net 15)
	)
	(segment
		(start 147.965001 187.497273)
		(end 147.965001 186.7309)
		(width 0.22)
		(layer "B.Cu")
		(net 15)
	)
	(segment
		(start 147.875001 184.8005)
		(end 147.649124 184.8005)
		(width 0.1)
		(layer "B.Cu")
		(net 15)
	)
	(segment
		(start 147.504291 186.137364)
		(end 147.563152 186.196225)
		(width 0.1)
		(layer "B.Cu")
		(net 15)
	)
	(segment
		(start 145.426879 189.966)
		(end 142.215465 189.966)
		(width 0.22)
		(layer "B.Cu")
		(net 15)
	)
	(segment
		(start 129.212501 202.38543)
		(end 129.212501 203.714853)
		(width 0.22)
		(layer "B.Cu")
		(net 15)
	)
	(segment
		(start 130.310446 199.734756)
		(end 138.568636 191.476566)
		(width 0.22)
		(layer "B.Cu")
		(net 15)
	)
	(segment
		(start 147.812579 186.362922)
		(end 147.704407 186.25475)
		(width 0.22)
		(layer "B.Cu")
		(net 15)
	)
	(arc
		(start 147.475001 186.066653)
		(mid 147.482613 186.104922)
		(end 147.504291 186.137364)
		(width 0.1)
		(layer "B.Cu")
		(net 15)
	)
	(arc
		(start 129.212501 203.714853)
		(mid 129.256357 203.935334)
		(end 129.38125 204.12225)
		(width 0.22)
		(layer "B.Cu")
		(net 15)
	)
	(arc
		(start 147.812579 186.362922)
		(mid 147.925387 186.531751)
		(end 147.965001 186.7309)
		(width 0.22)
		(layer "B.Cu")
		(net 15)
	)
	(arc
		(start 142.215465 189.966)
		(mid 140.241815 190.358583)
		(end 138.568636 191.476566)
		(width 0.22)
		(layer "B.Cu")
		(net 15)
	)
	(arc
		(start 147.704407 186.25475)
		(mid 147.627977 186.23954)
		(end 147.563152 186.196225)
		(width 0.1)
		(layer "B.Cu")
		(net 15)
	)
	(arc
		(start 147.965001 187.497273)
		(mid 147.78455 188.404457)
		(end 147.270671 189.173531)
		(width 0.22)
		(layer "B.Cu")
		(net 15)
	)
	(arc
		(start 130.310446 199.734756)
		(mid 129.497848 200.950896)
		(end 129.212501 202.38543)
		(width 0.22)
		(layer "B.Cu")
		(net 15)
	)
	(arc
		(start 147.526 184.851499)
		(mid 147.488255 184.907988)
		(end 147.475001 184.974623)
		(width 0.1)
		(layer "B.Cu")
		(net 15)
	)
	(arc
		(start 147.649124 184.8005)
		(mid 147.582489 184.813754)
		(end 147.526 184.851499)
		(width 0.1)
		(layer "B.Cu")
		(net 15)
	)
	(arc
		(start 147.221602 189.222601)
		(mid 146.398176 189.772796)
		(end 145.426879 189.966)
		(width 0.22)
		(layer "B.Cu")
		(net 15)
	)
	(segment
		(start 144.66675 205.42825)
		(end 144.498 205.2595)
		(width 0.22)
		(layer "B.Cu")
		(net 16)
	)
	(segment
		(start 144.835501 205.83565)
		(end 144.835501 208.020296)
		(width 0.22)
		(layer "B.Cu")
		(net 16)
	)
	(segment
		(start 144.525501 208.768703)
		(end 144.525501 210.801)
		(width 0.22)
		(layer "B.Cu")
		(net 16)
	)
	(arc
		(start 144.835501 208.020296)
		(mid 144.795217 208.222813)
		(end 144.680501 208.3945)
		(width 0.22)
		(layer "B.Cu")
		(net 16)
	)
	(arc
		(start 144.680501 208.3945)
		(mid 144.565784 208.566185)
		(end 144.525501 208.768703)
		(width 0.22)
		(layer "B.Cu")
		(net 16)
	)
	(arc
		(start 144.66675 205.42825)
		(mid 144.791644 205.615166)
		(end 144.835501 205.83565)
		(width 0.22)
		(layer "B.Cu")
		(net 16)
	)
	(segment
		(start 150.875001 182.800501)
		(end 150.375501 182.301)
		(width 0.256)
		(layer "F.Cu")
		(net 17)
	)
	(via
		(at 150.875001 182.800501)
		(size 0.45)
		(drill 0.1)
		(layers "F.Cu" "B.Cu")
		(net 17)
	)
	(segment
		(start 155.492335 184.240501)
		(end 152.228551 184.240501)
		(width 0.22)
		(layer "B.Cu")
		(net 17)
	)
	(segment
		(start 161.685001 192.679178)
		(end 161.685001 190.433166)
		(width 0.22)
		(layer "B.Cu")
		(net 17)
	)
	(segment
		(start 145.696474 200.710324)
		(end 147.202506 199.204293)
		(width 0.22)
		(layer "B.Cu")
		(net 17)
	)
	(segment
		(start 156.753678 197.610501)
		(end 151.050262 197.610501)
		(width 0.22)
		(layer "B.Cu")
		(net 17)
	)
	(segment
		(start 144.835501 203.787297)
		(end 144.835501 202.7889)
		(width 0.22)
		(layer "B.Cu")
		(net 17)
	)
	(segment
		(start 144.680501 204.161501)
		(end 144.525501 204.316501)
		(width 0.22)
		(layer "B.Cu")
		(net 17)
	)
	(segment
		(start 150.875001 182.800501)
		(end 151.030001 182.955501)
		(width 0.22)
		(layer "B.Cu")
		(net 17)
	)
	(segment
		(start 151.185001 183.369852)
		(end 151.185001 183.329704)
		(width 0.22)
		(layer "B.Cu")
		(net 17)
	)
	(segment
		(start 151.368389 183.812591)
		(end 151.49065 183.934852)
		(width 0.22)
		(layer "B.Cu")
		(net 17)
	)
	(segment
		(start 159.340091 185.834293)
		(end 160.091208 186.58541)
		(width 0.22)
		(layer "B.Cu")
		(net 17)
	)
	(arc
		(start 151.49065 183.934852)
		(mid 151.829202 184.161065)
		(end 152.228551 184.240501)
		(width 0.22)
		(layer "B.Cu")
		(net 17)
	)
	(arc
		(start 161.685001 192.679178)
		(mid 161.309626 194.566313)
		(end 160.24065 196.16615)
		(width 0.22)
		(layer "B.Cu")
		(net 17)
	)
	(arc
		(start 151.030001 182.955501)
		(mid 151.144717 183.127186)
		(end 151.185001 183.329704)
		(width 0.22)
		(layer "B.Cu")
		(net 17)
	)
	(arc
		(start 151.050262 197.610501)
		(mid 148.967871 198.024714)
		(end 147.202506 199.204293)
		(width 0.22)
		(layer "B.Cu")
		(net 17)
	)
	(arc
		(start 159.340091 185.834293)
		(mid 157.574725 184.654714)
		(end 155.492335 184.240501)
		(width 0.22)
		(layer "B.Cu")
		(net 17)
	)
	(arc
		(start 144.835501 203.787297)
		(mid 144.795217 203.989814)
		(end 144.680501 204.161501)
		(width 0.22)
		(layer "B.Cu")
		(net 17)
	)
	(arc
		(start 151.185001 183.369852)
		(mid 151.232661 183.60946)
		(end 151.368389 183.812591)
		(width 0.22)
		(layer "B.Cu")
		(net 17)
	)
	(arc
		(start 160.091208 186.58541)
		(mid 161.270787 188.350775)
		(end 161.685001 190.433166)
		(width 0.22)
		(layer "B.Cu")
		(net 17)
	)
	(arc
		(start 145.696474 200.710324)
		(mid 145.05926 201.663983)
		(end 144.835501 202.7889)
		(width 0.22)
		(layer "B.Cu")
		(net 17)
	)
	(arc
		(start 160.24065 196.16615)
		(mid 158.640813 197.235126)
		(end 156.753678 197.610501)
		(width 0.22)
		(layer "B.Cu")
		(net 17)
	)
	(segment
		(start 140.835501 205.83565)
		(end 140.835501 208.020296)
		(width 0.22)
		(layer "B.Cu")
		(net 18)
	)
	(segment
		(start 140.66675 205.42825)
		(end 140.498 205.2595)
		(width 0.22)
		(layer "B.Cu")
		(net 18)
	)
	(segment
		(start 140.525501 208.768703)
		(end 140.525501 210.801)
		(width 0.22)
		(layer "B.Cu")
		(net 18)
	)
	(arc
		(start 140.680501 208.3945)
		(mid 140.565784 208.566185)
		(end 140.525501 208.768703)
		(width 0.22)
		(layer "B.Cu")
		(net 18)
	)
	(arc
		(start 140.835501 208.020296)
		(mid 140.795217 208.222813)
		(end 140.680501 208.3945)
		(width 0.22)
		(layer "B.Cu")
		(net 18)
	)
	(arc
		(start 140.66675 205.42825)
		(mid 140.791644 205.615166)
		(end 140.835501 205.83565)
		(width 0.22)
		(layer "B.Cu")
		(net 18)
	)
	(segment
		(start 150.875001 184.800501)
		(end 150.375501 184.301)
		(width 0.256)
		(layer "F.Cu")
		(net 19)
	)
	(via
		(at 150.875001 184.800501)
		(size 0.45)
		(drill 0.1)
		(layers "F.Cu" "B.Cu")
		(net 19)
	)
	(segment
		(start 151.49065 185.934852)
		(end 151.368389 185.812591)
		(width 0.22)
		(layer "B.Cu")
		(net 19)
	)
	(segment
		(start 151.185001 185.369852)
		(end 151.185001 185.329704)
		(width 0.22)
		(layer "B.Cu")
		(net 19)
	)
	(segment
		(start 158.397148 188.79135)
		(end 157.27819 187.672392)
		(width 0.22)
		(layer "B.Cu")
		(net 19)
	)
	(segment
		(start 140.680501 204.211501)
		(end 140.525501 204.366501)
		(width 0.22)
		(layer "B.Cu")
		(net 19)
	)
	(segment
		(start 149.050262 195.610501)
		(end 156.460785 195.610501)
		(width 0.22)
		(layer "B.Cu")
		(net 19)
	)
	(segment
		(start 140.835501 202.8139)
		(end 140.835501 203.837297)
		(width 0.22)
		(layer "B.Cu")
		(net 19)
	)
	(segment
		(start 145.202506 197.204293)
		(end 141.714152 200.692647)
		(width 0.22)
		(layer "B.Cu")
		(net 19)
	)
	(segment
		(start 159.685001 191.900501)
		(end 159.685001 192.386285)
		(width 0.22)
		(layer "B.Cu")
		(net 19)
	)
	(segment
		(start 152.228551 186.240501)
		(end 153.821299 186.240501)
		(width 0.22)
		(layer "B.Cu")
		(net 19)
	)
	(segment
		(start 150.875001 184.800501)
		(end 151.030001 184.955501)
		(width 0.22)
		(layer "B.Cu")
		(net 19)
	)
	(arc
		(start 149.050262 195.610501)
		(mid 146.967871 196.024714)
		(end 145.202506 197.204293)
		(width 0.22)
		(layer "B.Cu")
		(net 19)
	)
	(arc
		(start 159.685001 192.386285)
		(mid 159.439572 193.620139)
		(end 158.74065 194.66615)
		(width 0.22)
		(layer "B.Cu")
		(net 19)
	)
	(arc
		(start 151.030001 184.955501)
		(mid 151.144717 185.127186)
		(end 151.185001 185.329704)
		(width 0.22)
		(layer "B.Cu")
		(net 19)
	)
	(arc
		(start 151.49065 185.934852)
		(mid 151.829202 186.161065)
		(end 152.228551 186.240501)
		(width 0.22)
		(layer "B.Cu")
		(net 19)
	)
	(arc
		(start 140.835501 203.837297)
		(mid 140.795217 204.039814)
		(end 140.680501 204.211501)
		(width 0.22)
		(layer "B.Cu")
		(net 19)
	)
	(arc
		(start 141.714152 200.692647)
		(mid 141.063854 201.665886)
		(end 140.835501 202.8139)
		(width 0.22)
		(layer "B.Cu")
		(net 19)
	)
	(arc
		(start 151.185001 185.369852)
		(mid 151.232661 185.60946)
		(end 151.368389 185.812591)
		(width 0.22)
		(layer "B.Cu")
		(net 19)
	)
	(arc
		(start 158.74065 194.66615)
		(mid 157.694639 195.365072)
		(end 156.460785 195.610501)
		(width 0.22)
		(layer "B.Cu")
		(net 19)
	)
	(arc
		(start 157.27819 187.672392)
		(mid 155.692154 186.612637)
		(end 153.821299 186.240501)
		(width 0.22)
		(layer "B.Cu")
		(net 19)
	)
	(arc
		(start 158.397148 188.79135)
		(mid 159.350298 190.21784)
		(end 159.685001 191.900501)
		(width 0.22)
		(layer "B.Cu")
		(net 19)
	)
	(segment
		(start 136.835501 205.83565)
		(end 136.835501 208.020296)
		(width 0.22)
		(layer "B.Cu")
		(net 20)
	)
	(segment
		(start 136.66675 205.42825)
		(end 136.498 205.2595)
		(width 0.22)
		(layer "B.Cu")
		(net 20)
	)
	(segment
		(start 136.525501 208.768703)
		(end 136.525501 210.801)
		(width 0.22)
		(layer "B.Cu")
		(net 20)
	)
	(arc
		(start 136.835501 208.020296)
		(mid 136.795217 208.222813)
		(end 136.680501 208.3945)
		(width 0.22)
		(layer "B.Cu")
		(net 20)
	)
	(arc
		(start 136.66675 205.42825)
		(mid 136.791644 205.615166)
		(end 136.835501 205.83565)
		(width 0.22)
		(layer "B.Cu")
		(net 20)
	)
	(arc
		(start 136.680501 208.3945)
		(mid 136.565784 208.566185)
		(end 136.525501 208.768703)
		(width 0.22)
		(layer "B.Cu")
		(net 20)
	)
	(segment
		(start 150.875001 186.800501)
		(end 150.375501 186.301)
		(width 0.256)
		(layer "F.Cu")
		(net 21)
	)
	(via
		(at 150.875001 186.800501)
		(size 0.45)
		(drill 0.1)
		(layers "F.Cu" "B.Cu")
		(net 21)
	)
	(segment
		(start 151.246671 190.960128)
		(end 149.939801 192.266998)
		(width 0.22)
		(layer "B.Cu")
		(net 21)
	)
	(segment
		(start 136.835501 203.837297)
		(end 136.835501 202.879149)
		(width 0.22)
		(layer "B.Cu")
		(net 21)
	)
	(segment
		(start 150.875001 186.800501)
		(end 151.063483 186.988983)
		(width 0.22)
		(layer "B.Cu")
		(net 21)
	)
	(segment
		(start 151.96 189.238001)
		(end 151.96 188.687594)
		(width 0.22)
		(layer "B.Cu")
		(net 21)
	)
	(segment
		(start 137.760291 200.646508)
		(end 143.452796 194.954003)
		(width 0.22)
		(layer "B.Cu")
		(net 21)
	)
	(segment
		(start 136.680501 204.211501)
		(end 136.525501 204.366501)
		(width 0.22)
		(layer "B.Cu")
		(net 21)
	)
	(segment
		(start 151.635867 187.905069)
		(end 151.306474 187.575676)
		(width 0.22)
		(layer "B.Cu")
		(net 21)
	)
	(arc
		(start 151.635867 187.905069)
		(mid 151.87576 188.264095)
		(end 151.96 188.687594)
		(width 0.22)
		(layer "B.Cu")
		(net 21)
	)
	(arc
		(start 149.939801 192.266998)
		(mid 148.451669 193.261335)
		(end 146.696299 193.610501)
		(width 0.22)
		(layer "B.Cu")
		(net 21)
	)
	(arc
		(start 136.835501 203.837297)
		(mid 136.795217 204.039814)
		(end 136.680501 204.211501)
		(width 0.22)
		(layer "B.Cu")
		(net 21)
	)
	(arc
		(start 151.063483 186.988983)
		(mid 151.153419 187.123582)
		(end 151.185001 187.282352)
		(width 0.22)
		(layer "B.Cu")
		(net 21)
	)
	(arc
		(start 146.696299 193.610501)
		(mid 144.940927 193.959665)
		(end 143.452796 194.954003)
		(width 0.22)
		(layer "B.Cu")
		(net 21)
	)
	(arc
		(start 151.185001 187.282352)
		(mid 151.216562 187.441105)
		(end 151.306474 187.575676)
		(width 0.22)
		(layer "B.Cu")
		(net 21)
	)
	(arc
		(start 137.760291 200.646508)
		(mid 137.075846 201.670852)
		(end 136.835501 202.879149)
		(width 0.22)
		(layer "B.Cu")
		(net 21)
	)
	(arc
		(start 151.96 189.238001)
		(mid 151.774611 190.170009)
		(end 151.246671 190.960128)
		(width 0.22)
		(layer "B.Cu")
		(net 21)
	)
	(segment
		(start 131.835501 205.83565)
		(end 131.835501 208.020296)
		(width 0.22)
		(layer "B.Cu")
		(net 22)
	)
	(segment
		(start 131.525501 208.768703)
		(end 131.525501 210.801)
		(width 0.22)
		(layer "B.Cu")
		(net 22)
	)
	(segment
		(start 131.66675 205.42825)
		(end 131.498 205.2595)
		(width 0.22)
		(layer "B.Cu")
		(net 22)
	)
	(arc
		(start 131.680501 208.3945)
		(mid 131.565784 208.566185)
		(end 131.525501 208.768703)
		(width 0.22)
		(layer "B.Cu")
		(net 22)
	)
	(arc
		(start 131.835501 208.020296)
		(mid 131.795217 208.222813)
		(end 131.680501 208.3945)
		(width 0.22)
		(layer "B.Cu")
		(net 22)
	)
	(arc
		(start 131.66675 205.42825)
		(mid 131.791644 205.615166)
		(end 131.835501 205.83565)
		(width 0.22)
		(layer "B.Cu")
		(net 22)
	)
	(segment
		(start 148.875001 187.800501)
		(end 148.375501 187.301)
		(width 0.256)
		(layer "F.Cu")
		(net 23)
	)
	(via
		(at 148.875001 187.800501)
		(size 0.45)
		(drill 0.1)
		(layers "F.Cu" "B.Cu")
		(net 23)
	)
	(segment
		(start 149.030001 187.955501)
		(end 148.875001 187.800501)
		(width 0.22)
		(layer "B.Cu")
		(net 23)
	)
	(segment
		(start 131.835501 203.837297)
		(end 131.835501 203.3139)
		(width 0.22)
		(layer "B.Cu")
		(net 23)
	)
	(segment
		(start 144.896299 191.610501)
		(end 145.448652 191.610501)
		(width 0.22)
		(layer "B.Cu")
		(net 23)
	)
	(segment
		(start 149.185001 188.329704)
		(end 149.185001 188.76615)
		(width 0.22)
		(layer "B.Cu")
		(net 23)
	)
	(segment
		(start 148.721387 189.885412)
		(end 148.09065 190.51615)
		(width 0.22)
		(layer "B.Cu")
		(net 23)
	)
	(segment
		(start 141.311374 193.095425)
		(end 132.360599 202.0462)
		(width 0.22)
		(layer "B.Cu")
		(net 23)
	)
	(segment
		(start 131.680501 204.211501)
		(end 131.525501 204.366501)
		(width 0.22)
		(layer "B.Cu")
		(net 23)
	)
	(arc
		(start 148.09065 190.51615)
		(mid 146.878491 191.326088)
		(end 145.448652 191.610501)
		(width 0.22)
		(layer "B.Cu")
		(net 23)
	)
	(arc
		(start 144.896299 191.610501)
		(mid 142.956151 191.99642)
		(end 141.311374 193.095425)
		(width 0.22)
		(layer "B.Cu")
		(net 23)
	)
	(arc
		(start 149.030001 187.955501)
		(mid 149.144717 188.127186)
		(end 149.185001 188.329704)
		(width 0.22)
		(layer "B.Cu")
		(net 23)
	)
	(arc
		(start 149.185001 188.76615)
		(mid 149.064511 189.37189)
		(end 148.721387 189.885412)
		(width 0.22)
		(layer "B.Cu")
		(net 23)
	)
	(arc
		(start 131.835501 203.837297)
		(mid 131.795217 204.039814)
		(end 131.680501 204.211501)
		(width 0.22)
		(layer "B.Cu")
		(net 23)
	)
	(arc
		(start 132.360599 202.0462)
		(mid 131.971969 202.627825)
		(end 131.835501 203.3139)
		(width 0.22)
		(layer "B.Cu")
		(net 23)
	)
	(segment
		(start 145.215501 208.024296)
		(end 145.215501 205.827111)
		(width 0.22)
		(layer "B.Cu")
		(net 24)
	)
	(segment
		(start 145.525501 208.772703)
		(end 145.525501 210.801)
		(width 0.22)
		(layer "B.Cu")
		(net 24)
	)
	(segment
		(start 145.38175 205.425749)
		(end 145.548 205.2595)
		(width 0.22)
		(layer "B.Cu")
		(net 24)
	)
	(arc
		(start 145.215501 208.024296)
		(mid 145.255784 208.226813)
		(end 145.370501 208.3985)
		(width 0.22)
		(layer "B.Cu")
		(net 24)
	)
	(arc
		(start 145.38175 205.425749)
		(mid 145.258707 205.609895)
		(end 145.215501 205.827111)
		(width 0.22)
		(layer "B.Cu")
		(net 24)
	)
	(arc
		(start 145.370501 208.3985)
		(mid 145.485217 208.570185)
		(end 145.525501 208.772703)
		(width 0.22)
		(layer "B.Cu")
		(net 24)
	)
	(segment
		(start 151.875001 182.800501)
		(end 151.375501 182.301)
		(width 0.256)
		(layer "F.Cu")
		(net 25)
	)
	(via
		(at 151.875001 182.800501)
		(size 0.45)
		(drill 0.1)
		(layers "F.Cu" "B.Cu")
		(net 25)
	)
	(segment
		(start 145.370501 204.161501)
		(end 145.525501 204.316501)
		(width 0.22)
		(layer "B.Cu")
		(net 25)
	)
	(segment
		(start 151.207666 197.990501)
		(end 156.753683 197.990501)
		(width 0.22)
		(layer "B.Cu")
		(net 25)
	)
	(segment
		(start 155.649739 183.860501)
		(end 152.228556 183.860501)
		(width 0.22)
		(layer "B.Cu")
		(net 25)
	)
	(segment
		(start 151.875001 182.800501)
		(end 151.692739 182.982762)
		(width 0.22)
		(layer "B.Cu")
		(net 25)
	)
	(segment
		(start 145.215501 203.787297)
		(end 145.215501 202.867602)
		(width 0.22)
		(layer "B.Cu")
		(net 25)
	)
	(segment
		(start 147.359909 199.584293)
		(end 146.020824 200.923379)
		(width 0.22)
		(layer "B.Cu")
		(net 25)
	)
	(segment
		(start 162.065001 192.679183)
		(end 162.065001 190.275762)
		(width 0.22)
		(layer "B.Cu")
		(net 25)
	)
	(segment
		(start 151.565001 183.29115)
		(end 151.565006 183.337845)
		(width 0.22)
		(layer "B.Cu")
		(net 25)
	)
	(segment
		(start 159.497495 185.454293)
		(end 160.471208 186.428006)
		(width 0.22)
		(layer "B.Cu")
		(net 25)
	)
	(segment
		(start 151.659755 183.566553)
		(end 151.759352 183.66615)
		(width 0.22)
		(layer "B.Cu")
		(net 25)
	)
	(arc
		(start 160.509352 196.434852)
		(mid 158.786236 197.5862)
		(end 156.753683 197.990501)
		(width 0.22)
		(layer "B.Cu")
		(net 25)
	)
	(arc
		(start 151.207666 197.990501)
		(mid 149.125275 198.404714)
		(end 147.359909 199.584293)
		(width 0.22)
		(layer "B.Cu")
		(net 25)
	)
	(arc
		(start 160.471208 186.428006)
		(mid 161.650787 188.193371)
		(end 162.065001 190.275762)
		(width 0.22)
		(layer "B.Cu")
		(net 25)
	)
	(arc
		(start 151.759352 183.66615)
		(mid 151.974624 183.80999)
		(end 152.228556 183.860501)
		(width 0.22)
		(layer "B.Cu")
		(net 25)
	)
	(arc
		(start 159.497495 185.454293)
		(mid 157.732129 184.274714)
		(end 155.649739 183.860501)
		(width 0.22)
		(layer "B.Cu")
		(net 25)
	)
	(arc
		(start 145.215501 203.787297)
		(mid 145.255784 203.989814)
		(end 145.370501 204.161501)
		(width 0.22)
		(layer "B.Cu")
		(net 25)
	)
	(arc
		(start 162.065001 192.679183)
		(mid 161.6607 194.711736)
		(end 160.509352 196.434852)
		(width 0.22)
		(layer "B.Cu")
		(net 25)
	)
	(arc
		(start 151.565006 183.337845)
		(mid 151.589638 183.461621)
		(end 151.659755 183.566553)
		(width 0.22)
		(layer "B.Cu")
		(net 25)
	)
	(arc
		(start 146.020824 200.923379)
		(mid 145.424797 201.815396)
		(end 145.215501 202.867602)
		(width 0.22)
		(layer "B.Cu")
		(net 25)
	)
	(arc
		(start 151.692739 182.982762)
		(mid 151.598199 183.124251)
		(end 151.565001 183.29115)
		(width 0.22)
		(layer "B.Cu")
		(net 25)
	)
	(segment
		(start 141.525501 208.772703)
		(end 141.525501 210.801)
		(width 0.22)
		(layer "B.Cu")
		(net 26)
	)
	(segment
		(start 141.215501 208.024296)
		(end 141.215501 205.827111)
		(width 0.22)
		(layer "B.Cu")
		(net 26)
	)
	(segment
		(start 141.38175 205.425749)
		(end 141.548 205.2595)
		(width 0.22)
		(layer "B.Cu")
		(net 26)
	)
	(arc
		(start 141.215501 208.024296)
		(mid 141.255784 208.226813)
		(end 141.370501 208.3985)
		(width 0.22)
		(layer "B.Cu")
		(net 26)
	)
	(arc
		(start 141.38175 205.425749)
		(mid 141.258707 205.609895)
		(end 141.215501 205.827111)
		(width 0.22)
		(layer "B.Cu")
		(net 26)
	)
	(arc
		(start 141.370501 208.3985)
		(mid 141.485217 208.570185)
		(end 141.525501 208.772703)
		(width 0.22)
		(layer "B.Cu")
		(net 26)
	)
	(segment
		(start 151.875001 184.800501)
		(end 151.375501 184.301)
		(width 0.256)
		(layer "F.Cu")
		(net 27)
	)
	(via
		(at 151.875001 184.800501)
		(size 0.45)
		(drill 0.1)
		(layers "F.Cu" "B.Cu")
		(net 27)
	)
	(segment
		(start 160.065001 191.900501)
		(end 160.065001 192.386289)
		(width 0.22)
		(layer "B.Cu")
		(net 27)
	)
	(segment
		(start 152.228556 185.860501)
		(end 153.978703 185.860501)
		(width 0.22)
		(layer "B.Cu")
		(net 27)
	)
	(segment
		(start 141.215501 202.892602)
		(end 141.215501 203.837297)
		(width 0.22)
		(layer "B.Cu")
		(net 27)
	)
	(segment
		(start 151.875001 184.800501)
		(end 151.692739 184.982762)
		(width 0.22)
		(layer "B.Cu")
		(net 27)
	)
	(segment
		(start 145.35991 197.584293)
		(end 142.038501 200.905702)
		(width 0.22)
		(layer "B.Cu")
		(net 27)
	)
	(segment
		(start 156.460789 195.990501)
		(end 149.207666 195.990501)
		(width 0.22)
		(layer "B.Cu")
		(net 27)
	)
	(segment
		(start 141.370501 204.211501)
		(end 141.525501 204.366501)
		(width 0.22)
		(layer "B.Cu")
		(net 27)
	)
	(segment
		(start 157.435594 187.292392)
		(end 158.665847 188.522645)
		(width 0.22)
		(layer "B.Cu")
		(net 27)
	)
	(segment
		(start 151.692739 185.599537)
		(end 151.759352 185.66615)
		(width 0.22)
		(layer "B.Cu")
		(net 27)
	)
	(arc
		(start 158.665847 188.522645)
		(mid 159.701372 190.072418)
		(end 160.065001 191.900501)
		(width 0.22)
		(layer "B.Cu")
		(net 27)
	)
	(arc
		(start 141.215501 203.837297)
		(mid 141.255784 204.039814)
		(end 141.370501 204.211501)
		(width 0.22)
		(layer "B.Cu")
		(net 27)
	)
	(arc
		(start 151.692739 184.982762)
		(mid 151.598199 185.124251)
		(end 151.565001 185.29115)
		(width 0.22)
		(layer "B.Cu")
		(net 27)
	)
	(arc
		(start 151.565001 185.29115)
		(mid 151.598199 185.458047)
		(end 151.692739 185.599537)
		(width 0.22)
		(layer "B.Cu")
		(net 27)
	)
	(arc
		(start 160.065001 192.386289)
		(mid 159.790646 193.765561)
		(end 159.009352 194.934852)
		(width 0.22)
		(layer "B.Cu")
		(net 27)
	)
	(arc
		(start 149.207666 195.990501)
		(mid 147.125275 196.404714)
		(end 145.35991 197.584293)
		(width 0.22)
		(layer "B.Cu")
		(net 27)
	)
	(arc
		(start 159.009352 194.934852)
		(mid 157.840061 195.716146)
		(end 156.460789 195.990501)
		(width 0.22)
		(layer "B.Cu")
		(net 27)
	)
	(arc
		(start 142.038501 200.905702)
		(mid 141.429391 201.817299)
		(end 141.215501 202.892602)
		(width 0.22)
		(layer "B.Cu")
		(net 27)
	)
	(arc
		(start 153.978703 185.860501)
		(mid 155.849558 186.232637)
		(end 157.435594 187.292392)
		(width 0.22)
		(layer "B.Cu")
		(net 27)
	)
	(arc
		(start 151.759352 185.66615)
		(mid 151.974624 185.80999)
		(end 152.228556 185.860501)
		(width 0.22)
		(layer "B.Cu")
		(net 27)
	)
	(segment
		(start 132.38175 205.425749)
		(end 132.548 205.2595)
		(width 0.22)
		(layer "B.Cu")
		(net 28)
	)
	(segment
		(start 132.215501 208.024296)
		(end 132.215501 205.827111)
		(width 0.22)
		(layer "B.Cu")
		(net 28)
	)
	(segment
		(start 132.525501 208.772703)
		(end 132.525501 210.801)
		(width 0.22)
		(layer "B.Cu")
		(net 28)
	)
	(arc
		(start 132.38175 205.425749)
		(mid 132.258707 205.609895)
		(end 132.215501 205.827111)
		(width 0.22)
		(layer "B.Cu")
		(net 28)
	)
	(arc
		(start 132.215501 208.024296)
		(mid 132.255784 208.226813)
		(end 132.370501 208.3985)
		(width 0.22)
		(layer "B.Cu")
		(net 28)
	)
	(arc
		(start 132.370501 208.3985)
		(mid 132.485217 208.570185)
		(end 132.525501 208.772703)
		(width 0.22)
		(layer "B.Cu")
		(net 28)
	)
	(segment
		(start 149.875001 187.800501)
		(end 149.375501 187.301)
		(width 0.256)
		(layer "F.Cu")
		(net 29)
	)
	(via
		(at 149.875001 187.800501)
		(size 0.45)
		(drill 0.1)
		(layers "F.Cu" "B.Cu")
		(net 29)
	)
	(segment
		(start 132.215501 203.392602)
		(end 132.215501 203.837297)
		(width 0.22)
		(layer "B.Cu")
		(net 29)
	)
	(segment
		(start 148.922171 190.537829)
		(end 148.871165 190.588835)
		(width 0.22)
		(layer "B.Cu")
		(net 29)
	)
	(segment
		(start 149.565001 188.329704)
		(end 149.565001 188.767616)
		(width 0.22)
		(layer "B.Cu")
		(net 29)
	)
	(segment
		(start 145.448657 191.990501)
		(end 144.975581 191.990501)
		(width 0.22)
		(layer "B.Cu")
		(net 29)
	)
	(segment
		(start 148.699359 190.66)
		(end 148.60986 190.66)
		(width 0.22)
		(layer "B.Cu")
		(net 29)
	)
	(segment
		(start 132.370501 204.211501)
		(end 132.525501 204.366501)
		(width 0.22)
		(layer "B.Cu")
		(net 29)
	)
	(segment
		(start 149.875001 187.800501)
		(end 149.720001 187.955501)
		(width 0.22)
		(layer "B.Cu")
		(net 29)
	)
	(segment
		(start 148.991122 190.15308)
		(end 148.991122 190.371366)
		(width 0.22)
		(layer "B.Cu")
		(net 29)
	)
	(segment
		(start 141.524017 193.420186)
		(end 132.684948 202.259255)
		(width 0.22)
		(layer "B.Cu")
		(net 29)
	)
	(segment
		(start 148.389554 190.751254)
		(end 148.214744 190.926064)
		(width 0.22)
		(layer "B.Cu")
		(net 29)
	)
	(arc
		(start 148.699359 190.66)
		(mid 148.79234 190.641505)
		(end 148.871165 190.588835)
		(width 0.22)
		(layer "B.Cu")
		(net 29)
	)
	(arc
		(start 148.214744 190.926064)
		(mid 146.930115 191.714688)
		(end 145.448657 191.990501)
		(width 0.22)
		(layer "B.Cu")
		(net 29)
	)
	(arc
		(start 148.389554 190.751254)
		(mid 148.490631 190.683716)
		(end 148.60986 190.66)
		(width 0.22)
		(layer "B.Cu")
		(net 29)
	)
	(arc
		(start 149.720001 187.955501)
		(mid 149.605284 188.127186)
		(end 149.565001 188.329704)
		(width 0.22)
		(layer "B.Cu")
		(net 29)
	)
	(arc
		(start 144.975581 191.990501)
		(mid 143.107608 192.362064)
		(end 141.524017 193.420186)
		(width 0.22)
		(layer "B.Cu")
		(net 29)
	)
	(arc
		(start 132.215501 203.837297)
		(mid 132.255784 204.039814)
		(end 132.370501 204.211501)
		(width 0.22)
		(layer "B.Cu")
		(net 29)
	)
	(arc
		(start 149.565001 188.767616)
		(mid 149.415855 189.517424)
		(end 148.991122 190.15308)
		(width 0.22)
		(layer "B.Cu")
		(net 29)
	)
	(arc
		(start 148.991122 190.371366)
		(mid 148.973202 190.461455)
		(end 148.922171 190.537829)
		(width 0.22)
		(layer "B.Cu")
		(net 29)
	)
	(arc
		(start 132.684948 202.259255)
		(mid 132.337506 202.779239)
		(end 132.215501 203.392602)
		(width 0.22)
		(layer "B.Cu")
		(net 29)
	)
	(segment
		(start 151.875001 186.800501)
		(end 151.375501 186.301)
		(width 0.256)
		(layer "F.Cu")
		(net 30)
	)
	(via
		(at 151.875001 186.800501)
		(size 0.45)
		(drill 0.1)
		(layers "F.Cu" "B.Cu")
		(net 30)
	)
	(segment
		(start 151.357279 191.712721)
		(end 151.28 191.79)
		(width 0.22)
		(layer "B.Cu")
		(net 30)
	)
	(segment
		(start 151.565001 187.20365)
		(end 151.565008 187.236331)
		(width 0.22)
		(layer "B.Cu")
		(net 30)
	)
	(segment
		(start 137.370501 204.211501)
		(end 137.525501 204.366501)
		(width 0.22)
		(layer "B.Cu")
		(net 30)
	)
	(segment
		(start 151.875001 186.800501)
		(end 151.630867 187.044634)
		(width 0.22)
		(layer "B.Cu")
		(net 30)
	)
	(segment
		(start 151.152721 191.842721)
		(end 150.97604 191.842721)
		(width 0.22)
		(layer "B.Cu")
		(net 30)
	)
	(segment
		(start 137.215501 202.892602)
		(end 137.215501 203.837297)
		(width 0.22)
		(layer "B.Cu")
		(net 30)
	)
	(segment
		(start 151.41 191.40876)
		(end 151.41 191.585442)
		(width 0.22)
		(layer "B.Cu")
		(net 30)
	)
	(segment
		(start 152.34 188.619805)
		(end 152.34 189.238001)
		(width 0.22)
		(layer "B.Cu")
		(net 30)
	)
	(segment
		(start 151.515369 191.228833)
		(end 151.462721 191.281481)
		(width 0.22)
		(layer "B.Cu")
		(net 30)
	)
	(segment
		(start 151.607794 187.339592)
		(end 151.9525 187.684298)
		(width 0.22)
		(layer "B.Cu")
		(net 30)
	)
	(segment
		(start 150.84876 191.895442)
		(end 150.72938 192.014822)
		(width 0.22)
		(layer "B.Cu")
		(net 30)
	)
	(segment
		(start 150.72938 192.014822)
		(end 150.097164 192.647039)
		(width 0.22)
		(layer "B.Cu")
		(net 30)
	)
	(segment
		(start 143.6102 195.334003)
		(end 138.038501 200.905702)
		(width 0.22)
		(layer "B.Cu")
		(net 30)
	)
	(arc
		(start 138.038501 200.905702)
		(mid 137.429391 201.817299)
		(end 137.215501 202.892602)
		(width 0.22)
		(layer "B.Cu")
		(net 30)
	)
	(arc
		(start 152.34 189.238001)
		(mid 152.125685 190.315431)
		(end 151.515369 191.228833)
		(width 0.22)
		(layer "B.Cu")
		(net 30)
	)
	(arc
		(start 151.41 191.40876)
		(mid 151.423702 191.339877)
		(end 151.462721 191.281481)
		(width 0.22)
		(layer "B.Cu")
		(net 30)
	)
	(arc
		(start 150.097164 192.647039)
		(mid 148.609081 193.641346)
		(end 146.853703 193.990501)
		(width 0.22)
		(layer "B.Cu")
		(net 30)
	)
	(arc
		(start 137.215501 203.837297)
		(mid 137.255784 204.039814)
		(end 137.370501 204.211501)
		(width 0.22)
		(layer "B.Cu")
		(net 30)
	)
	(arc
		(start 151.357279 191.712721)
		(mid 151.396298 191.654325)
		(end 151.41 191.585442)
		(width 0.22)
		(layer "B.Cu")
		(net 30)
	)
	(arc
		(start 151.565008 187.236331)
		(mid 151.576134 187.292216)
		(end 151.607794 187.339592)
		(width 0.22)
		(layer "B.Cu")
		(net 30)
	)
	(arc
		(start 146.853703 193.990501)
		(mid 145.098331 194.339665)
		(end 143.6102 195.334003)
		(width 0.22)
		(layer "B.Cu")
		(net 30)
	)
	(arc
		(start 151.630867 187.044634)
		(mid 151.582119 187.117591)
		(end 151.565001 187.20365)
		(width 0.22)
		(layer "B.Cu")
		(net 30)
	)
	(arc
		(start 150.97604 191.842721)
		(mid 150.907157 191.856423)
		(end 150.84876 191.895442)
		(width 0.22)
		(layer "B.Cu")
		(net 30)
	)
	(arc
		(start 151.152721 191.842721)
		(mid 151.221604 191.829019)
		(end 151.28 191.79)
		(width 0.22)
		(layer "B.Cu")
		(net 30)
	)
	(arc
		(start 151.9525 187.684298)
		(mid 152.239292 188.113512)
		(end 152.34 188.619805)
		(width 0.22)
		(layer "B.Cu")
		(net 30)
	)
	(segment
		(start 137.38175 205.425749)
		(end 137.548 205.2595)
		(width 0.22)
		(layer "B.Cu")
		(net 31)
	)
	(segment
		(start 137.525501 208.772703)
		(end 137.525501 210.801)
		(width 0.22)
		(layer "B.Cu")
		(net 31)
	)
	(segment
		(start 137.215501 208.024296)
		(end 137.215501 205.827111)
		(width 0.22)
		(layer "B.Cu")
		(net 31)
	)
	(arc
		(start 137.38175 205.425749)
		(mid 137.258707 205.609895)
		(end 137.215501 205.827111)
		(width 0.22)
		(layer "B.Cu")
		(net 31)
	)
	(arc
		(start 137.370501 208.3985)
		(mid 137.485217 208.570185)
		(end 137.525501 208.772703)
		(width 0.22)
		(layer "B.Cu")
		(net 31)
	)
	(arc
		(start 137.215501 208.024296)
		(mid 137.255784 208.226813)
		(end 137.370501 208.3985)
		(width 0.22)
		(layer "B.Cu")
		(net 31)
	)
	(segment
		(start 83.788 130.7)
		(end 83.788 129.717)
		(width 0.4)
		(layer "B.Cu")
		(net 32)
	)
	(segment
		(start 80.55 130.95)
		(end 80.55 132.55)
		(width 0.4)
		(layer "B.Cu")
		(net 32)
	)
	(segment
		(start 80.55 132.55)
		(end 79.05 134.05)
		(width 0.4)
		(layer "B.Cu")
		(net 32)
	)
	(segment
		(start 83.788 129.717)
		(end 83.805 129.7)
		(width 0.4)
		(layer "B.Cu")
		(net 32)
	)
	(segment
		(start 79.05 134.05)
		(end 79.05 141)
		(width 0.4)
		(layer "B.Cu")
		(net 32)
	)
	(segment
		(start 81.1405 129.662487)
		(end 81.1405 130.3595)
		(width 0.4)
		(layer "B.Cu")
		(net 32)
	)
	(segment
		(start 79.05 141)
		(end 80.5 142.45)
		(width 0.4)
		(layer "B.Cu")
		(net 32)
	)
	(segment
		(start 80.5 142.45)
		(end 80.5 144.2)
		(width 0.4)
		(layer "B.Cu")
		(net 32)
	)
	(segment
		(start 81.1405 144.8405)
		(end 81.1405 145.361487)
		(width 0.4)
		(layer "B.Cu")
		(net 32)
	)
	(segment
		(start 81.178013 129.7)
		(end 81.1405 129.662487)
		(width 0.4)
		(layer "B.Cu")
		(net 32)
	)
	(segment
		(start 83.805 129.7)
		(end 81.178013 129.7)
		(width 0.4)
		(layer "B.Cu")
		(net 32)
	)
	(segment
		(start 81.1405 130.3595)
		(end 80.55 130.95)
		(width 0.4)
		(layer "B.Cu")
		(net 32)
	)
	(segment
		(start 80.5 144.2)
		(end 81.1405 144.8405)
		(width 0.4)
		(layer "B.Cu")
		(net 32)
	)
	(segment
		(start 94.450501 119.441)
		(end 94.450501 117.176)
		(width 0.15)
		(layer "F.Cu")
		(net 33)
	)
	(segment
		(start 86.976001 186.226001)
		(end 87.4 186.65)
		(width 0.256)
		(layer "F.Cu")
		(net 34)
	)
	(segment
		(start 86.976001 186.1005)
		(end 86.976001 186.226001)
		(width 0.256)
		(layer "F.Cu")
		(net 34)
	)
	(segment
		(start 87.4 187.385499)
		(end 87.465001 187.4505)
		(width 0.256)
		(layer "F.Cu")
		(net 34)
	)
	(segment
		(start 87.4 186.65)
		(end 87.4 187.385499)
		(width 0.256)
		(layer "F.Cu")
		(net 34)
	)
	(segment
		(start 181.066 149.65)
		(end 180.425 149.65)
		(width 0.256)
		(layer "F.Cu")
		(net 36)
	)
	(segment
		(start 181.066 149.766)
		(end 181.066 149.65)
		(width 0.256)
		(layer "F.Cu")
		(net 36)
	)
	(segment
		(start 181.889 150.825)
		(end 181.889 150.589)
		(width 0.256)
		(layer "F.Cu")
		(net 36)
	)
	(segment
		(start 181.889 150.589)
		(end 181.066 149.766)
		(width 0.256)
		(layer "F.Cu")
		(net 36)
	)
	(segment
		(start 181.066 149.625)
		(end 181.066 148.984001)
		(width 0.256)
		(layer "F.Cu")
		(net 36)
	)
	(via
		(at 181.066 148.984001)
		(size 0.45)
		(drill 0.1)
		(layers "F.Cu" "B.Cu")
		(net 36)
	)
	(via
		(at 180.425 149.65)
		(size 0.45)
		(drill 0.1)
		(layers "F.Cu" "B.Cu")
		(net 36)
	)
	(segment
		(start 181.066 147.52)
		(end 181.066 148.984001)
		(width 0.15)
		(layer "B.Cu")
		(net 36)
	)
	(segment
		(start 146.75 149.575)
		(end 180.691834 149.575)
		(width 2)
		(layer "B.Cu")
		(net 36)
	)
	(segment
		(start 140.1 157.25)
		(end 140.1 156.225)
		(width 2)
		(layer "B.Cu")
		(net 36)
	)
	(segment
		(start 140.1 156.225)
		(end 146.75 149.575)
		(width 2)
		(layer "B.Cu")
		(net 36)
	)
	(segment
		(start 180.691834 149.575)
		(end 180.709 149.557834)
		(width 2)
		(layer "B.Cu")
		(net 36)
	)
	(segment
		(start 140.302001 157.25)
		(end 140.302001 158.615)
		(width 0.4)
		(layer "B.Cu")
		(net 36)
	)
	(segment
		(start 104.651 182.934)
		(end 104.651 183.785)
		(width 0.15)
		(layer "F.Cu")
		(net 37)
	)
	(segment
		(start 104.651 183.785)
		(end 105.351 184.484999)
		(width 0.15)
		(layer "F.Cu")
		(net 37)
	)
	(segment
		(start 193.663499 134.19)
		(end 194.013499 134.54)
		(width 0.4)
		(layer "F.Cu")
		(net 38)
	)
	(segment
		(start 194.525 136.978499)
		(end 195.064499 136.439)
		(width 0.256)
		(layer "F.Cu")
		(net 38)
	)
	(segment
		(start 195.064499 136.439)
		(end 195.312499 136.439)
		(width 0.256)
		(layer "F.Cu")
		(net 38)
	)
	(segment
		(start 121.146 201.486)
		(end 121.146 201.346)
		(width 0.4)
		(layer "F.Cu")
		(net 38)
	)
	(segment
		(start 193.663499 133.58)
		(end 193.663499 134.19)
		(width 0.4)
		(layer "F.Cu")
		(net 38)
	)
	(segment
		(start 191.36 134.24)
		(end 189.792901 135.807099)
		(width 0.4)
		(layer "F.Cu")
		(net 38)
	)
	(segment
		(start 194.525 137)
		(end 194.525 136.978499)
		(width 0.256)
		(layer "F.Cu")
		(net 38)
	)
	(segment
		(start 193.713499 134.24)
		(end 191.36 134.24)
		(width 0.4)
		(layer "F.Cu")
		(net 38)
	)
	(segment
		(start 189.792901 135.807099)
		(end 188.691759 135.807099)
		(width 0.4)
		(layer "F.Cu")
		(net 38)
	)
	(segment
		(start 194.013499 134.54)
		(end 195.313499 134.54)
		(width 0.4)
		(layer "F.Cu")
		(net 38)
	)
	(via
		(at 205.7 179.4)
		(size 0.45)
		(drill 0.1)
		(layers "F.Cu" "B.Cu")
		(net 38)
	)
	(via
		(at 203.9 178.05)
		(size 0.45)
		(drill 0.1)
		(layers "F.Cu" "B.Cu")
		(net 38)
	)
	(via
		(at 174.500501 196.376)
		(size 0.45)
		(drill 0.1)
		(layers "F.Cu" "B.Cu")
		(net 38)
	)
	(via
		(at 186.791759 136.307099)
		(size 0.45)
		(drill 0.1)
		(layers "F.Cu" "B.Cu")
		(net 38)
	)
	(via
		(at 203.8 162.3)
		(size 0.45)
		(drill 0.1)
		(layers "F.Cu" "B.Cu")
		(net 38)
	)
	(via
		(at 188.291759 136.307099)
		(size 0.45)
		(drill 0.1)
		(layers "F.Cu" "B.Cu")
		(net 38)
	)
	(via
		(at 203.85 159.7)
		(size 0.45)
		(drill 0.1)
		(layers "F.Cu" "B.Cu")
		(net 38)
	)
	(via
		(at 173.900501 196.076)
		(size 0.45)
		(drill 0.1)
		(layers "F.Cu" "B.Cu")
		(net 38)
	)
	(via
		(at 203.9 178.9)
		(size 0.45)
		(drill 0.1)
		(layers "F.Cu" "B.Cu")
		(net 38)
	)
	(via
		(at 205.65 161)
		(size 0.45)
		(drill 0.1)
		(layers "F.Cu" "B.Cu")
		(net 38)
	)
	(via
		(at 175.3 197.45)
		(size 0.45)
		(drill 0.1)
		(layers "F.Cu" "B.Cu")
		(net 38)
	)
	(via
		(at 205.65 162.75)
		(size 0.45)
		(drill 0.1)
		(layers "F.Cu" "B.Cu")
		(net 38)
	)
	(via
		(at 175.400501 199.476)
		(size 0.45)
		(drill 0.1)
		(layers "F.Cu" "B.Cu")
		(net 38)
	)
	(via
		(at 187.991759 135.807099)
		(size 0.45)
		(drill 0.1)
		(layers "F.Cu" "B.Cu")
		(net 38)
	)
	(via
		(at 175.000501 196.976)
		(size 0.45)
		(drill 0.1)
		(layers "F.Cu" "B.Cu")
		(net 38)
	)
	(via
		(at 173.8 193.976)
		(size 0.45)
		(drill 0.1)
		(layers "F.Cu" "B.Cu")
		(net 38)
	)
	(via
		(at 190.5 135.8)
		(size 0.45)
		(drill 0.1)
		(layers "F.Cu" "B.Cu")
		(net 38)
	)
	(via
		(at 118.15 199.8)
		(size 0.45)
		(drill 0.1)
		(layers "F.Cu" "B.Cu")
		(net 38)
	)
	(via
		(at 175.100501 198.976)
		(size 0.45)
		(drill 0.1)
		(layers "F.Cu" "B.Cu")
		(net 38)
	)
	(via
		(at 186.491759 135.807099)
		(size 0.45)
		(drill 0.1)
		(layers "F.Cu" "B.Cu")
		(net 38)
	)
	(via
		(at 119 197.95)
		(size 0.45)
		(drill 0.1)
		(layers "F.Cu" "B.Cu")
		(net 38)
	)
	(via
		(at 175.100501 199.976)
		(size 0.45)
		(drill 0.1)
		(layers "F.Cu" "B.Cu")
		(net 38)
	)
	(via
		(at 205.7 178.5)
		(size 0.45)
		(drill 0.1)
		(layers "F.Cu" "B.Cu")
		(net 38)
	)
	(via
		(at 194.525 137)
		(size 0.45)
		(drill 0.1)
		(layers "F.Cu" "B.Cu")
		(net 38)
	)
	(via
		(at 175.800501 198.976)
		(size 0.45)
		(drill 0.1)
		(layers "F.Cu" "B.Cu")
		(net 38)
	)
	(via
		(at 188.691759 135.807099)
		(size 0.45)
		(drill 0.1)
		(layers "F.Cu" "B.Cu")
		(net 38)
	)
	(via
		(at 189.2 136.3)
		(size 0.45)
		(drill 0.1)
		(layers "F.Cu" "B.Cu")
		(net 38)
	)
	(via
		(at 193.663499 133.58)
		(size 0.45)
		(drill 0.1)
		(layers "F.Cu" "B.Cu")
		(net 38)
	)
	(via
		(at 117.700501 197.876)
		(size 0.45)
		(drill 0.1)
		(layers "F.Cu" "B.Cu")
		(net 38)
	)
	(via
		(at 205.7 181.05)
		(size 0.45)
		(drill 0.1)
		(layers "F.Cu" "B.Cu")
		(net 38)
	)
	(via
		(at 187.191759 135.807099)
		(size 0.45)
		(drill 0.1)
		(layers "F.Cu" "B.Cu")
		(net 38)
	)
	(via
		(at 205.7 159.2)
		(size 0.45)
		(drill 0.1)
		(layers "F.Cu" "B.Cu")
		(net 38)
	)
	(via
		(at 116.5 199.65)
		(size 0.45)
		(drill 0.1)
		(layers "F.Cu" "B.Cu")
		(net 38)
	)
	(via
		(at 119 199.25)
		(size 0.45)
		(drill 0.1)
		(layers "F.Cu" "B.Cu")
		(net 38)
	)
	(via
		(at 205.7 180.25)
		(size 0.45)
		(drill 0.1)
		(layers "F.Cu" "B.Cu")
		(net 38)
	)
	(via
		(at 203.85 160.55)
		(size 0.45)
		(drill 0.1)
		(layers "F.Cu" "B.Cu")
		(net 38)
	)
	(via
		(at 205.65 161.9)
		(size 0.45)
		(drill 0.1)
		(layers "F.Cu" "B.Cu")
		(net 38)
	)
	(via
		(at 173.85 194.476)
		(size 0.45)
		(drill 0.1)
		(layers "F.Cu" "B.Cu")
		(net 38)
	)
	(via
		(at 190.45 137)
		(size 0.45)
		(drill 0.1)
		(layers "F.Cu" "B.Cu")
		(net 38)
	)
	(via
		(at 203.85 181.45)
		(size 0.45)
		(drill 0.1)
		(layers "F.Cu" "B.Cu")
		(net 38)
	)
	(via
		(at 118.400501 197.076)
		(size 0.45)
		(drill 0.1)
		(layers "F.Cu" "B.Cu")
		(net 38)
	)
	(via
		(at 118.300501 198.676)
		(size 0.45)
		(drill 0.1)
		(layers "F.Cu" "B.Cu")
		(net 38)
	)
	(via
		(at 177.8 199)
		(size 0.45)
		(drill 0.1)
		(layers "F.Cu" "B.Cu")
		(net 38)
	)
	(via
		(at 203.8 163.95)
		(size 0.45)
		(drill 0.1)
		(layers "F.Cu" "B.Cu")
		(net 38)
	)
	(via
		(at 205.65 164.35)
		(size 0.45)
		(drill 0.1)
		(layers "F.Cu" "B.Cu")
		(net 38)
	)
	(via
		(at 175.800501 199.976)
		(size 0.45)
		(drill 0.1)
		(layers "F.Cu" "B.Cu")
		(net 38)
	)
	(via
		(at 205.65 163.55)
		(size 0.45)
		(drill 0.1)
		(layers "F.Cu" "B.Cu")
		(net 38)
	)
	(via
		(at 189.95 136.3)
		(size 0.45)
		(drill 0.1)
		(layers "F.Cu" "B.Cu")
		(net 38)
	)
	(via
		(at 203.8 163.1)
		(size 0.45)
		(drill 0.1)
		(layers "F.Cu" "B.Cu")
		(net 38)
	)
	(via
		(at 203.8 164.75)
		(size 0.45)
		(drill 0.1)
		(layers "F.Cu" "B.Cu")
		(net 38)
	)
	(via
		(at 187.591759 136.307099)
		(size 0.45)
		(drill 0.1)
		(layers "F.Cu" "B.Cu")
		(net 38)
	)
	(via
		(at 189.55 135.8)
		(size 0.45)
		(drill 0.1)
		(layers "F.Cu" "B.Cu")
		(net 38)
	)
	(via
		(at 178.3 199.5)
		(size 0.45)
		(drill 0.1)
		(layers "F.Cu" "B.Cu")
		(net 38)
	)
	(via
		(at 115.100501 198.576)
		(size 0.45)
		(drill 0.1)
		(layers "F.Cu" "B.Cu")
		(net 38)
	)
	(via
		(at 203.85 179.8)
		(size 0.45)
		(drill 0.1)
		(layers "F.Cu" "B.Cu")
		(net 38)
	)
	(via
		(at 117.000501 198.576)
		(size 0.45)
		(drill 0.1)
		(layers "F.Cu" "B.Cu")
		(net 38)
	)
	(via
		(at 175.343539 198.501059)
		(size 0.45)
		(drill 0.1)
		(layers "F.Cu" "B.Cu")
		(net 38)
	)
	(via
		(at 175.000501 195.776501)
		(size 0.45)
		(drill 0.1)
		(layers "F.Cu" "B.Cu")
		(net 38)
	)
	(via
		(at 203.9 177.2)
		(size 0.45)
		(drill 0.1)
		(layers "F.Cu" "B.Cu")
		(net 38)
	)
	(via
		(at 177.8 200)
		(size 0.45)
		(drill 0.1)
		(layers "F.Cu" "B.Cu")
		(net 38)
	)
	(via
		(at 117.100501 197.076)
		(size 0.45)
		(drill 0.1)
		(layers "F.Cu" "B.Cu")
		(net 38)
	)
	(via
		(at 175.100501 197.976)
		(size 0.45)
		(drill 0.1)
		(layers "F.Cu" "B.Cu")
		(net 38)
	)
	(via
		(at 176.200501 199.476)
		(size 0.45)
		(drill 0.1)
		(layers "F.Cu" "B.Cu")
		(net 38)
	)
	(via
		(at 177.2 199.476)
		(size 0.45)
		(drill 0.1)
		(layers "F.Cu" "B.Cu")
		(net 38)
	)
	(via
		(at 116 198.95)
		(size 0.45)
		(drill 0.1)
		(layers "F.Cu" "B.Cu")
		(net 38)
	)
	(via
		(at 205.75 177.6)
		(size 0.45)
		(drill 0.1)
		(layers "F.Cu" "B.Cu")
		(net 38)
	)
	(via
		(at 173.8 195)
		(size 0.45)
		(drill 0.1)
		(layers "F.Cu" "B.Cu")
		(net 38)
	)
	(via
		(at 191.1 136.45)
		(size 0.45)
		(drill 0.1)
		(layers "F.Cu" "B.Cu")
		(net 38)
	)
	(via
		(at 117.6 199.2)
		(size 0.45)
		(drill 0.1)
		(layers "F.Cu" "B.Cu")
		(net 38)
	)
	(via
		(at 176.7 198.976)
		(size 0.45)
		(drill 0.1)
		(layers "F.Cu" "B.Cu")
		(net 38)
	)
	(via
		(at 175.300501 196.376)
		(size 0.45)
		(drill 0.1)
		(layers "F.Cu" "B.Cu")
		(net 38)
	)
	(via
		(at 205.7 160.1)
		(size 0.45)
		(drill 0.1)
		(layers "F.Cu" "B.Cu")
		(net 38)
	)
	(via
		(at 176.7 199.976)
		(size 0.45)
		(drill 0.1)
		(layers "F.Cu" "B.Cu")
		(net 38)
	)
	(via
		(at 173.85 195.55)
		(size 0.45)
		(drill 0.1)
		(layers "F.Cu" "B.Cu")
		(net 38)
	)
	(via
		(at 205.7 181.85)
		(size 0.45)
		(drill 0.1)
		(layers "F.Cu" "B.Cu")
		(net 38)
	)
	(via
		(at 203.85 180.6)
		(size 0.45)
		(drill 0.1)
		(layers "F.Cu" "B.Cu")
		(net 38)
	)
	(via
		(at 174.400501 195.776)
		(size 0.45)
		(drill 0.1)
		(layers "F.Cu" "B.Cu")
		(net 38)
	)
	(via
		(at 116.100501 197.876)
		(size 0.45)
		(drill 0.1)
		(layers "F.Cu" "B.Cu")
		(net 38)
	)
	(via
		(at 115.15 199.7)
		(size 0.45)
		(drill 0.1)
		(layers "F.Cu" "B.Cu")
		(net 38)
	)
	(via
		(at 203.85 161.4)
		(size 0.45)
		(drill 0.1)
		(layers "F.Cu" "B.Cu")
		(net 38)
	)
	(via
		(at 203.85 182.25)
		(size 0.45)
		(drill 0.1)
		(layers "F.Cu" "B.Cu")
		(net 38)
	)
	(segment
		(start 173.584501 196.076)
		(end 173.284501 196.376)
		(width 0.4)
		(layer "B.Cu")
		(net 38)
	)
	(segment
		(start 194.525 134.441501)
		(end 193.663499 133.58)
		(width 0.256)
		(layer "B.Cu")
		(net 38)
	)
	(segment
		(start 173.900501 196.076)
		(end 173.584501 196.076)
		(width 0.4)
		(layer "B.Cu")
		(net 38)
	)
	(segment
		(start 194.525 137)
		(end 194.525 134.441501)
		(width 0.256)
		(layer "B.Cu")
		(net 38)
	)
	(segment
		(start 201.165501 185.9405)
		(end 202.028001 185.9405)
		(width 0.182)
		(layer "F.Cu")
		(net 39)
	)
	(via
		(at 202.028001 185.9405)
		(size 0.45)
		(drill 0.1)
		(layers "F.Cu" "B.Cu")
		(net 39)
	)
	(segment
		(start 202.043501 185.925)
		(end 202.028001 185.9405)
		(width 0.256)
		(layer "B.Cu")
		(net 39)
	)
	(segment
		(start 202.95 185.834)
		(end 202.859 185.925)
		(width 0.256)
		(layer "B.Cu")
		(net 39)
	)
	(segment
		(start 202.859 185.925)
		(end 202.043501 185.925)
		(width 0.256)
		(layer "B.Cu")
		(net 39)
	)
	(segment
		(start 201.981001 168.4845)
		(end 201.131001 168.4845)
		(width 0.182)
		(layer "F.Cu")
		(net 40)
	)
	(segment
		(start 202.068501 168.572)
		(end 201.981001 168.4845)
		(width 0.182)
		(layer "F.Cu")
		(net 40)
	)
	(via
		(at 202.068501 168.572)
		(size 0.45)
		(drill 0.1)
		(layers "F.Cu" "B.Cu")
		(net 40)
	)
	(segment
		(start 202.115501 168.525)
		(end 202.068501 168.572)
		(width 0.256)
		(layer "B.Cu")
		(net 40)
	)
	(segment
		(start 202.759 168.525)
		(end 202.115501 168.525)
		(width 0.256)
		(layer "B.Cu")
		(net 40)
	)
	(segment
		(start 202.9 168.384)
		(end 202.759 168.525)
		(width 0.256)
		(layer "B.Cu")
		(net 40)
	)
	(segment
		(start 102 183.6)
		(end 102 184.315)
		(width 0.15)
		(layer "F.Cu")
		(net 41)
	)
	(segment
		(start 197.729 138.289)
		(end 197.7 138.318)
		(width 0.182)
		(layer "F.Cu")
		(net 41)
	)
	(segment
		(start 183.976 197.308)
		(end 184.15 197.134)
		(width 0.256)
		(layer "F.Cu")
		(net 41)
	)
	(segment
		(start 106.151 181.929)
		(end 106.946 181.929)
		(width 0.15)
		(layer "F.Cu")
		(net 41)
	)
	(segment
		(start 107.3 184.315)
		(end 107.885 184.315)
		(width 0.15)
		(layer "F.Cu")
		(net 41)
	)
	(segment
		(start 107.251 182.234)
		(end 107.885 182.234)
		(width 0.15)
		(layer "F.Cu")
		(net 41)
	)
	(segment
		(start 184.15 193.384)
		(end 184.784 193.384)
		(width 0.256)
		(layer "F.Cu")
		(net 41)
	)
	(segment
		(start 184.784 193.384)
		(end 184.8 193.4)
		(width 0.256)
		(layer "F.Cu")
		(net 41)
	)
	(segment
		(start 102.25 183.35)
		(end 102 183.6)
		(width 0.15)
		(layer "F.Cu")
		(net 41)
	)
	(segment
		(start 197.8 141.225)
		(end 197.8 141.603)
		(width 0.256)
		(layer "F.Cu")
		(net 41)
	)
	(segment
		(start 183.976 193.558)
		(end 184.15 193.384)
		(width 0.256)
		(layer "F.Cu")
		(net 41)
	)
	(segment
		(start 183.027 197.308)
		(end 183.976 197.308)
		(width 0.256)
		(layer "F.Cu")
		(net 41)
	)
	(segment
		(start 198.749499 138.289)
		(end 197.729 138.289)
		(width 0.182)
		(layer "F.Cu")
		(net 41)
	)
	(segment
		(start 108.326 183.874)
		(end 108.326 182.675)
		(width 0.15)
		(layer "F.Cu")
		(net 41)
	)
	(segment
		(start 107.885 184.315)
		(end 108.326 183.874)
		(width 0.15)
		(layer "F.Cu")
		(net 41)
	)
	(segment
		(start 106.946 181.929)
		(end 107.251 182.234)
		(width 0.15)
		(layer "F.Cu")
		(net 41)
	)
	(segment
		(start 184.15 197.134)
		(end 184.784 197.134)
		(width 0.256)
		(layer "F.Cu")
		(net 41)
	)
	(segment
		(start 197.619 147.801)
		(end 197.615 147.805)
		(width 0.198)
		(layer "F.Cu")
		(net 41)
	)
	(segment
		(start 107.885 182.234)
		(end 107.901 182.25)
		(width 0.15)
		(layer "F.Cu")
		(net 41)
	)
	(segment
		(start 183.027 193.558)
		(end 183.976 193.558)
		(width 0.256)
		(layer "F.Cu")
		(net 41)
	)
	(segment
		(start 108.326 182.675)
		(end 107.901 182.25)
		(width 0.15)
		(layer "F.Cu")
		(net 41)
	)
	(segment
		(start 197.825 141.2)
		(end 197.8 141.225)
		(width 0.256)
		(layer "F.Cu")
		(net 41)
	)
	(segment
		(start 197.8 141.603)
		(end 197.5495 141.8535)
		(width 0.256)
		(layer "F.Cu")
		(net 41)
	)
	(segment
		(start 199.2 141.2)
		(end 197.825 141.2)
		(width 0.256)
		(layer "F.Cu")
		(net 41)
	)
	(segment
		(start 198.714499 147.801)
		(end 197.619 147.801)
		(width 0.198)
		(layer "F.Cu")
		(net 41)
	)
	(segment
		(start 184.784 197.134)
		(end 184.8 197.15)
		(width 0.256)
		(layer "F.Cu")
		(net 41)
	)
	(via
		(at 199.443499 134.225)
		(size 0.45)
		(drill 0.1)
		(layers "F.Cu" "B.Cu")
		(free yes)
		(net 41)
	)
	(via
		(at 198.749499 138.289)
		(size 0.45)
		(drill 0.1)
		(layers "F.Cu" "B.Cu")
		(net 41)
	)
	(via
		(at 184.8 193.4)
		(size 0.45)
		(drill 0.1)
		(layers "F.Cu" "B.Cu")
		(net 41)
	)
	(via
		(at 196.050499 145.19)
		(size 0.45)
		(drill 0.1)
		(layers "F.Cu" "B.Cu")
		(net 41)
	)
	(via
		(at 198.714499 147.801)
		(size 0.45)
		(drill 0.1)
		(layers "F.Cu" "B.Cu")
		(net 41)
	)
	(via
		(at 107.901 182.25)
		(size 0.45)
		(drill 0.1)
		(layers "F.Cu" "B.Cu")
		(net 41)
	)
	(via
		(at 199.973499 135.09)
		(size 0.45)
		(drill 0.1)
		(layers "F.Cu" "B.Cu")
		(free yes)
		(net 41)
	)
	(via
		(at 195.95 151.8)
		(size 0.45)
		(drill 0.1)
		(layers "F.Cu" "B.Cu")
		(net 41)
	)
	(via
		(at 191.7255 135.1)
		(size 0.45)
		(drill 0.1)
		(layers "F.Cu" "B.Cu")
		(net 41)
	)
	(via
		(at 200.65 135.075)
		(size 0.45)
		(drill 0.1)
		(layers "F.Cu" "B.Cu")
		(free yes)
		(net 41)
	)
	(via
		(at 197.8 141.225)
		(size 0.45)
		(drill 0.1)
		(layers "F.Cu" "B.Cu")
		(net 41)
	)
	(via
		(at 184.8 197.15)
		(size 0.45)
		(drill 0.1)
		(layers "F.Cu" "B.Cu")
		(net 41)
	)
	(via
		(at 200.225 134.2)
		(size 0.45)
		(drill 0.1)
		(layers "F.Cu" "B.Cu")
		(free yes)
		(net 41)
	)
	(via
		(at 197.125 148.9)
		(size 0.45)
		(drill 0.1)
		(layers "F.Cu" "B.Cu")
		(net 41)
	)
	(via
		(at 102.25 183.35)
		(size 0.45)
		(drill 0.1)
		(layers "F.Cu" "B.Cu")
		(net 41)
	)
	(segment
		(start 184.8 197.15)
		(end 184.8 193.4)
		(width 0.256)
		(layer "B.Cu")
		(net 41)
	)
	(segment
		(start 198.664499 147.851)
		(end 195.9 147.851)
		(width 0.256)
		(layer "B.Cu")
		(net 41)
	)
	(segment
		(start 204.5 168.05)
		(end 204.3 168.25)
		(width 0.256)
		(layer "B.Cu")
		(net 41)
	)
	(segment
		(start 201.9 190.7)
		(end 190.3 190.7)
		(width 0.256)
		(layer "B.Cu")
		(net 41)
	)
	(segment
		(start 197.8 142)
		(end 197.8 141.225)
		(width 0.256)
		(layer "B.Cu")
		(net 41)
	)
	(segment
		(start 92.7 179.35)
		(end 92.7 180.55)
		(width 0.4)
		(layer "B.Cu")
		(net 41)
	)
	(segment
		(start 204.3 188.3)
		(end 201.9 190.7)
		(width 0.256)
		(layer "B.Cu")
		(net 41)
	)
	(segment
		(start 173.75627 132.35)
		(end 173.05627 133.05)
		(width 0.4)
		(layer "B.Cu")
		(net 41)
	)
	(segment
		(start 81.6 161.8)
		(end 81.95 162.15)
		(width 0.4)
		(layer "B.Cu")
		(net 41)
	)
	(segment
		(start 173.05627 133.05)
		(end 101.6 133.05)
		(width 0.4)
		(layer "B.Cu")
		(net 41)
	)
	(segment
		(start 82.8 149.2)
		(end 81.6 150.4)
		(width 0.4)
		(layer "B.Cu")
		(net 41)
	)
	(segment
		(start 101.35 183.35)
		(end 102.25 183.35)
		(width 0.4)
		(layer "B.Cu")
		(net 41)
	)
	(segment
		(start 105.25 183.35)
		(end 102.25 183.35)
		(width 0.4)
		(layer "B.Cu")
		(net 41)
	)
	(segment
		(start 107.901 182.25)
		(end 106.35 182.25)
		(width 0.4)
		(layer "B.Cu")
		(net 41)
	)
	(segment
		(start 96.15 130.8)
		(end 96.15 138.25)
		(width 0.4)
		(layer "B.Cu")
		(net 41)
	)
	(segment
		(start 185.9 192.3)
		(end 184.8 193.4)
		(width 0.256)
		(layer "B.Cu")
		(net 41)
	)
	(segment
		(start 195.9 145.851)
		(end 195.9 147.851)
		(width 0.256)
		(layer "B.Cu")
		(net 41)
	)
	(segment
		(start 81.95 173.8)
		(end 86.8 178.65)
		(width 0.4)
		(layer "B.Cu")
		(net 41)
	)
	(segment
		(start 198.714499 147.801)
		(end 198.699499 147.786)
		(width 0.182)
		(layer "B.Cu")
		(net 41)
	)
	(segment
		(start 197.5 142.3)
		(end 197.8 142)
		(width 0.256)
		(layer "B.Cu")
		(net 41)
	)
	(segment
		(start 204.3 182.95)
		(end 204.3 188.3)
		(width 0.256)
		(layer "B.Cu")
		(net 41)
	)
	(segment
		(start 85.2 149.2)
		(end 82.8 149.2)
		(width 0.4)
		(layer "B.Cu")
		(net 41)
	)
	(segment
		(start 204.3 168.25)
		(end 204.3 176.25)
		(width 0.256)
		(layer "B.Cu")
		(net 41)
	)
	(segment
		(start 199.2 141.2)
		(end 197.825 141.2)
		(width 0.15)
		(layer "B.Cu")
		(net 41)
	)
	(segment
		(start 198.740499 138.28)
		(end 198.1 138.28)
		(width 0.256)
		(layer "B.Cu")
		(net 41)
	)
	(segment
		(start 204.5 182.75)
		(end 204.3 182.95)
		(width 0.256)
		(layer "B.Cu")
		(net 41)
	)
	(segment
		(start 92.7 180.55)
		(end 96.3 184.15)
		(width 0.4)
		(layer "B.Cu")
		(net 41)
	)
	(segment
		(start 185.9 192.3)
		(end 188.7 192.3)
		(width 0.256)
		(layer "B.Cu")
		(net 41)
	)
	(segment
		(start 197.825 141.2)
		(end 197.8 141.225)
		(width 0.15)
		(layer "B.Cu")
		(net 41)
	)
	(segment
		(start 106.35 182.25)
		(end 105.25 183.35)
		(width 0.4)
		(layer "B.Cu")
		(net 41)
	)
	(segment
		(start 204.5 159.1)
		(end 204.5 168.05)
		(width 0.256)
		(layer "B.Cu")
		(net 41)
	)
	(segment
		(start 188.9755 132.35)
		(end 173.75627 132.35)
		(width 0.4)
		(layer "B.Cu")
		(net 41)
	)
	(segment
		(start 196.468499 156.568499)
		(end 198.5 158.6)
		(width 0.256)
		(layer "B.Cu")
		(net 41)
	)
	(segment
		(start 100.55 184.15)
		(end 101.35 183.35)
		(width 0.4)
		(layer "B.Cu")
		(net 41)
	)
	(segment
		(start 196.465001 151.8)
		(end 195.95 151.8)
		(width 0.4)
		(layer "B.Cu")
		(net 41)
	)
	(segment
		(start 197.775 141.25)
		(end 197.8 141.225)
		(width 0.256)
		(layer "B.Cu")
		(net 41)
	)
	(segment
		(start 198.699499 147.786)
		(end 198.065 147.786)
		(width 0.182)
		(layer "B.Cu")
		(net 41)
	)
	(segment
		(start 198.5 158.6)
		(end 204 158.6)
		(width 0.256)
		(layer "B.Cu")
		(net 41)
	)
	(segment
		(start 198.749499 138.289)
		(end 198.740499 138.28)
		(width 0.182)
		(layer "B.Cu")
		(net 41)
	)
	(segment
		(start 198.714499 147.801)
		(end 198.664499 147.851)
		(width 0.256)
		(layer "B.Cu")
		(net 41)
	)
	(segment
		(start 191.7255 135.1)
		(end 188.9755 132.35)
		(width 0.4)
		(layer "B.Cu")
		(net 41)
	)
	(segment
		(start 196.468499 152.8535)
		(end 196.468499 156.568499)
		(width 0.256)
		(layer "B.Cu")
		(net 41)
	)
	(segment
		(start 204 158.6)
		(end 204.5 159.1)
		(width 0.256)
		(layer "B.Cu")
		(net 41)
	)
	(segment
		(start 98.95 130.4)
		(end 96.55 130.4)
		(width 0.4)
		(layer "B.Cu")
		(net 41)
	)
	(segment
		(start 195.9 145.196)
		(end 195.905 145.191)
		(width 0.256)
		(layer "B.Cu")
		(net 41)
	)
	(segment
		(start 96.15 138.25)
		(end 85.2 149.2)
		(width 0.4)
		(layer "B.Cu")
		(net 41)
	)
	(segment
		(start 195.9 145.851)
		(end 195.9 145.196)
		(width 0.256)
		(layer "B.Cu")
		(net 41)
	)
	(segment
		(start 96.55 130.4)
		(end 96.15 130.8)
		(width 0.4)
		(layer "B.Cu")
		(net 41)
	)
	(segment
		(start 204.5 176.45)
		(end 204.5 182.75)
		(width 0.256)
		(layer "B.Cu")
		(net 41)
	)
	(segment
		(start 204.3 176.25)
		(end 204.5 176.45)
		(width 0.256)
		(layer "B.Cu")
		(net 41)
	)
	(segment
		(start 188.7 192.3)
		(end 190.3 190.7)
		(width 0.256)
		(layer "B.Cu")
		(net 41)
	)
	(segment
		(start 101.6 133.05)
		(end 98.95 130.4)
		(width 0.4)
		(layer "B.Cu")
		(net 41)
	)
	(segment
		(start 196.465001 151.8)
		(end 196.465001 152.850002)
		(width 0.4)
		(layer "B.Cu")
		(net 41)
	)
	(segment
		(start 96.3 184.15)
		(end 100.55 184.15)
		(width 0.4)
		(layer "B.Cu")
		(net 41)
	)
	(segment
		(start 197.034 141.25)
		(end 197.775 141.25)
		(width 0.256)
		(layer "B.Cu")
		(net 41)
	)
	(segment
		(start 81.95 162.15)
		(end 81.95 173.8)
		(width 0.4)
		(layer "B.Cu")
		(net 41)
	)
	(segment
		(start 197.06 142.3)
		(end 197.5 142.3)
		(width 0.256)
		(layer "B.Cu")
		(net 41)
	)
	(segment
		(start 81.6 150.4)
		(end 81.6 161.8)
		(width 0.4)
		(layer "B.Cu")
		(net 41)
	)
	(segment
		(start 92 178.65)
		(end 92.7 179.35)
		(width 0.4)
		(layer "B.Cu")
		(net 41)
	)
	(segment
		(start 196.465001 152.850002)
		(end 196.468499 152.8535)
		(width 0.4)
		(layer "B.Cu")
		(net 41)
	)
	(segment
		(start 86.8 178.65)
		(end 92 178.65)
		(width 0.4)
		(layer "B.Cu")
		(net 41)
	)
	(segment
		(start 195.95 151.8)
		(end 195.95 150.075)
		(width 0.4)
		(layer "In4.Cu")
		(net 41)
	)
	(segment
		(start 195.95 150.075)
		(end 197.125 148.9)
		(width 0.4)
		(layer "In4.Cu")
		(net 41)
	)
	(segment
		(start 191.195501 188.873)
		(end 192.195501 189.873)
		(width 0.4)
		(layer "F.Cu")
		(net 42)
	)
	(segment
		(start 191.195501 186.273)
		(end 191.195501 188.873)
		(width 0.4)
		(layer "F.Cu")
		(net 42)
	)
	(segment
		(start 192.195501 189.873)
		(end 195.198001 189.873)
		(width 0.4)
		(layer "F.Cu")
		(net 42)
	)
	(segment
		(start 191.245501 186.223)
		(end 191.195501 186.273)
		(width 0.4)
		(layer "F.Cu")
		(net 42)
	)
	(segment
		(start 195.198001 189.873)
		(end 195.910501 189.1605)
		(width 0.4)
		(layer "F.Cu")
		(net 42)
	)
	(via
		(at 191.14 189.86)
		(size 0.45)
		(drill 0.1)
		(layers "F.Cu" "B.Cu")
		(net 42)
	)
	(segment
		(start 191.69 189.31)
		(end 191.14 189.86)
		(width 0.15)
		(layer "B.Cu")
		(net 42)
	)
	(segment
		(start 191.69 189.26)
		(end 191.69 189.31)
		(width 0.15)
		(layer "B.Cu")
		(net 42)
	)
	(segment
		(start 103.951 184.485)
		(end 103.851 184.385)
		(width 0.15)
		(layer "F.Cu")
		(net 43)
	)
	(segment
		(start 104.157 183.679)
		(end 103.951 183.885)
		(width 0.15)
		(layer "F.Cu")
		(net 43)
	)
	(segment
		(start 103.851 184.385)
		(end 103.135 184.385)
		(width 0.15)
		(layer "F.Cu")
		(net 43)
	)
	(segment
		(start 103.951 183.885)
		(end 103.951 184.485)
		(width 0.15)
		(layer "F.Cu")
		(net 43)
	)
	(segment
		(start 103.135 184.385)
		(end 103.05 184.3)
		(width 0.15)
		(layer "F.Cu")
		(net 43)
	)
	(segment
		(start 104.157 182.934)
		(end 104.157 183.679)
		(width 0.15)
		(layer "F.Cu")
		(net 43)
	)
	(segment
		(start 126.376501 186.301)
		(end 125.877001 186.8005)
		(width 0.256)
		(layer "F.Cu")
		(net 44)
	)
	(via
		(at 125.877001 186.8005)
		(size 0.45)
		(drill 0.1)
		(layers "F.Cu" "B.Cu")
		(net 44)
	)
	(segment
		(start 125.2 185.8)
		(end 124.2 184.8)
		(width 0.256)
		(layer "B.Cu")
		(net 44)
	)
	(segment
		(start 125.877001 186.8005)
		(end 125.6005 186.8005)
		(width 0.256)
		(layer "B.Cu")
		(net 44)
	)
	(segment
		(start 125.2 186.4)
		(end 125.2 185.8)
		(width 0.256)
		(layer "B.Cu")
		(net 44)
	)
	(segment
		(start 125.6005 186.8005)
		(end 125.2 186.4)
		(width 0.256)
		(layer "B.Cu")
		(net 44)
	)
	(segment
		(start 163.4 175.332713)
		(end 163.467287 175.4)
		(width 0.256)
		(layer "F.Cu")
		(net 45)
	)
	(segment
		(start 166.100501 177.500501)
		(end 167 178.4)
		(width 0.256)
		(layer "F.Cu")
		(net 45)
	)
	(segment
		(start 95.575 185.085)
		(end 95.575 185.775)
		(width 0.15)
		(layer "F.Cu")
		(net 45)
	)
	(segment
		(start 164.715 175.2)
		(end 165.487 175.2)
		(width 0.256)
		(layer "F.Cu")
		(net 45)
	)
	(segment
		(start 165.7 175.2)
		(end 165.487 175.2)
		(width 0.256)
		(layer "F.Cu")
		(net 45)
	)
	(segment
		(start 166.100501 175.600501)
		(end 165.7 175.2)
		(width 0.256)
		(layer "F.Cu")
		(net 45)
	)
	(segment
		(start 144.375501 175.301)
		(end 144.875001 175.8005)
		(width 0.256)
		(layer "F.Cu")
		(net 45)
	)
	(segment
		(start 167 178.4)
		(end 168.67 178.4)
		(width 0.256)
		(layer "F.Cu")
		(net 45)
	)
	(segment
		(start 166.100501 177.500501)
		(end 166.100501 175.600501)
		(width 0.256)
		(layer "F.Cu")
		(net 45)
	)
	(segment
		(start 163.467287 175.4)
		(end 163.8 175.4)
		(width 0.256)
		(layer "F.Cu")
		(net 45)
	)
	(segment
		(start 163.8 175.4)
		(end 164 175.2)
		(width 0.256)
		(layer "F.Cu")
		(net 45)
	)
	(segment
		(start 164 175.2)
		(end 164.715 175.2)
		(width 0.256)
		(layer "F.Cu")
		(net 45)
	)
	(via
		(at 163.4 175.332713)
		(size 0.45)
		(drill 0.1)
		(layers "F.Cu" "B.Cu")
		(net 45)
	)
	(via
		(at 144.875001 175.8005)
		(size 0.45)
		(drill 0.1)
		(layers "F.Cu" "B.Cu")
		(net 45)
	)
	(via
		(at 95.575 185.775)
		(size 0.45)
		(drill 0.1)
		(layers "F.Cu" "B.Cu")
		(net 45)
	)
	(segment
		(start 97.5 185.775)
		(end 95.575 185.775)
		(width 0.15)
		(layer "B.Cu")
		(net 45)
	)
	(segment
		(start 145.375501 176.301)
		(end 144.875001 175.8005)
		(width 0.1)
		(layer "In4.Cu")
		(net 45)
	)
	(segment
		(start 163.055996 175.332713)
		(end 161.638709 176.75)
		(width 0.1)
		(layer "In4.Cu")
		(net 45)
	)
	(segment
		(start 163.4 175.332713)
		(end 163.055996 175.332713)
		(width 0.1)
		(layer "In4.Cu")
		(net 45)
	)
	(segment
		(start 159.15 176.75)
		(end 158.55 177.35)
		(width 0.1)
		(layer "In4.Cu")
		(net 45)
	)
	(segment
		(start 161.638709 176.75)
		(end 159.15 176.75)
		(width 0.1)
		(layer "In4.Cu")
		(net 45)
	)
	(segment
		(start 152.3755 176.301)
		(end 145.375501 176.301)
		(width 0.1)
		(layer "In4.Cu")
		(net 45)
	)
	(segment
		(start 158.55 177.35)
		(end 153.4245 177.35)
		(width 0.1)
		(layer "In4.Cu")
		(net 45)
	)
	(segment
		(start 153.4245 177.35)
		(end 152.3755 176.301)
		(width 0.1)
		(layer "In4.Cu")
		(net 45)
	)
	(segment
		(start 144.875001 175.8005)
		(end 144.375501 176.3)
		(width 0.1)
		(layer "In9.Cu")
		(net 45)
	)
	(segment
		(start 102.8 188.9)
		(end 98.7 188.9)
		(width 0.1)
		(layer "In9.Cu")
		(net 45)
	)
	(segment
		(start 98.7 188.9)
		(end 95.575 185.775)
		(width 0.1)
		(layer "In9.Cu")
		(net 45)
	)
	(segment
		(start 133.6 176.3)
		(end 133.4 176.5)
		(width 0.1)
		(layer "In9.Cu")
		(net 45)
	)
	(segment
		(start 144.375501 176.3)
		(end 133.6 176.3)
		(width 0.1)
		(layer "In9.Cu")
		(net 45)
	)
	(segment
		(start 133.4 188)
		(end 132.4 189)
		(width 0.1)
		(layer "In9.Cu")
		(net 45)
	)
	(segment
		(start 133.4 176.5)
		(end 133.4 188)
		(width 0.1)
		(layer "In9.Cu")
		(net 45)
	)
	(segment
		(start 105.95 192.05)
		(end 102.8 188.9)
		(width 0.1)
		(layer "In9.Cu")
		(net 45)
	)
	(segment
		(start 132.4 191.3)
		(end 131.65 192.05)
		(width 0.1)
		(layer "In9.Cu")
		(net 45)
	)
	(segment
		(start 131.65 192.05)
		(end 105.95 192.05)
		(width 0.1)
		(layer "In9.Cu")
		(net 45)
	)
	(segment
		(start 132.4 189)
		(end 132.4 191.3)
		(width 0.1)
		(layer "In9.Cu")
		(net 45)
	)
	(segment
		(start 167.7 176.4)
		(end 168.67 176.4)
		(width 0.256)
		(layer "F.Cu")
		(net 46)
	)
	(segment
		(start 163.9 174.7)
		(end 164.715 174.7)
		(width 0.256)
		(layer "F.Cu")
		(net 46)
	)
	(segment
		(start 164.715 174.7)
		(end 165.487 174.7)
		(width 0.256)
		(layer "F.Cu")
		(net 46)
	)
	(segment
		(start 166 174.7)
		(end 167.7 176.4)
		(width 0.256)
		(layer "F.Cu")
		(net 46)
	)
	(segment
		(start 144.375501 177.301)
		(end 144.875 177.8005)
		(width 0.256)
		(layer "F.Cu")
		(net 46)
	)
	(segment
		(start 165.487 174.7)
		(end 166 174.7)
		(width 0.256)
		(layer "F.Cu")
		(net 46)
	)
	(segment
		(start 94.525 185.085)
		(end 94.525 185.775)
		(width 0.15)
		(layer "F.Cu")
		(net 46)
	)
	(via
		(at 163.9 174.7)
		(size 0.45)
		(drill 0.1)
		(layers "F.Cu" "B.Cu")
		(net 46)
	)
	(via
		(at 144.875 177.8005)
		(size 0.45)
		(drill 0.1)
		(layers "F.Cu" "B.Cu")
		(net 46)
	)
	(via
		(at 94.525 185.775)
		(size 0.45)
		(drill 0.1)
		(layers "F.Cu" "B.Cu")
		(net 46)
	)
	(segment
		(start 97.5 188.275)
		(end 96.225 187)
		(width 0.15)
		(layer "B.Cu")
		(net 46)
	)
	(segment
		(start 95.3 187)
		(end 94.525 186.225)
		(width 0.15)
		(layer "B.Cu")
		(net 46)
	)
	(segment
		(start 94.525 186.225)
		(end 94.525 185.775)
		(width 0.15)
		(layer "B.Cu")
		(net 46)
	)
	(segment
		(start 96.225 187)
		(end 95.3 187)
		(width 0.15)
		(layer "B.Cu")
		(net 46)
	)
	(segment
		(start 159.349 177.301)
		(end 162.299 177.301)
		(width 0.107)
		(layer "In4.Cu")
		(net 46)
	)
	(segment
		(start 163.9 175.7)
		(end 163.9 174.7)
		(width 0.107)
		(layer "In4.Cu")
		(net 46)
	)
	(segment
		(start 158.95 177.7)
		(end 159.349 177.301)
		(width 0.107)
		(layer "In4.Cu")
		(net 46)
	)
	(segment
		(start 162.299 177.301)
		(end 163.9 175.7)
		(width 0.107)
		(layer "In4.Cu")
		(net 46)
	)
	(segment
		(start 152.849 177.301)
		(end 153.248 177.7)
		(width 0.107)
		(layer "In4.Cu")
		(net 46)
	)
	(segment
		(start 153.248 177.7)
		(end 158.95 177.7)
		(width 0.107)
		(layer "In4.Cu")
		(net 46)
	)
	(segment
		(start 145.3745 177.301)
		(end 152.849 177.301)
		(width 0.107)
		(layer "In4.Cu")
		(net 46)
	)
	(segment
		(start 144.875 177.8005)
		(end 145.3745 177.301)
		(width 0.107)
		(layer "In4.Cu")
		(net 46)
	)
	(segment
		(start 134.6 177.3)
		(end 134.4 177.5)
		(width 0.1)
		(layer "In9.Cu")
		(net 46)
	)
	(segment
		(start 101.5 189.5)
		(end 97.625 189.5)
		(width 0.1)
		(layer "In9.Cu")
		(net 46)
	)
	(segment
		(start 132.8 191.4)
		(end 131.1 193.1)
		(width 0.1)
		(layer "In9.Cu")
		(net 46)
	)
	(segment
		(start 144.875 177.8005)
		(end 144.3745 177.3)
		(width 0.1)
		(layer "In9.Cu")
		(net 46)
	)
	(segment
		(start 94.525 186.4)
		(end 94.525 185.775)
		(width 0.1)
		(layer "In9.Cu")
		(net 46)
	)
	(segment
		(start 97.625 189.5)
		(end 94.525 186.4)
		(width 0.1)
		(layer "In9.Cu")
		(net 46)
	)
	(segment
		(start 134.4 177.5)
		(end 134.4 188.3)
		(width 0.1)
		(layer "In9.Cu")
		(net 46)
	)
	(segment
		(start 132.8 189.09717)
		(end 132.8 191.4)
		(width 0.1)
		(layer "In9.Cu")
		(net 46)
	)
	(segment
		(start 144.3745 177.3)
		(end 134.6 177.3)
		(width 0.1)
		(layer "In9.Cu")
		(net 46)
	)
	(segment
		(start 134.2 188.5)
		(end 133.39717 188.5)
		(width 0.1)
		(layer "In9.Cu")
		(net 46)
	)
	(segment
		(start 133.39717 188.5)
		(end 132.8 189.09717)
		(width 0.1)
		(layer "In9.Cu")
		(net 46)
	)
	(segment
		(start 134.4 188.3)
		(end 134.2 188.5)
		(width 0.1)
		(layer "In9.Cu")
		(net 46)
	)
	(segment
		(start 105.1 193.1)
		(end 101.5 189.5)
		(width 0.1)
		(layer "In9.Cu")
		(net 46)
	)
	(segment
		(start 131.1 193.1)
		(end 105.1 193.1)
		(width 0.1)
		(layer "In9.Cu")
		(net 46)
	)
	(segment
		(start 145.375501 173.302)
		(end 145.875001 172.8025)
		(width 0.256)
		(layer "F.Cu")
		(net 47)
	)
	(segment
		(start 164 173.7)
		(end 164.002 173.702)
		(width 0.256)
		(layer "F.Cu")
		(net 47)
	)
	(segment
		(start 166.003002 173.702)
		(end 165.487 173.702)
		(width 0.256)
		(layer "F.Cu")
		(net 47)
	)
	(segment
		(start 166.701002 174.4)
		(end 168.67 174.4)
		(width 0.256)
		(layer "F.Cu")
		(net 47)
	)
	(segment
		(start 164.715 173.702)
		(end 165.487 173.702)
		(width 0.256)
		(layer "F.Cu")
		(net 47)
	)
	(segment
		(start 166.003002 173.702)
		(end 166.701002 174.4)
		(width 0.256)
		(layer "F.Cu")
		(net 47)
	)
	(segment
		(start 92.3 185.085)
		(end 92.3 185.775)
		(width 0.15)
		(layer "F.Cu")
		(net 47)
	)
	(segment
		(start 164.002 173.702)
		(end 164.715 173.702)
		(width 0.256)
		(layer "F.Cu")
		(net 47)
	)
	(via
		(at 92.3 185.775)
		(size 0.45)
		(drill 0.1)
		(layers "F.Cu" "B.Cu")
		(net 47)
	)
	(via
		(at 145.875001 172.8025)
		(size 0.45)
		(drill 0.1)
		(layers "F.Cu" "B.Cu")
		(net 47)
	)
	(via
		(at 164 173.7)
		(size 0.45)
		(drill 0.1)
		(layers "F.Cu" "B.Cu")
		(net 47)
	)
	(segment
		(start 92.3 186.9)
		(end 92.5 187.1)
		(width 0.15)
		(layer "B.Cu")
		(net 47)
	)
	(segment
		(start 92.3 185.775)
		(end 92.3 186.9)
		(width 0.15)
		(layer "B.Cu")
		(net 47)
	)
	(segment
		(start 92.5 187.1)
		(end 92.5 188.275)
		(width 0.15)
		(layer "B.Cu")
		(net 47)
	)
	(segment
		(start 147.550501 175.251)
		(end 146.450501 174.151)
		(width 0.1)
		(layer "In4.Cu")
		(net 47)
	)
	(segment
		(start 146.450501 173.378)
		(end 145.875001 172.8025)
		(width 0.1)
		(layer "In4.Cu")
		(net 47)
	)
	(segment
		(start 161.349 175.251)
		(end 147.550501 175.251)
		(width 0.1)
		(layer "In4.Cu")
		(net 47)
	)
	(segment
		(start 162.9 173.7)
		(end 161.349 175.251)
		(width 0.1)
		(layer "In4.Cu")
		(net 47)
	)
	(segment
		(start 146.450501 174.151)
		(end 146.450501 173.378)
		(width 0.1)
		(layer "In4.Cu")
		(net 47)
	)
	(segment
		(start 164 173.7)
		(end 162.9 173.7)
		(width 0.1)
		(layer "In4.Cu")
		(net 47)
	)
	(segment
		(start 145.875001 172.8025)
		(end 145.404501 173.273)
		(width 0.1)
		(layer "In9.Cu")
		(net 47)
	)
	(segment
		(start 96.625 190.1)
		(end 92.3 185.775)
		(width 0.1)
		(layer "In9.Cu")
		(net 47)
	)
	(segment
		(start 135.4 188.2)
		(end 134.7 188.9)
		(width 0.1)
		(layer "In9.Cu")
		(net 47)
	)
	(segment
		(start 103.845501 193.595501)
		(end 100.35 190.1)
		(width 0.1)
		(layer "In9.Cu")
		(net 47)
	)
	(segment
		(start 145.404501 173.273)
		(end 145.404501 178.095499)
		(width 0.1)
		(layer "In9.Cu")
		(net 47)
	)
	(segment
		(start 133.2 189.4)
		(end 133.2 191.665684)
		(width 0.1)
		(layer "In9.Cu")
		(net 47)
	)
	(segment
		(start 131.270183 193.595501)
		(end 103.845501 193.595501)
		(width 0.1)
		(layer "In9.Cu")
		(net 47)
	)
	(segment
		(start 145.2 178.3)
		(end 135.6 178.3)
		(width 0.1)
		(layer "In9.Cu")
		(net 47)
	)
	(segment
		(start 100.35 190.1)
		(end 96.625 190.1)
		(width 0.1)
		(layer "In9.Cu")
		(net 47)
	)
	(segment
		(start 145.404501 178.095499)
		(end 145.2 178.3)
		(width 0.1)
		(layer "In9.Cu")
		(net 47)
	)
	(segment
		(start 133.7 188.9)
		(end 133.2 189.4)
		(width 0.1)
		(layer "In9.Cu")
		(net 47)
	)
	(segment
		(start 134.7 188.9)
		(end 133.7 188.9)
		(width 0.1)
		(layer "In9.Cu")
		(net 47)
	)
	(segment
		(start 135.4 178.5)
		(end 135.4 188.2)
		(width 0.1)
		(layer "In9.Cu")
		(net 47)
	)
	(segment
		(start 133.2 191.665684)
		(end 131.270183 193.595501)
		(width 0.1)
		(layer "In9.Cu")
		(net 47)
	)
	(segment
		(start 135.6 178.3)
		(end 135.4 178.5)
		(width 0.1)
		(layer "In9.Cu")
		(net 47)
	)
	(segment
		(start 167.103 172.401)
		(end 166.302 173.202)
		(width 0.256)
		(layer "F.Cu")
		(net 48)
	)
	(segment
		(start 163.4 173.3)
		(end 163.5 173.2)
		(width 0.256)
		(layer "F.Cu")
		(net 48)
	)
	(segment
		(start 93.422843 185.083328)
		(end 93.422843 185.773328)
		(width 0.15)
		(layer "F.Cu")
		(net 48)
	)
	(segment
		(start 168.67 172.401)
		(end 167.103 172.401)
		(width 0.256)
		(layer "F.Cu")
		(net 48)
	)
	(segment
		(start 166.302 173.202)
		(end 165.487 173.202)
		(width 0.256)
		(layer "F.Cu")
		(net 48)
	)
	(segment
		(start 164.713 173.2)
		(end 164.715 173.202)
		(width 0.256)
		(layer "F.Cu")
		(net 48)
	)
	(segment
		(start 146.375501 173.302)
		(end 146.875001 172.8025)
		(width 0.256)
		(layer "F.Cu")
		(net 48)
	)
	(segment
		(start 163.5 173.2)
		(end 164.713 173.2)
		(width 0.256)
		(layer "F.Cu")
		(net 48)
	)
	(segment
		(start 164.715 173.202)
		(end 165.487 173.202)
		(width 0.256)
		(layer "F.Cu")
		(net 48)
	)
	(via
		(at 93.422843 185.773328)
		(size 0.45)
		(drill 0.1)
		(layers "F.Cu" "B.Cu")
		(net 48)
	)
	(via
		(at 163.4 173.3)
		(size 0.45)
		(drill 0.1)
		(layers "F.Cu" "B.Cu")
		(net 48)
	)
	(via
		(at 146.875001 172.8025)
		(size 0.45)
		(drill 0.1)
		(layers "F.Cu" "B.Cu")
		(net 48)
	)
	(segment
		(start 93.422843 186.697843)
		(end 95 188.275)
		(width 0.15)
		(layer "B.Cu")
		(net 48)
	)
	(segment
		(start 93.422843 185.773328)
		(end 93.422843 186.697843)
		(width 0.15)
		(layer "B.Cu")
		(net 48)
	)
	(segment
		(start 147.86817 174.326)
		(end 147.437001 173.894831)
		(width 0.1)
		(layer "In4.Cu")
		(net 48)
	)
	(segment
		(start 162.5 173.3)
		(end 161.474 174.326)
		(width 0.1)
		(layer "In4.Cu")
		(net 48)
	)
	(segment
		(start 147.437001 173.894831)
		(end 147.437001 173.3645)
		(width 0.1)
		(layer "In4.Cu")
		(net 48)
	)
	(segment
		(start 163.4 173.3)
		(end 162.5 173.3)
		(width 0.1)
		(layer "In4.Cu")
		(net 48)
	)
	(segment
		(start 147.437001 173.3645)
		(end 146.875001 172.8025)
		(width 0.1)
		(layer "In4.Cu")
		(net 48)
	)
	(segment
		(start 161.474 174.326)
		(end 147.86817 174.326)
		(width 0.1)
		(layer "In4.Cu")
		(net 48)
	)
	(segment
		(start 146.365501 173.312)
		(end 146.875001 172.8025)
		(width 0.1)
		(layer "In9.Cu")
		(net 48)
	)
	(segment
		(start 131.026832 194.5)
		(end 133.6 191.926832)
		(width 0.1)
		(layer "In9.Cu")
		(net 48)
	)
	(segment
		(start 136.7 179.3)
		(end 146.05 179.3)
		(width 0.1)
		(layer "In9.Cu")
		(net 48)
	)
	(segment
		(start 146.05 179.3)
		(end 146.365501 178.984499)
		(width 0.1)
		(layer "In9.Cu")
		(net 48)
	)
	(segment
		(start 133.6 189.6)
		(end 133.8 189.4)
		(width 0.1)
		(layer "In9.Cu")
		(net 48)
	)
	(segment
		(start 136.4 179.6)
		(end 136.7 179.3)
		(width 0.1)
		(layer "In9.Cu")
		(net 48)
	)
	(segment
		(start 93.422843 185.773328)
		(end 92.724515 185.075)
		(width 0.1)
		(layer "In9.Cu")
		(net 48)
	)
	(segment
		(start 91.3 185.425)
		(end 91.3 186.425)
		(width 0.1)
		(layer "In9.Cu")
		(net 48)
	)
	(segment
		(start 146.365501 178.984499)
		(end 146.365501 173.312)
		(width 0.1)
		(layer "In9.Cu")
		(net 48)
	)
	(segment
		(start 133.8 189.4)
		(end 134.953916 189.4)
		(width 0.1)
		(layer "In9.Cu")
		(net 48)
	)
	(segment
		(start 95.575 190.7)
		(end 99.05 190.7)
		(width 0.1)
		(layer "In9.Cu")
		(net 48)
	)
	(segment
		(start 99.05 190.7)
		(end 102.85 194.5)
		(width 0.1)
		(layer "In9.Cu")
		(net 48)
	)
	(segment
		(start 91.65 185.075)
		(end 91.3 185.425)
		(width 0.1)
		(layer "In9.Cu")
		(net 48)
	)
	(segment
		(start 136.4 187.953916)
		(end 136.4 179.6)
		(width 0.1)
		(layer "In9.Cu")
		(net 48)
	)
	(segment
		(start 92.724515 185.075)
		(end 91.65 185.075)
		(width 0.1)
		(layer "In9.Cu")
		(net 48)
	)
	(segment
		(start 91.3 186.425)
		(end 95.575 190.7)
		(width 0.1)
		(layer "In9.Cu")
		(net 48)
	)
	(segment
		(start 102.85 194.5)
		(end 131.026832 194.5)
		(width 0.1)
		(layer "In9.Cu")
		(net 48)
	)
	(segment
		(start 134.953916 189.4)
		(end 136.4 187.953916)
		(width 0.1)
		(layer "In9.Cu")
		(net 48)
	)
	(segment
		(start 133.6 191.926832)
		(end 133.6 189.6)
		(width 0.1)
		(layer "In9.Cu")
		(net 48)
	)
	(segment
		(start 97.75 136.545)
		(end 97.75 137.15)
		(width 0.256)
		(layer "F.Cu")
		(net 49)
	)
	(segment
		(start 97.75 137.15)
		(end 97.7 137.2)
		(width 0.256)
		(layer "F.Cu")
		(net 49)
	)
	(segment
		(start 106.650001 138.8025)
		(end 106.650001 137.7275)
		(width 0.201)
		(layer "F.Cu")
		(net 49)
	)
	(via
		(at 106.650001 137.7275)
		(size 0.45)
		(drill 0.1)
		(layers "F.Cu" "B.Cu")
		(net 49)
	)
	(via
		(at 97.7 137.2)
		(size 0.45)
		(drill 0.1)
		(layers "F.Cu" "B.Cu")
		(net 49)
	)
	(segment
		(start 100 137.8)
		(end 98.3 137.8)
		(width 0.1)
		(layer "In2.Cu")
		(net 49)
	)
	(segment
		(start 101.514 136.286)
		(end 100 137.8)
		(width 0.1)
		(layer "In2.Cu")
		(net 49)
	)
	(segment
		(start 106.650001 136.8255)
		(end 106.110501 136.286)
		(width 0.1)
		(layer "In2.Cu")
		(net 49)
	)
	(segment
		(start 106.110501 136.286)
		(end 101.514 136.286)
		(width 0.1)
		(layer "In2.Cu")
		(net 49)
	)
	(segment
		(start 106.650001 137.7275)
		(end 106.650001 136.8255)
		(width 0.1)
		(layer "In2.Cu")
		(net 49)
	)
	(segment
		(start 98.3 137.8)
		(end 97.7 137.2)
		(width 0.1)
		(layer "In2.Cu")
		(net 49)
	)
	(segment
		(start 99.6 137.3)
		(end 99.613501 137.313501)
		(width 0.256)
		(layer "F.Cu")
		(net 50)
	)
	(segment
		(start 99.613501 137.313501)
		(end 99.613501 139.428)
		(width 0.256)
		(layer "F.Cu")
		(net 50)
	)
	(segment
		(start 107.150001 138.8025)
		(end 107.150001 139.8775)
		(width 0.201)
		(layer "F.Cu")
		(net 50)
	)
	(segment
		(start 99.8 136.555)
		(end 99.8 137.1)
		(width 0.256)
		(layer "F.Cu")
		(net 50)
	)
	(segment
		(start 99.8 137.1)
		(end 99.6 137.3)
		(width 0.256)
		(layer "F.Cu")
		(net 50)
	)
	(via
		(at 99.6 137.3)
		(size 0.45)
		(drill 0.1)
		(layers "F.Cu" "B.Cu")
		(net 50)
	)
	(via
		(at 107.150001 139.8775)
		(size 0.45)
		(drill 0.1)
		(layers "F.Cu" "B.Cu")
		(net 50)
	)
	(segment
		(start 107.150001 139.8775)
		(end 107.150001 136.475501)
		(width 0.1)
		(layer "In2.Cu")
		(net 50)
	)
	(segment
		(start 99.6 136.75)
		(end 99.6 137.3)
		(width 0.1)
		(layer "In2.Cu")
		(net 50)
	)
	(segment
		(start 107.150001 136.475501)
		(end 106.3405 135.666)
		(width 0.1)
		(layer "In2.Cu")
		(net 50)
	)
	(segment
		(start 100.684 135.666)
		(end 99.6 136.75)
		(width 0.1)
		(layer "In2.Cu")
		(net 50)
	)
	(segment
		(start 106.3405 135.666)
		(end 100.684 135.666)
		(width 0.1)
		(layer "In2.Cu")
		(net 50)
	)
	(segment
		(start 192.195501 178.673)
		(end 194.573001 178.673)
		(width 0.4)
		(layer "F.Cu")
		(net 51)
	)
	(segment
		(start 191.245501 182.223)
		(end 191.245501 179.623)
		(width 0.4)
		(layer "F.Cu")
		(net 51)
	)
	(segment
		(start 191.245501 179.623)
		(end 192.195501 178.673)
		(width 0.4)
		(layer "F.Cu")
		(net 51)
	)
	(segment
		(start 194.573001 178.673)
		(end 195.310501 179.4105)
		(width 0.4)
		(layer "F.Cu")
		(net 51)
	)
	(via
		(at 191.198 179.1)
		(size 0.45)
		(drill 0.1)
		(layers "F.Cu" "B.Cu")
		(net 51)
	)
	(segment
		(start 191.198 179.098)
		(end 191.198 179.1)
		(width 0.15)
		(layer "B.Cu")
		(net 51)
	)
	(segment
		(start 189.1 177)
		(end 191.198 179.098)
		(width 0.15)
		(layer "B.Cu")
		(net 51)
	)
	(segment
		(start 191.168501 168.772)
		(end 191.168501 171.372)
		(width 0.4)
		(layer "F.Cu")
		(net 52)
	)
	(segment
		(start 195.996001 171.8445)
		(end 195.996001 171.722)
		(width 0.4)
		(layer "F.Cu")
		(net 52)
	)
	(segment
		(start 191.168501 171.372)
		(end 192.268501 172.472)
		(width 0.4)
		(layer "F.Cu")
		(net 52)
	)
	(segment
		(start 195.368501 172.472)
		(end 195.996001 171.8445)
		(width 0.4)
		(layer "F.Cu")
		(net 52)
	)
	(segment
		(start 192.268501 172.472)
		(end 195.368501 172.472)
		(width 0.4)
		(layer "F.Cu")
		(net 52)
	)
	(via
		(at 190 168.7)
		(size 0.45)
		(drill 0.1)
		(layers "F.Cu" "B.Cu")
		(net 52)
	)
	(segment
		(start 191 168.7)
		(end 190 168.7)
		(width 0.15)
		(layer "B.Cu")
		(net 52)
	)
	(via
		(at 202.1 162.2)
		(size 0.45)
		(drill 0.1)
		(layers "F.Cu" "B.Cu")
		(net 53)
	)
	(segment
		(start 202.1 162.2)
		(end 201.5 161.6)
		(width 0.15)
		(layer "B.Cu")
		(net 53)
	)
	(segment
		(start 98.962501 137.332501)
		(end 98.78 137.15)
		(width 0.256)
		(layer "F.Cu")
		(net 54)
	)
	(segment
		(start 98.78 137.15)
		(end 98.78 136.555)
		(width 0.256)
		(layer "F.Cu")
		(net 54)
	)
	(segment
		(start 107.650001 138.8025)
		(end 107.650001 137.7275)
		(width 0.201)
		(layer "F.Cu")
		(net 54)
	)
	(segment
		(start 98.962501 137.332501)
		(end 98.962501 139.428)
		(width 0.256)
		(layer "F.Cu")
		(net 54)
	)
	(via
		(at 107.650001 137.7275)
		(size 0.45)
		(drill 0.1)
		(layers "F.Cu" "B.Cu")
		(net 54)
	)
	(via
		(at 98.962501 137.332501)
		(size 0.45)
		(drill 0.1)
		(layers "F.Cu" "B.Cu")
		(net 54)
	)
	(segment
		(start 98.962501 136.687499)
		(end 98.962501 137.332501)
		(width 0.1)
		(layer "In2.Cu")
		(net 54)
	)
	(segment
		(start 100.449499 135.200501)
		(end 98.962501 136.687499)
		(width 0.1)
		(layer "In2.Cu")
		(net 54)
	)
	(segment
		(start 107.575001 136.100501)
		(end 106.675001 135.200501)
		(width 0.1)
		(layer "In2.Cu")
		(net 54)
	)
	(segment
		(start 107.650001 137.7275)
		(end 107.575001 137.6525)
		(width 0.1)
		(layer "In2.Cu")
		(net 54)
	)
	(segment
		(start 107.575001 137.6525)
		(end 107.575001 136.100501)
		(width 0.1)
		(layer "In2.Cu")
		(net 54)
	)
	(segment
		(start 106.675001 135.200501)
		(end 100.449499 135.200501)
		(width 0.1)
		(layer "In2.Cu")
		(net 54)
	)
	(segment
		(start 108.900001 146.2025)
		(end 108.900001 147.2775)
		(width 0.201)
		(layer "F.Cu")
		(net 55)
	)
	(segment
		(start 138.376501 170.302)
		(end 137.877001 169.8025)
		(width 0.256)
		(layer "F.Cu")
		(net 55)
	)
	(via
		(at 137.877001 169.8025)
		(size 0.45)
		(drill 0.1)
		(layers "F.Cu" "B.Cu")
		(net 55)
	)
	(via
		(at 108.900001 147.2775)
		(size 0.45)
		(drill 0.1)
		(layers "F.Cu" "B.Cu")
		(net 55)
	)
	(segment
		(start 109.866212 161.422208)
		(end 109.866213 161.422209)
		(width 0.148)
		(layer "In2.Cu")
		(net 55)
	)
	(segment
		(start 111.216022 163.96147)
		(end 111.216022 163.961471)
		(width 0.148)
		(layer "In2.Cu")
		(net 55)
	)
	(segment
		(start 111.216022 163.961471)
		(end 111.633969 163.543519)
		(width 0.148)
		(layer "In2.Cu")
		(net 55)
	)
	(segment
		(start 108.066251 160.747303)
		(end 108.034052 160.779501)
		(width 0.148)
		(layer "In2.Cu")
		(net 55)
	)
	(segment
		(start 111.987524 163.54352)
		(end 111.987525 163.543521)
		(width 0.148)
		(layer "In2.Cu")
		(net 55)
	)
	(segment
		(start 109.44826 162.547262)
		(end 109.448261 162.547263)
		(width 0.148)
		(layer "In2.Cu")
		(net 55)
	)
	(segment
		(start 136.689362 170.2555)
		(end 137.424001 170.2555)
		(width 0.148)
		(layer "In2.Cu")
		(net 55)
	)
	(segment
		(start 121.973501 174.301)
		(end 133.019139 174.301)
		(width 0.148)
		(layer "In2.Cu")
		(net 55)
	)
	(segment
		(start 110.573316 162.482865)
		(end 110.364342 162.69184)
		(width 0.148)
		(layer "In2.Cu")
		(net 55)
	)
	(segment
		(start 110.364342 162.69184)
		(end 110.36434 162.691839)
		(width 0.148)
		(layer "In2.Cu")
		(net 55)
	)
	(segment
		(start 109.09471 161.840158)
		(end 109.09471 161.840159)
		(width 0.148)
		(layer "In2.Cu")
		(net 55)
	)
	(segment
		(start 108.387605 161.133054)
		(end 108.805553 160.715103)
		(width 0.148)
		(layer "In2.Cu")
		(net 55)
	)
	(segment
		(start 111.071444 163.398943)
		(end 110.862469 163.607917)
		(width 0.148)
		(layer "In2.Cu")
		(net 55)
	)
	(segment
		(start 137.424001 170.2555)
		(end 137.877001 169.8025)
		(width 0.148)
		(layer "In2.Cu")
		(net 55)
	)
	(segment
		(start 111.987524 163.897073)
		(end 111.77855 164.106048)
		(width 0.148)
		(layer "In2.Cu")
		(net 55)
	)
	(segment
		(start 110.508918 163.254367)
		(end 110.926865 162.836415)
		(width 0.148)
		(layer "In2.Cu")
		(net 55)
	)
	(segment
		(start 112.308877 164.636377)
		(end 112.308877 164.636376)
		(width 0.148)
		(layer "In2.Cu")
		(net 55)
	)
	(segment
		(start 110.573316 162.482866)
		(end 110.573316 162.482865)
		(width 0.148)
		(layer "In2.Cu")
		(net 55)
	)
	(segment
		(start 108.06625 160.747303)
		(end 108.066251 160.747303)
		(width 0.148)
		(layer "In2.Cu")
		(net 55)
	)
	(segment
		(start 111.28042 162.836416)
		(end 111.280421 162.836417)
		(width 0.148)
		(layer "In2.Cu")
		(net 55)
	)
	(segment
		(start 135.330001 171.990139)
		(end 135.330001 171.708861)
		(width 0.148)
		(layer "In2.Cu")
		(net 55)
	)
	(segment
		(start 108.900001 147.2775)
		(end 107.5 148.677501)
		(width 0.148)
		(layer "In2.Cu")
		(net 55)
	)
	(segment
		(start 111.987524 163.897074)
		(end 111.987524 163.897073)
		(width 0.148)
		(layer "In2.Cu")
		(net 55)
	)
	(segment
		(start 110.508918 163.254366)
		(end 110.508918 163.254367)
		(width 0.148)
		(layer "In2.Cu")
		(net 55)
	)
	(segment
		(start 108.741156 161.840158)
		(end 108.741157 161.840159)
		(width 0.148)
		(layer "In2.Cu")
		(net 55)
	)
	(segment
		(start 134.678001 172.2555)
		(end 135.06464 172.2555)
		(width 0.148)
		(layer "In2.Cu")
		(net 55)
	)
	(segment
		(start 109.159108 160.715104)
		(end 109.159109 160.715105)
		(width 0.148)
		(layer "In2.Cu")
		(net 55)
	)
	(segment
		(start 110.36434 162.691839)
		(end 110.155365 162.900813)
		(width 0.148)
		(layer "In2.Cu")
		(net 55)
	)
	(segment
		(start 109.801814 162.547262)
		(end 109.801814 162.547263)
		(width 0.148)
		(layer "In2.Cu")
		(net 55)
	)
	(segment
		(start 135.97064 171.3495)
		(end 136.330001 170.990139)
		(width 0.148)
		(layer "In2.Cu")
		(net 55)
	)
	(segment
		(start 112.308877 164.636376)
		(end 121.973501 174.301)
		(width 0.148)
		(layer "In2.Cu")
		(net 55)
	)
	(segment
		(start 109.159108 161.068658)
		(end 109.159108 161.068657)
		(width 0.148)
		(layer "In2.Cu")
		(net 55)
	)
	(segment
		(start 109.657236 161.984735)
		(end 109.448261 162.193709)
		(width 0.148)
		(layer "In2.Cu")
		(net 55)
	)
	(segment
		(start 108.034053 161.133054)
		(end 108.034052 161.133054)
		(width 0.148)
		(layer "In2.Cu")
		(net 55)
	)
	(segment
		(start 110.573316 162.129312)
		(end 110.573317 162.129313)
		(width 0.148)
		(layer "In2.Cu")
		(net 55)
	)
	(segment
		(start 109.159108 161.068657)
		(end 108.950134 161.277632)
		(width 0.148)
		(layer "In2.Cu")
		(net 55)
	)
	(segment
		(start 134.054898 173.265242)
		(end 134.372001 172.948139)
		(width 0.148)
		(layer "In2.Cu")
		(net 55)
	)
	(segment
		(start 134.372001 172.5615)
		(end 134.678001 172.2555)
		(width 0.148)
		(layer "In2.Cu")
		(net 55)
	)
	(segment
		(start 133.337743 173.982397)
		(end 133.337743 173.589758)
		(width 0.148)
		(layer "In2.Cu")
		(net 55)
	)
	(segment
		(start 107.5 159.827499)
		(end 108.066251 160.39375)
		(width 0.148)
		(layer "In2.Cu")
		(net 55)
	)
	(segment
		(start 108.950132 161.277631)
		(end 108.741157 161.486605)
		(width 0.148)
		(layer "In2.Cu")
		(net 55)
	)
	(segment
		(start 109.09471 161.840159)
		(end 109.512657 161.422207)
		(width 0.148)
		(layer "In2.Cu")
		(net 55)
	)
	(segment
		(start 134.372001 172.948139)
		(end 134.372001 172.5615)
		(width 0.148)
		(layer "In2.Cu")
		(net 55)
	)
	(segment
		(start 111.569572 164.668574)
		(end 111.569573 164.668575)
		(width 0.148)
		(layer "In2.Cu")
		(net 55)
	)
	(segment
		(start 135.330001 171.708861)
		(end 135.689362 171.3495)
		(width 0.148)
		(layer "In2.Cu")
		(net 55)
	)
	(segment
		(start 109.866212 161.775761)
		(end 109.657238 161.984736)
		(width 0.148)
		(layer "In2.Cu")
		(net 55)
	)
	(segment
		(start 111.071446 163.398944)
		(end 111.071444 163.398943)
		(width 0.148)
		(layer "In2.Cu")
		(net 55)
	)
	(segment
		(start 133.337743 173.589758)
		(end 133.662259 173.265242)
		(width 0.148)
		(layer "In2.Cu")
		(net 55)
	)
	(segment
		(start 136.330001 170.990139)
		(end 136.330001 170.614861)
		(width 0.148)
		(layer "In2.Cu")
		(net 55)
	)
	(segment
		(start 111.923126 164.668575)
		(end 111.955324 164.636376)
		(width 0.148)
		(layer "In2.Cu")
		(net 55)
	)
	(segment
		(start 109.801814 162.547263)
		(end 110.219761 162.129311)
		(width 0.148)
		(layer "In2.Cu")
		(net 55)
	)
	(segment
		(start 135.689362 171.3495)
		(end 135.97064 171.3495)
		(width 0.148)
		(layer "In2.Cu")
		(net 55)
	)
	(segment
		(start 109.657238 161.984736)
		(end 109.657236 161.984735)
		(width 0.148)
		(layer "In2.Cu")
		(net 55)
	)
	(segment
		(start 133.662259 173.265242)
		(end 134.054898 173.265242)
		(width 0.148)
		(layer "In2.Cu")
		(net 55)
	)
	(segment
		(start 110.155364 163.254366)
		(end 110.155365 163.254367)
		(width 0.148)
		(layer "In2.Cu")
		(net 55)
	)
	(segment
		(start 136.330001 170.614861)
		(end 136.689362 170.2555)
		(width 0.148)
		(layer "In2.Cu")
		(net 55)
	)
	(segment
		(start 111.778548 164.106047)
		(end 111.569573 164.315021)
		(width 0.148)
		(layer "In2.Cu")
		(net 55)
	)
	(segment
		(start 110.862468 163.96147)
		(end 110.862469 163.961471)
		(width 0.148)
		(layer "In2.Cu")
		(net 55)
	)
	(segment
		(start 107.5 148.677501)
		(end 107.5 159.827499)
		(width 0.148)
		(layer "In2.Cu")
		(net 55)
	)
	(segment
		(start 108.387605 161.133053)
		(end 108.387605 161.133054)
		(width 0.148)
		(layer "In2.Cu")
		(net 55)
	)
	(segment
		(start 135.06464 172.2555)
		(end 135.330001 171.990139)
		(width 0.148)
		(layer "In2.Cu")
		(net 55)
	)
	(segment
		(start 108.950134 161.277632)
		(end 108.950132 161.277631)
		(width 0.148)
		(layer "In2.Cu")
		(net 55)
	)
	(segment
		(start 111.923126 164.668574)
		(end 111.923126 164.668575)
		(width 0.148)
		(layer "In2.Cu")
		(net 55)
	)
	(segment
		(start 111.77855 164.106048)
		(end 111.778548 164.106047)
		(width 0.148)
		(layer "In2.Cu")
		(net 55)
	)
	(segment
		(start 111.28042 163.18997)
		(end 111.28042 163.189969)
		(width 0.148)
		(layer "In2.Cu")
		(net 55)
	)
	(segment
		(start 111.28042 163.189969)
		(end 111.071446 163.398944)
		(width 0.148)
		(layer "In2.Cu")
		(net 55)
	)
	(segment
		(start 109.866212 161.775762)
		(end 109.866212 161.775761)
		(width 0.148)
		(layer "In2.Cu")
		(net 55)
	)
	(segment
		(start 133.019139 174.301)
		(end 133.337743 173.982397)
		(width 0.148)
		(layer "In2.Cu")
		(net 55)
	)
	(arc
		(start 110.862469 163.607917)
		(mid 110.789245 163.784693)
		(end 110.862468 163.96147)
		(width 0.148)
		(layer "In2.Cu")
		(net 55)
	)
	(arc
		(start 109.159109 160.715105)
		(mid 109.232332 160.891882)
		(end 109.159108 161.068658)
		(width 0.148)
		(layer "In2.Cu")
		(net 55)
	)
	(arc
		(start 109.512657 161.422207)
		(mid 109.689435 161.348985)
		(end 109.866212 161.422208)
		(width 0.148)
		(layer "In2.Cu")
		(net 55)
	)
	(arc
		(start 111.987525 163.543521)
		(mid 112.060748 163.720298)
		(end 111.987524 163.897074)
		(width 0.148)
		(layer "In2.Cu")
		(net 55)
	)
	(arc
		(start 111.280421 162.836417)
		(mid 111.353644 163.013194)
		(end 111.28042 163.18997)
		(width 0.148)
		(layer "In2.Cu")
		(net 55)
	)
	(arc
		(start 110.155365 162.900813)
		(mid 110.082141 163.077589)
		(end 110.155364 163.254366)
		(width 0.148)
		(layer "In2.Cu")
		(net 55)
	)
	(arc
		(start 109.866213 161.422209)
		(mid 109.939436 161.598986)
		(end 109.866212 161.775762)
		(width 0.148)
		(layer "In2.Cu")
		(net 55)
	)
	(arc
		(start 108.741157 161.486605)
		(mid 108.667933 161.663381)
		(end 108.741156 161.840158)
		(width 0.148)
		(layer "In2.Cu")
		(net 55)
	)
	(arc
		(start 111.633969 163.543519)
		(mid 111.810747 163.470297)
		(end 111.987524 163.54352)
		(width 0.148)
		(layer "In2.Cu")
		(net 55)
	)
	(arc
		(start 109.448261 162.547263)
		(mid 109.625038 162.620486)
		(end 109.801814 162.547262)
		(width 0.148)
		(layer "In2.Cu")
		(net 55)
	)
	(arc
		(start 110.219761 162.129311)
		(mid 110.396539 162.056089)
		(end 110.573316 162.129312)
		(width 0.148)
		(layer "In2.Cu")
		(net 55)
	)
	(arc
		(start 108.741157 161.840159)
		(mid 108.917934 161.913382)
		(end 109.09471 161.840158)
		(width 0.148)
		(layer "In2.Cu")
		(net 55)
	)
	(arc
		(start 110.862469 163.961471)
		(mid 111.039246 164.034694)
		(end 111.216022 163.96147)
		(width 0.148)
		(layer "In2.Cu")
		(net 55)
	)
	(arc
		(start 111.569573 164.315021)
		(mid 111.496349 164.491797)
		(end 111.569572 164.668574)
		(width 0.148)
		(layer "In2.Cu")
		(net 55)
	)
	(arc
		(start 108.066251 160.39375)
		(mid 108.139474 160.570527)
		(end 108.06625 160.747303)
		(width 0.148)
		(layer "In2.Cu")
		(net 55)
	)
	(arc
		(start 110.926865 162.836415)
		(mid 111.103643 162.763193)
		(end 111.28042 162.836416)
		(width 0.148)
		(layer "In2.Cu")
		(net 55)
	)
	(arc
		(start 109.448261 162.193709)
		(mid 109.375037 162.370485)
		(end 109.44826 162.547262)
		(width 0.148)
		(layer "In2.Cu")
		(net 55)
	)
	(arc
		(start 111.955324 164.636376)
		(mid 112.132101 164.563153)
		(end 112.308877 164.636377)
		(width 0.148)
		(layer "In2.Cu")
		(net 55)
	)
	(arc
		(start 111.569573 164.668575)
		(mid 111.74635 164.741798)
		(end 111.923126 164.668574)
		(width 0.148)
		(layer "In2.Cu")
		(net 55)
	)
	(arc
		(start 110.155365 163.254367)
		(mid 110.332142 163.32759)
		(end 110.508918 163.254366)
		(width 0.148)
		(layer "In2.Cu")
		(net 55)
	)
	(arc
		(start 110.573317 162.129313)
		(mid 110.64654 162.30609)
		(end 110.573316 162.482866)
		(width 0.148)
		(layer "In2.Cu")
		(net 55)
	)
	(arc
		(start 108.034052 161.133054)
		(mid 108.210829 161.206277)
		(end 108.387605 161.133053)
		(width 0.148)
		(layer "In2.Cu")
		(net 55)
	)
	(arc
		(start 108.034052 160.779501)
		(mid 107.960829 160.956278)
		(end 108.034053 161.133054)
		(width 0.148)
		(layer "In2.Cu")
		(net 55)
	)
	(arc
		(start 108.805553 160.715103)
		(mid 108.982331 160.641881)
		(end 109.159108 160.715104)
		(width 0.148)
		(layer "In2.Cu")
		(net 55)
	)
	(via
		(at 202 174.2)
		(size 0.45)
		(drill 0.1)
		(layers "F.Cu" "B.Cu")
		(net 56)
	)
	(segment
		(start 202 174.2)
		(end 202.6 174.8)
		(width 0.15)
		(layer "B.Cu")
		(net 56)
	)
	(segment
		(start 136.376501 170.302)
		(end 135.877002 169.8025)
		(width 0.256)
		(layer "F.Cu")
		(net 57)
	)
	(segment
		(start 109.150001 138.8025)
		(end 109.150001 139.8775)
		(width 0.201)
		(layer "F.Cu")
		(net 57)
	)
	(via
		(at 135.877002 169.8025)
		(size 0.45)
		(drill 0.1)
		(layers "F.Cu" "B.Cu")
		(net 57)
	)
	(via
		(at 109.150001 139.8775)
		(size 0.45)
		(drill 0.1)
		(layers "F.Cu" "B.Cu")
		(net 57)
	)
	(segment
		(start 109.150001 140.849999)
		(end 108.850001 141.149999)
		(width 0.148)
		(layer "In2.Cu")
		(net 57)
	)
	(segment
		(start 108.850001 146.0775)
		(end 109.400501 146.628)
		(width 0.148)
		(layer "In2.Cu")
		(net 57)
	)
	(segment
		(start 133.001273 173.2425)
		(end 133.276001 172.967772)
		(width 0.148)
		(layer "In2.Cu")
		(net 57)
	)
	(segment
		(start 108.25 159.25)
		(end 122.2425 173.2425)
		(width 0.148)
		(layer "In2.Cu")
		(net 57)
	)
	(segment
		(start 109.400501 147.676)
		(end 108.25 148.826501)
		(width 0.148)
		(layer "In2.Cu")
		(net 57)
	)
	(segment
		(start 134.891273 171.3525)
		(end 135.276001 170.967772)
		(width 0.148)
		(layer "In2.Cu")
		(net 57)
	)
	(segment
		(start 108.850001 141.149999)
		(end 108.850001 146.0775)
		(width 0.148)
		(layer "In2.Cu")
		(net 57)
	)
	(segment
		(start 135.276001 170.967772)
		(end 135.276001 170.403501)
		(width 0.148)
		(layer "In2.Cu")
		(net 57)
	)
	(segment
		(start 122.2425 173.2425)
		(end 133.001273 173.2425)
		(width 0.148)
		(layer "In2.Cu")
		(net 57)
	)
	(segment
		(start 134.575001 171.3525)
		(end 134.891273 171.3525)
		(width 0.148)
		(layer "In2.Cu")
		(net 57)
	)
	(segment
		(start 134.276001 171.967773)
		(end 134.276001 171.6515)
		(width 0.148)
		(layer "In2.Cu")
		(net 57)
	)
	(segment
		(start 134.276001 171.6515)
		(end 134.575001 171.3525)
		(width 0.148)
		(layer "In2.Cu")
		(net 57)
	)
	(segment
		(start 108.25 148.826501)
		(end 108.25 159.25)
		(width 0.148)
		(layer "In2.Cu")
		(net 57)
	)
	(segment
		(start 109.400501 146.628)
		(end 109.400501 147.676)
		(width 0.148)
		(layer "In2.Cu")
		(net 57)
	)
	(segment
		(start 134.042273 172.201501)
		(end 134.276001 171.967773)
		(width 0.148)
		(layer "In2.Cu")
		(net 57)
	)
	(segment
		(start 109.150001 139.8775)
		(end 109.150001 140.849999)
		(width 0.148)
		(layer "In2.Cu")
		(net 57)
	)
	(segment
		(start 133.776 172.201501)
		(end 134.042273 172.201501)
		(width 0.148)
		(layer "In2.Cu")
		(net 57)
	)
	(segment
		(start 135.276001 170.403501)
		(end 135.877002 169.8025)
		(width 0.148)
		(layer "In2.Cu")
		(net 57)
	)
	(segment
		(start 133.276001 172.967772)
		(end 133.276001 172.7015)
		(width 0.148)
		(layer "In2.Cu")
		(net 57)
	)
	(segment
		(start 133.276001 172.7015)
		(end 133.776 172.201501)
		(width 0.148)
		(layer "In2.Cu")
		(net 57)
	)
	(via
		(at 201.38 189.5)
		(size 0.45)
		(drill 0.1)
		(layers "F.Cu" "B.Cu")
		(net 58)
	)
	(segment
		(start 201.38 189.5)
		(end 200.4 189.5)
		(width 0.15)
		(layer "B.Cu")
		(net 58)
	)
	(segment
		(start 135.376501 170.302)
		(end 134.877001 169.8025)
		(width 0.256)
		(layer "F.Cu")
		(net 59)
	)
	(segment
		(start 109.900001 146.2025)
		(end 109.900001 147.2775)
		(width 0.201)
		(layer "F.Cu")
		(net 59)
	)
	(via
		(at 109.900001 147.2775)
		(size 0.45)
		(drill 0.1)
		(layers "F.Cu" "B.Cu")
		(net 59)
	)
	(via
		(at 134.877001 169.8025)
		(size 0.45)
		(drill 0.1)
		(layers "F.Cu" "B.Cu")
		(net 59)
	)
	(segment
		(start 110.19262 160.325145)
		(end 110.575143 159.942618)
		(width 0.148)
		(layer "In2.Cu")
		(net 59)
	)
	(segment
		(start 113.72814 163.860664)
		(end 113.72814 163.860665)
		(width 0.148)
		(layer "In2.Cu")
		(net 59)
	)
	(segment
		(start 133.017501 172.26)
		(end 133.39 171.887501)
		(width 0.148)
		(layer "In2.Cu")
		(net 59)
	)
	(segment
		(start 110.221591 159.589067)
		(end 110.221593 159.589068)
		(width 0.148)
		(layer "In2.Cu")
		(net 59)
	)
	(segment
		(start 112.342904 161.71038)
		(end 112.342906 161.710381)
		(width 0.148)
		(layer "In2.Cu")
		(net 59)
	)
	(segment
		(start 111.606828 161.739353)
		(end 111.989351 161.356826)
		(width 0.148)
		(layer "In2.Cu")
		(net 59)
	)
	(segment
		(start 113.374587 163.860666)
		(end 113.374587 163.860665)
		(width 0.148)
		(layer "In2.Cu")
		(net 59)
	)
	(segment
		(start 110.207106 159.603552)
		(end 109.839067 159.971592)
		(width 0.148)
		(layer "In2.Cu")
		(net 59)
	)
	(segment
		(start 110.899724 161.032249)
		(end 111.282247 160.649722)
		(width 0.148)
		(layer "In2.Cu")
		(net 59)
	)
	(segment
		(start 113.021036 163.15356)
		(end 113.021036 163.153561)
		(width 0.148)
		(layer "In2.Cu")
		(net 59)
	)
	(segment
		(start 110.221593 159.589068)
		(end 110.207106 159.603552)
		(width 0.148)
		(layer "In2.Cu")
		(net 59)
	)
	(segment
		(start 109 149.026501)
		(end 109 158.75)
		(width 0.148)
		(layer "In2.Cu")
		(net 59)
	)
	(segment
		(start 114.464218 163.831693)
		(end 114.449731 163.846177)
		(width 0.148)
		(layer "In2.Cu")
		(net 59)
	)
	(segment
		(start 113.050011 162.063932)
		(end 113.050009 162.063931)
		(width 0.148)
		(layer "In2.Cu")
		(net 59)
	)
	(segment
		(start 112.667483 163.153562)
		(end 112.667483 163.153561)
		(width 0.148)
		(layer "In2.Cu")
		(net 59)
	)
	(segment
		(start 112.313932 162.446457)
		(end 112.696455 162.06393)
		(width 0.148)
		(layer "In2.Cu")
		(net 59)
	)
	(segment
		(start 111.960379 162.446458)
		(end 111.960379 162.446457)
		(width 0.148)
		(layer "In2.Cu")
		(net 59)
	)
	(segment
		(start 112.342907 161.356828)
		(end 112.342905 161.356827)
		(width 0.148)
		(layer "In2.Cu")
		(net 59)
	)
	(segment
		(start 134.41 170.84)
		(end 134.41 170.269501)
		(width 0.148)
		(layer "In2.Cu")
		(net 59)
	)
	(segment
		(start 110.928696 160.296172)
		(end 110.928698 160.296173)
		(width 0.148)
		(layer "In2.Cu")
		(net 59)
	)
	(segment
		(start 111.635803 160.649724)
		(end 111.635801 160.649723)
		(width 0.148)
		(layer "In2.Cu")
		(net 59)
	)
	(segment
		(start 114.464219 163.47814)
		(end 114.464217 163.478139)
		(width 0.148)
		(layer "In2.Cu")
		(net 59)
	)
	(segment
		(start 111.6358 161.003276)
		(end 111.635802 161.003277)
		(width 0.148)
		(layer "In2.Cu")
		(net 59)
	)
	(segment
		(start 109 158.75)
		(end 109.5 159.25)
		(width 0.148)
		(layer "In2.Cu")
		(net 59)
	)
	(segment
		(start 113.757114 163.124589)
		(end 113.374587 163.507112)
		(width 0.148)
		(layer "In2.Cu")
		(net 59)
	)
	(segment
		(start 113.757112 163.124588)
		(end 113.757114 163.124589)
		(width 0.148)
		(layer "In2.Cu")
		(net 59)
	)
	(segment
		(start 114.449731 164.199731)
		(end 122.51 172.26)
		(width 0.148)
		(layer "In2.Cu")
		(net 59)
	)
	(segment
		(start 110.928699 159.94262)
		(end 110.928697 159.942619)
		(width 0.148)
		(layer "In2.Cu")
		(net 59)
	)
	(segment
		(start 109.900001 147.2775)
		(end 109.900001 148.1265)
		(width 0.148)
		(layer "In2.Cu")
		(net 59)
	)
	(segment
		(start 134.41 170.269501)
		(end 134.877001 169.8025)
		(width 0.148)
		(layer "In2.Cu")
		(net 59)
	)
	(segment
		(start 133.39 171.887501)
		(end 133.39 171.59)
		(width 0.148)
		(layer "In2.Cu")
		(net 59)
	)
	(segment
		(start 133.95 171.3)
		(end 134.41 170.84)
		(width 0.148)
		(layer "In2.Cu")
		(net 59)
	)
	(segment
		(start 113.72814 163.860665)
		(end 114.110663 163.478138)
		(width 0.148)
		(layer "In2.Cu")
		(net 59)
	)
	(segment
		(start 114.464216 163.831692)
		(end 114.464218 163.831693)
		(width 0.148)
		(layer "In2.Cu")
		(net 59)
	)
	(segment
		(start 113.05001 162.417485)
		(end 112.667483 162.800008)
		(width 0.148)
		(layer "In2.Cu")
		(net 59)
	)
	(segment
		(start 113.757115 162.771036)
		(end 113.757113 162.771035)
		(width 0.148)
		(layer "In2.Cu")
		(net 59)
	)
	(segment
		(start 113.050008 162.417484)
		(end 113.05001 162.417485)
		(width 0.148)
		(layer "In2.Cu")
		(net 59)
	)
	(segment
		(start 112.342906 161.710381)
		(end 111.960379 162.092904)
		(width 0.148)
		(layer "In2.Cu")
		(net 59)
	)
	(segment
		(start 122.51 172.26)
		(end 133.017501 172.26)
		(width 0.148)
		(layer "In2.Cu")
		(net 59)
	)
	(segment
		(start 109.900001 148.1265)
		(end 109 149.026501)
		(width 0.148)
		(layer "In2.Cu")
		(net 59)
	)
	(segment
		(start 110.928698 160.296173)
		(end 110.546171 160.678696)
		(width 0.148)
		(layer "In2.Cu")
		(net 59)
	)
	(segment
		(start 110.546171 161.03225)
		(end 110.546171 161.032249)
		(width 0.148)
		(layer "In2.Cu")
		(net 59)
	)
	(segment
		(start 111.606828 161.739352)
		(end 111.606828 161.739353)
		(width 0.148)
		(layer "In2.Cu")
		(net 59)
	)
	(segment
		(start 109.853553 159.249999)
		(end 109.853554 159.250001)
		(width 0.148)
		(layer "In2.Cu")
		(net 59)
	)
	(segment
		(start 113.021036 163.153561)
		(end 113.403559 162.771034)
		(width 0.148)
		(layer "In2.Cu")
		(net 59)
	)
	(segment
		(start 109.853554 159.250001)
		(end 109.868038 159.235514)
		(width 0.148)
		(layer "In2.Cu")
		(net 59)
	)
	(segment
		(start 114.44973 164.19973)
		(end 114.449731 164.199731)
		(width 0.148)
		(layer "In2.Cu")
		(net 59)
	)
	(segment
		(start 111.253275 161.739354)
		(end 111.253275 161.739353)
		(width 0.148)
		(layer "In2.Cu")
		(net 59)
	)
	(segment
		(start 110.19262 160.325144)
		(end 110.19262 160.325145)
		(width 0.148)
		(layer "In2.Cu")
		(net 59)
	)
	(segment
		(start 110.221591 159.235513)
		(end 110.221592 159.235514)
		(width 0.148)
		(layer "In2.Cu")
		(net 59)
	)
	(segment
		(start 112.313932 162.446456)
		(end 112.313932 162.446457)
		(width 0.148)
		(layer "In2.Cu")
		(net 59)
	)
	(segment
		(start 110.899724 161.032248)
		(end 110.899724 161.032249)
		(width 0.148)
		(layer "In2.Cu")
		(net 59)
	)
	(segment
		(start 111.635802 161.003277)
		(end 111.253275 161.3858)
		(width 0.148)
		(layer "In2.Cu")
		(net 59)
	)
	(segment
		(start 133.39 171.59)
		(end 133.68 171.3)
		(width 0.148)
		(layer "In2.Cu")
		(net 59)
	)
	(segment
		(start 109.839067 160.325146)
		(end 109.839067 160.325145)
		(width 0.148)
		(layer "In2.Cu")
		(net 59)
	)
	(segment
		(start 133.68 171.3)
		(end 133.95 171.3)
		(width 0.148)
		(layer "In2.Cu")
		(net 59)
	)
	(arc
		(start 110.575143 159.942618)
		(mid 110.751922 159.869397)
		(end 110.928699 159.94262)
		(width 0.148)
		(layer "In2.Cu")
		(net 59)
	)
	(arc
		(start 110.546171 160.678696)
		(mid 110.472948 160.855473)
		(end 110.546171 161.03225)
		(width 0.148)
		(layer "In2.Cu")
		(net 59)
	)
	(arc
		(start 111.960379 162.446457)
		(mid 112.137156 162.51968)
		(end 112.313932 162.446456)
		(width 0.148)
		(layer "In2.Cu")
		(net 59)
	)
	(arc
		(start 111.253275 161.3858)
		(mid 111.180052 161.562577)
		(end 111.253275 161.739354)
		(width 0.148)
		(layer "In2.Cu")
		(net 59)
	)
	(arc
		(start 113.403559 162.771034)
		(mid 113.580338 162.697813)
		(end 113.757115 162.771036)
		(width 0.148)
		(layer "In2.Cu")
		(net 59)
	)
	(arc
		(start 114.464217 163.478139)
		(mid 114.53744 163.654916)
		(end 114.464216 163.831692)
		(width 0.148)
		(layer "In2.Cu")
		(net 59)
	)
	(arc
		(start 113.374587 163.860665)
		(mid 113.551364 163.933888)
		(end 113.72814 163.860664)
		(width 0.148)
		(layer "In2.Cu")
		(net 59)
	)
	(arc
		(start 114.110663 163.478138)
		(mid 114.287442 163.404917)
		(end 114.464219 163.47814)
		(width 0.148)
		(layer "In2.Cu")
		(net 59)
	)
	(arc
		(start 111.282247 160.649722)
		(mid 111.459026 160.576501)
		(end 111.635803 160.649724)
		(width 0.148)
		(layer "In2.Cu")
		(net 59)
	)
	(arc
		(start 112.667483 163.153561)
		(mid 112.84426 163.226784)
		(end 113.021036 163.15356)
		(width 0.148)
		(layer "In2.Cu")
		(net 59)
	)
	(arc
		(start 113.050009 162.063931)
		(mid 113.123232 162.240708)
		(end 113.050008 162.417484)
		(width 0.148)
		(layer "In2.Cu")
		(net 59)
	)
	(arc
		(start 112.342905 161.356827)
		(mid 112.416128 161.533604)
		(end 112.342904 161.71038)
		(width 0.148)
		(layer "In2.Cu")
		(net 59)
	)
	(arc
		(start 113.374587 163.507112)
		(mid 113.301364 163.683889)
		(end 113.374587 163.860666)
		(width 0.148)
		(layer "In2.Cu")
		(net 59)
	)
	(arc
		(start 111.989351 161.356826)
		(mid 112.16613 161.283605)
		(end 112.342907 161.356828)
		(width 0.148)
		(layer "In2.Cu")
		(net 59)
	)
	(arc
		(start 111.960379 162.092904)
		(mid 111.887156 162.269681)
		(end 111.960379 162.446458)
		(width 0.148)
		(layer "In2.Cu")
		(net 59)
	)
	(arc
		(start 109.839067 160.325145)
		(mid 110.015844 160.398368)
		(end 110.19262 160.325144)
		(width 0.148)
		(layer "In2.Cu")
		(net 59)
	)
	(arc
		(start 109.5 159.25)
		(mid 109.676777 159.323223)
		(end 109.853553 159.249999)
		(width 0.148)
		(layer "In2.Cu")
		(net 59)
	)
	(arc
		(start 110.221592 159.235514)
		(mid 110.294815 159.412291)
		(end 110.221591 159.589067)
		(width 0.148)
		(layer "In2.Cu")
		(net 59)
	)
	(arc
		(start 112.667483 162.800008)
		(mid 112.59426 162.976785)
		(end 112.667483 163.153562)
		(width 0.148)
		(layer "In2.Cu")
		(net 59)
	)
	(arc
		(start 111.635801 160.649723)
		(mid 111.709024 160.8265)
		(end 111.6358 161.003276)
		(width 0.148)
		(layer "In2.Cu")
		(net 59)
	)
	(arc
		(start 109.868038 159.235514)
		(mid 110.044814 159.16229)
		(end 110.221591 159.235513)
		(width 0.148)
		(layer "In2.Cu")
		(net 59)
	)
	(arc
		(start 110.928697 159.942619)
		(mid 111.00192 160.119396)
		(end 110.928696 160.296172)
		(width 0.148)
		(layer "In2.Cu")
		(net 59)
	)
	(arc
		(start 113.757113 162.771035)
		(mid 113.830336 162.947812)
		(end 113.757112 163.124588)
		(width 0.148)
		(layer "In2.Cu")
		(net 59)
	)
	(arc
		(start 110.546171 161.032249)
		(mid 110.722948 161.105472)
		(end 110.899724 161.032248)
		(width 0.148)
		(layer "In2.Cu")
		(net 59)
	)
	(arc
		(start 109.839067 159.971592)
		(mid 109.765844 160.148369)
		(end 109.839067 160.325146)
		(width 0.148)
		(layer "In2.Cu")
		(net 59)
	)
	(arc
		(start 114.449731 163.846177)
		(mid 114.376507 164.022953)
		(end 114.44973 164.19973)
		(width 0.148)
		(layer "In2.Cu")
		(net 59)
	)
	(arc
		(start 112.696455 162.06393)
		(mid 112.873234 161.990709)
		(end 113.050011 162.063932)
		(width 0.148)
		(layer "In2.Cu")
		(net 59)
	)
	(arc
		(start 111.253275 161.739353)
		(mid 111.430052 161.812576)
		(end 111.606828 161.739352)
		(width 0.148)
		(layer "In2.Cu")
		(net 59)
	)
	(segment
		(start 192.168501 161.172)
		(end 194.646001 161.172)
		(width 0.4)
		(layer "F.Cu")
		(net 60)
	)
	(segment
		(start 194.646001 161.172)
		(end 195.396001 161.922)
		(width 0.4)
		(layer "F.Cu")
		(net 60)
	)
	(segment
		(start 191.168501 162.172)
		(end 192.168501 161.172)
		(width 0.4)
		(layer "F.Cu")
		(net 60)
	)
	(segment
		(start 191.168501 164.772)
		(end 191.168501 162.172)
		(width 0.4)
		(layer "F.Cu")
		(net 60)
	)
	(via
		(at 190 163.4)
		(size 0.45)
		(drill 0.1)
		(layers "F.Cu" "B.Cu")
		(net 60)
	)
	(segment
		(start 190.5 162.5)
		(end 190.5 161.7)
		(width 0.15)
		(layer "B.Cu")
		(net 60)
	)
	(segment
		(start 190 163.4)
		(end 190 163)
		(width 0.15)
		(layer "B.Cu")
		(net 60)
	)
	(segment
		(start 190 163)
		(end 190.5 162.5)
		(width 0.15)
		(layer "B.Cu")
		(net 60)
	)
	(segment
		(start 110.150001 138.8025)
		(end 110.150001 139.8775)
		(width 0.201)
		(layer "F.Cu")
		(net 61)
	)
	(segment
		(start 134.376501 170.302)
		(end 133.877001 169.8025)
		(width 0.256)
		(layer "F.Cu")
		(net 61)
	)
	(via
		(at 110.150001 139.8775)
		(size 0.45)
		(drill 0.1)
		(layers "F.Cu" "B.Cu")
		(net 61)
	)
	(via
		(at 133.877001 169.8025)
		(size 0.45)
		(drill 0.1)
		(layers "F.Cu" "B.Cu")
		(net 61)
	)
	(segment
		(start 119.90466 168.789121)
		(end 119.904661 168.78912)
		(width 0.148)
		(layer "In2.Cu")
		(net 61)
	)
	(segment
		(start 110.150001 140.949999)
		(end 110.150001 139.8775)
		(width 0.148)
		(layer "In2.Cu")
		(net 61)
	)
	(segment
		(start 121.349787 169.465328)
		(end 120.965326 169.849785)
		(width 0.148)
		(layer "In2.Cu")
		(net 61)
	)
	(segment
		(start 119.582009 167.343996)
		(end 119.582008 167.343995)
		(width 0.148)
		(layer "In2.Cu")
		(net 61)
	)
	(segment
		(start 120.611771 169.496232)
		(end 120.611772 169.496231)
		(width 0.148)
		(layer "In2.Cu")
		(net 61)
	)
	(segment
		(start 120.642676 168.758217)
		(end 120.258215 169.142674)
		(width 0.148)
		(layer "In2.Cu")
		(net 61)
	)
	(segment
		(start 119.935565 168.051106)
		(end 119.551104 168.435563)
		(width 0.148)
		(layer "In2.Cu")
		(net 61)
	)
	(segment
		(start 122.394999 170.541447)
		(end 122.395 170.541446)
		(width 0.148)
		(layer "In2.Cu")
		(net 61)
	)
	(segment
		(start 119.228455 167.343994)
		(end 119.228454 167.343995)
		(width 0.148)
		(layer "In2.Cu")
		(net 61)
	)
	(segment
		(start 121.318882 170.203343)
		(end 121.318883 170.203342)
		(width 0.148)
		(layer "In2.Cu")
		(net 61)
	)
	(segment
		(start 132.967773 171.276)
		(end 122.776 171.276)
		(width 0.148)
		(layer "In2.Cu")
		(net 61)
	)
	(segment
		(start 119.228454 167.343995)
		(end 119.213 167.359448)
		(width 0.148)
		(layer "In2.Cu")
		(net 61)
	)
	(segment
		(start 119.197549 168.08201)
		(end 119.19755 168.082009)
		(width 0.148)
		(layer "In2.Cu")
		(net 61)
	)
	(segment
		(start 109.900001 145.9525)
		(end 109.900001 141.199999)
		(width 0.148)
		(layer "In2.Cu")
		(net 61)
	)
	(segment
		(start 109.75 149.026501)
		(end 110.425001 148.3515)
		(width 0.148)
		(layer "In2.Cu")
		(net 61)
	)
	(segment
		(start 121.349788 169.465327)
		(end 121.349787 169.465328)
		(width 0.148)
		(layer "In2.Cu")
		(net 61)
	)
	(segment
		(start 120.611773 169.849786)
		(end 120.611772 169.849785)
		(width 0.148)
		(layer "In2.Cu")
		(net 61)
	)
	(segment
		(start 110.425001 146.4775)
		(end 109.900001 145.9525)
		(width 0.148)
		(layer "In2.Cu")
		(net 61)
	)
	(segment
		(start 119.19755 168.082009)
		(end 119.582008 167.697549)
		(width 0.148)
		(layer "In2.Cu")
		(net 61)
	)
	(segment
		(start 109.75 158.25)
		(end 109.75 149.026501)
		(width 0.148)
		(layer "In2.Cu")
		(net 61)
	)
	(segment
		(start 122.776 171.276)
		(end 122.395 170.895)
		(width 0.148)
		(layer "In2.Cu")
		(net 61)
	)
	(segment
		(start 120.642677 168.758216)
		(end 120.642676 168.758217)
		(width 0.148)
		(layer "In2.Cu")
		(net 61)
	)
	(segment
		(start 133.877001 169.8025)
		(end 133.402001 170.2775)
		(width 0.148)
		(layer "In2.Cu")
		(net 61)
	)
	(segment
		(start 119.904662 169.142675)
		(end 119.904661 169.142674)
		(width 0.148)
		(layer "In2.Cu")
		(net 61)
	)
	(segment
		(start 121.318884 170.556897)
		(end 121.318883 170.556896)
		(width 0.148)
		(layer "In2.Cu")
		(net 61)
	)
	(segment
		(start 133.402001 170.841772)
		(end 132.967773 171.276)
		(width 0.148)
		(layer "In2.Cu")
		(net 61)
	)
	(segment
		(start 122.056899 170.172439)
		(end 121.672437 170.556896)
		(width 0.148)
		(layer "In2.Cu")
		(net 61)
	)
	(segment
		(start 118.859447 167.359448)
		(end 109.75 158.25)
		(width 0.148)
		(layer "In2.Cu")
		(net 61)
	)
	(segment
		(start 118.859447 167.359447)
		(end 118.859447 167.359448)
		(width 0.148)
		(layer "In2.Cu")
		(net 61)
	)
	(segment
		(start 120.611772 169.496231)
		(end 120.99623 169.111771)
		(width 0.148)
		(layer "In2.Cu")
		(net 61)
	)
	(segment
		(start 122.395 170.541446)
		(end 122.410453 170.525992)
		(width 0.148)
		(layer "In2.Cu")
		(net 61)
	)
	(segment
		(start 119.935566 168.051105)
		(end 119.935565 168.051106)
		(width 0.148)
		(layer "In2.Cu")
		(net 61)
	)
	(segment
		(start 122.0569 170.172438)
		(end 122.056899 170.172439)
		(width 0.148)
		(layer "In2.Cu")
		(net 61)
	)
	(segment
		(start 119.904661 168.78912)
		(end 120.289119 168.40466)
		(width 0.148)
		(layer "In2.Cu")
		(net 61)
	)
	(segment
		(start 109.900001 141.199999)
		(end 110.150001 140.949999)
		(width 0.148)
		(layer "In2.Cu")
		(net 61)
	)
	(segment
		(start 121.318883 170.203342)
		(end 121.703341 169.818882)
		(width 0.148)
		(layer "In2.Cu")
		(net 61)
	)
	(segment
		(start 133.402001 170.2775)
		(end 133.402001 170.841772)
		(width 0.148)
		(layer "In2.Cu")
		(net 61)
	)
	(segment
		(start 122.410452 170.172439)
		(end 122.410453 170.172439)
		(width 0.148)
		(layer "In2.Cu")
		(net 61)
	)
	(segment
		(start 119.197551 168.435564)
		(end 119.19755 168.435563)
		(width 0.148)
		(layer "In2.Cu")
		(net 61)
	)
	(segment
		(start 120.28912 168.051107)
		(end 120.289119 168.051106)
		(width 0.148)
		(layer "In2.Cu")
		(net 61)
	)
	(segment
		(start 120.996231 168.758218)
		(end 120.99623 168.758217)
		(width 0.148)
		(layer "In2.Cu")
		(net 61)
	)
	(segment
		(start 110.425001 148.3515)
		(end 110.425001 146.4775)
		(width 0.148)
		(layer "In2.Cu")
		(net 61)
	)
	(segment
		(start 121.703342 169.465329)
		(end 121.703341 169.465328)
		(width 0.148)
		(layer "In2.Cu")
		(net 61)
	)
	(arc
		(start 119.582008 167.697549)
		(mid 119.655232 167.520773)
		(end 119.582009 167.343996)
		(width 0.148)
		(layer "In2.Cu")
		(net 61)
	)
	(arc
		(start 120.611772 169.849785)
		(mid 120.538548 169.673009)
		(end 120.611771 169.496232)
		(width 0.148)
		(layer "In2.Cu")
		(net 61)
	)
	(arc
		(start 121.318883 170.556896)
		(mid 121.245659 170.38012)
		(end 121.318882 170.203343)
		(width 0.148)
		(layer "In2.Cu")
		(net 61)
	)
	(arc
		(start 119.213 167.359448)
		(mid 119.036223 167.432671)
		(end 118.859447 167.359447)
		(width 0.148)
		(layer "In2.Cu")
		(net 61)
	)
	(arc
		(start 119.19755 168.435563)
		(mid 119.124326 168.258787)
		(end 119.197549 168.08201)
		(width 0.148)
		(layer "In2.Cu")
		(net 61)
	)
	(arc
		(start 120.289119 168.40466)
		(mid 120.362343 168.227884)
		(end 120.28912 168.051107)
		(width 0.148)
		(layer "In2.Cu")
		(net 61)
	)
	(arc
		(start 122.410453 170.172439)
		(mid 122.233677 170.099215)
		(end 122.0569 170.172438)
		(width 0.148)
		(layer "In2.Cu")
		(net 61)
	)
	(arc
		(start 122.410453 170.525992)
		(mid 122.483676 170.349215)
		(end 122.410452 170.172439)
		(width 0.148)
		(layer "In2.Cu")
		(net 61)
	)
	(arc
		(start 120.99623 169.111771)
		(mid 121.069454 168.934995)
		(end 120.996231 168.758218)
		(width 0.148)
		(layer "In2.Cu")
		(net 61)
	)
	(arc
		(start 121.703341 169.818882)
		(mid 121.776565 169.642106)
		(end 121.703342 169.465329)
		(width 0.148)
		(layer "In2.Cu")
		(net 61)
	)
	(arc
		(start 119.582008 167.343995)
		(mid 119.405232 167.270771)
		(end 119.228455 167.343994)
		(width 0.148)
		(layer "In2.Cu")
		(net 61)
	)
	(arc
		(start 119.551104 168.435563)
		(mid 119.374328 168.508787)
		(end 119.197551 168.435564)
		(width 0.148)
		(layer "In2.Cu")
		(net 61)
	)
	(arc
		(start 119.904661 169.142674)
		(mid 119.831437 168.965898)
		(end 119.90466 168.789121)
		(width 0.148)
		(layer "In2.Cu")
		(net 61)
	)
	(arc
		(start 120.99623 168.758217)
		(mid 120.819454 168.684993)
		(end 120.642677 168.758216)
		(width 0.148)
		(layer "In2.Cu")
		(net 61)
	)
	(arc
		(start 121.672437 170.556896)
		(mid 121.495661 170.63012)
		(end 121.318884 170.556897)
		(width 0.148)
		(layer "In2.Cu")
		(net 61)
	)
	(arc
		(start 120.289119 168.051106)
		(mid 120.112343 167.977882)
		(end 119.935566 168.051105)
		(width 0.148)
		(layer "In2.Cu")
		(net 61)
	)
	(arc
		(start 122.395 170.895)
		(mid 122.321776 170.718224)
		(end 122.394999 170.541447)
		(width 0.148)
		(layer "In2.Cu")
		(net 61)
	)
	(arc
		(start 120.258215 169.142674)
		(mid 120.081439 169.215898)
		(end 119.904662 169.142675)
		(width 0.148)
		(layer "In2.Cu")
		(net 61)
	)
	(arc
		(start 120.965326 169.849785)
		(mid 120.78855 169.923009)
		(end 120.611773 169.849786)
		(width 0.148)
		(layer "In2.Cu")
		(net 61)
	)
	(arc
		(start 121.703341 169.465328)
		(mid 121.526565 169.392104)
		(end 121.349788 169.465327)
		(width 0.148)
		(layer "In2.Cu")
		(net 61)
	)
	(segment
		(start 193.7 144.45)
		(end 193.85 144.6)
		(width 0.15)
		(layer "F.Cu")
		(net 62)
	)
	(segment
		(start 198.940499 145.440499)
		(end 198.940499 145.901)
		(width 0.15)
		(layer "F.Cu")
		(net 62)
	)
	(segment
		(start 205.0785 149.8035)
		(end 206.0795 149.8035)
		(width 0.256)
		(layer "F.Cu")
		(net 62)
	)
	(segment
		(start 193.85 144.6)
		(end 198.1 144.6)
		(width 0.15)
		(layer "F.Cu")
		(net 62)
	)
	(segment
		(start 198.937499 145.904)
		(end 197.615 145.904)
		(width 0.256)
		(layer "F.Cu")
		(net 62)
	)
	(segment
		(start 198.1 144.6)
		(end 198.940499 145.440499)
		(width 0.15)
		(layer "F.Cu")
		(net 62)
	)
	(segment
		(start 198.940499 145.901)
		(end 198.937499 145.904)
		(width 0.256)
		(layer "F.Cu")
		(net 62)
	)
	(via
		(at 206.0795 149.8035)
		(size 0.45)
		(drill 0.1)
		(layers "F.Cu" "B.Cu")
		(net 62)
	)
	(via
		(at 198.940499 145.901)
		(size 0.45)
		(drill 0.1)
		(layers "F.Cu" "B.Cu")
		(net 62)
	)
	(segment
		(start 205.85625 149.58025)
		(end 206.0795 149.8035)
		(width 0.15)
		(layer "B.Cu")
		(net 62)
	)
	(segment
		(start 198.840499 145.801)
		(end 198.149 145.801)
		(width 0.256)
		(layer "B.Cu")
		(net 62)
	)
	(segment
		(start 198.940499 145.901)
		(end 202.61975 149.58025)
		(width 0.15)
		(layer "B.Cu")
		(net 62)
	)
	(segment
		(start 198.940499 145.901)
		(end 198.840499 145.801)
		(width 0.256)
		(layer "B.Cu")
		(net 62)
	)
	(segment
		(start 202.61975 149.58025)
		(end 205.85625 149.58025)
		(width 0.15)
		(layer "B.Cu")
		(net 62)
	)
	(segment
		(start 174.720501 193.714503)
		(end 175.150501 193.714503)
		(width 0.177)
		(layer "F.Cu")
		(net 63)
	)
	(segment
		(start 175.665502 193.199502)
		(end 176.070503 193.199503)
		(width 0.177)
		(layer "F.Cu")
		(net 63)
	)
	(segment
		(start 175.150501 193.714503)
		(end 175.665502 193.199502)
		(width 0.177)
		(layer "F.Cu")
		(net 63)
	)
	(segment
		(start 195.65 195.45)
		(end 195.79 195.45)
		(width 0.4)
		(layer "F.Cu")
		(net 64)
	)
	(segment
		(start 195.79 195.45)
		(end 195.79 194.39)
		(width 0.4)
		(layer "F.Cu")
		(net 64)
	)
	(segment
		(start 195.15 194.35)
		(end 195.25 194.25)
		(width 0.4)
		(layer "F.Cu")
		(net 64)
	)
	(segment
		(start 195.65 193.091)
		(end 195.634 193.075)
		(width 0.4)
		(layer "F.Cu")
		(net 64)
	)
	(segment
		(start 195.634 193.075)
		(end 195.634 191.724)
		(width 0.4)
		(layer "F.Cu")
		(net 64)
	)
	(segment
		(start 195.15 195.35)
		(end 195.25 195.45)
		(width 0.4)
		(layer "F.Cu")
		(net 64)
	)
	(segment
		(start 195.79 194.39)
		(end 195.65 194.25)
		(width 0.4)
		(layer "F.Cu")
		(net 64)
	)
	(segment
		(start 196.033 191.325)
		(end 197.501 191.325)
		(width 0.4)
		(layer "F.Cu")
		(net 64)
	)
	(segment
		(start 195.25 195.45)
		(end 195.65 195.45)
		(width 0.4)
		(layer "F.Cu")
		(net 64)
	)
	(segment
		(start 195.25 194.25)
		(end 195.65 194.25)
		(width 0.4)
		(layer "F.Cu")
		(net 64)
	)
	(segment
		(start 195.634 191.724)
		(end 196.033 191.325)
		(width 0.4)
		(layer "F.Cu")
		(net 64)
	)
	(segment
		(start 195.65 194.25)
		(end 195.65 193.091)
		(width 0.4)
		(layer "F.Cu")
		(net 64)
	)
	(via
		(at 195.65 194.25)
		(size 0.45)
		(drill 0.1)
		(layers "F.Cu" "B.Cu")
		(net 64)
	)
	(via
		(at 195.65 195.45)
		(size 0.45)
		(drill 0.1)
		(layers "F.Cu" "B.Cu")
		(net 64)
	)
	(via
		(at 189.3 190.6)
		(size 0.45)
		(drill 0.1)
		(layers "F.Cu" "B.Cu")
		(net 64)
	)
	(segment
		(start 189.3 190.6)
		(end 186.4 190.6)
		(width 0.15)
		(layer "B.Cu")
		(net 64)
	)
	(segment
		(start 110.900001 146.2025)
		(end 110.900001 147.2775)
		(width 0.201)
		(layer "F.Cu")
		(net 65)
	)
	(segment
		(start 133.376501 170.302)
		(end 132.877001 169.8025)
		(width 0.256)
		(layer "F.Cu")
		(net 65)
	)
	(via
		(at 110.900001 147.2775)
		(size 0.45)
		(drill 0.1)
		(layers "F.Cu" "B.Cu")
		(net 65)
	)
	(via
		(at 132.877001 169.8025)
		(size 0.45)
		(drill 0.1)
		(layers "F.Cu" "B.Cu")
		(net 65)
	)
	(segment
		(start 118.231895 165.06611)
		(end 118.231894 165.066111)
		(width 0.148)
		(layer "In2.Cu")
		(net 65)
	)
	(segment
		(start 114.645363 162.288644)
		(end 115.049893 161.884109)
		(width 0.148)
		(layer "In2.Cu")
		(net 65)
	)
	(segment
		(start 116.766695 164.409978)
		(end 116.766696 164.409977)
		(width 0.148)
		(layer "In2.Cu")
		(net 65)
	)
	(segment
		(start 112.92856 159.409222)
		(end 112.92856 159.409223)
		(width 0.148)
		(layer "In2.Cu")
		(net 65)
	)
	(segment
		(start 116.464115 162.944777)
		(end 116.464115 162.944778)
		(width 0.148)
		(layer "In2.Cu")
		(net 65)
	)
	(segment
		(start 115.352472 163.349308)
		(end 115.352474 163.349309)
		(width 0.148)
		(layer "In2.Cu")
		(net 65)
	)
	(segment
		(start 113.231141 160.874422)
		(end 113.635671 160.469887)
		(width 0.148)
		(layer "In2.Cu")
		(net 65)
	)
	(segment
		(start 112.524029 160.167312)
		(end 112.52403 160.167311)
		(width 0.148)
		(layer "In2.Cu")
		(net 65)
	)
	(segment
		(start 118.180918 165.824199)
		(end 118.585448 165.419664)
		(width 0.148)
		(layer "In2.Cu")
		(net 65)
	)
	(segment
		(start 110.5 149.176501)
		(end 110.900001 148.7765)
		(width 0.148)
		(layer "In2.Cu")
		(net 65)
	)
	(segment
		(start 113.231139 161.227975)
		(end 113.231141 161.227976)
		(width 0.148)
		(layer "In2.Cu")
		(net 65)
	)
	(segment
		(start 118.939006 165.773221)
		(end 118.939005 165.773222)
		(width 0.148)
		(layer "In2.Cu")
		(net 65)
	)
	(segment
		(start 113.635671 160.116333)
		(end 113.635671 160.116334)
		(width 0.148)
		(layer "In2.Cu")
		(net 65)
	)
	(segment
		(start 113.938251 161.581534)
		(end 113.938252 161.581533)
		(width 0.148)
		(layer "In2.Cu")
		(net 65)
	)
	(segment
		(start 115.757004 162.237666)
		(end 115.757004 162.237667)
		(width 0.148)
		(layer "In2.Cu")
		(net 65)
	)
	(segment
		(start 111.816919 159.4602)
		(end 111.842407 159.434709)
		(width 0.148)
		(layer "In2.Cu")
		(net 65)
	)
	(segment
		(start 118.585448 165.06611)
		(end 118.585448 165.066111)
		(width 0.148)
		(layer "In2.Cu")
		(net 65)
	)
	(segment
		(start 117.473806 165.117089)
		(end 117.473807 165.117088)
		(width 0.148)
		(layer "In2.Cu")
		(net 65)
	)
	(segment
		(start 116.059584 163.702867)
		(end 116.059585 163.702866)
		(width 0.148)
		(layer "In2.Cu")
		(net 65)
	)
	(segment
		(start 115.049893 161.530555)
		(end 115.049893 161.530556)
		(width 0.148)
		(layer "In2.Cu")
		(net 65)
	)
	(segment
		(start 118.888027 166.531309)
		(end 119.292559 166.126775)
		(width 0.148)
		(layer "In2.Cu")
		(net 65)
	)
	(segment
		(start 114.69634 161.530555)
		(end 114.696339 161.530556)
		(width 0.148)
		(layer "In2.Cu")
		(net 65)
	)
	(segment
		(start 117.524784 164.358999)
		(end 117.524783 164.359)
		(width 0.148)
		(layer "In2.Cu")
		(net 65)
	)
	(segment
		(start 114.645362 162.288645)
		(end 114.645363 162.288644)
		(width 0.148)
		(layer "In2.Cu")
		(net 65)
	)
	(segment
		(start 111.842408 159.081156)
		(end 111.842407 159.081155)
		(width 0.148)
		(layer "In2.Cu")
		(net 65)
	)
	(segment
		(start 116.059583 164.056419)
		(end 116.059585 164.05642)
		(width 0.148)
		(layer "In2.Cu")
		(net 65)
	)
	(segment
		(start 119.267072 166.859375)
		(end 119.241581 166.884863)
		(width 0.148)
		(layer "In2.Cu")
		(net 65)
	)
	(segment
		(start 118.180917 165.8242)
		(end 118.180918 165.824199)
		(width 0.148)
		(layer "In2.Cu")
		(net 65)
	)
	(segment
		(start 118.939005 165.773222)
		(end 118.53447 166.177752)
		(width 0.148)
		(layer "In2.Cu")
		(net 65)
	)
	(segment
		(start 111.816917 159.813753)
		(end 111.816919 159.813754)
		(width 0.148)
		(layer "In2.Cu")
		(net 65)
	)
	(segment
		(start 114.342782 160.823444)
		(end 114.342782 160.823445)
		(width 0.148)
		(layer "In2.Cu")
		(net 65)
	)
	(segment
		(start 119.292559 165.773221)
		(end 119.292559 165.773222)
		(width 0.148)
		(layer "In2.Cu")
		(net 65)
	)
	(segment
		(start 116.110561 162.944778)
		(end 115.706026 163.349308)
		(width 0.148)
		(layer "In2.Cu")
		(net 65)
	)
	(segment
		(start 116.817672 163.651889)
		(end 116.413137 164.056419)
		(width 0.148)
		(layer "In2.Cu")
		(net 65)
	)
	(segment
		(start 116.110562 162.944777)
		(end 116.110561 162.944778)
		(width 0.148)
		(layer "In2.Cu")
		(net 65)
	)
	(segment
		(start 117.473807 165.117088)
		(end 117.878337 164.712553)
		(width 0.148)
		(layer "In2.Cu")
		(net 65)
	)
	(segment
		(start 113.938252 161.581533)
		(end 114.342782 161.176998)
		(width 0.148)
		(layer "In2.Cu")
		(net 65)
	)
	(segment
		(start 113.23114 160.874423)
		(end 113.231141 160.874422)
		(width 0.148)
		(layer "In2.Cu")
		(net 65)
	)
	(segment
		(start 115.403451 162.237666)
		(end 115.40345 162.237667)
		(width 0.148)
		(layer "In2.Cu")
		(net 65)
	)
	(segment
		(start 113.989228 160.823445)
		(end 113.584693 161.227975)
		(width 0.148)
		(layer "In2.Cu")
		(net 65)
	)
	(segment
		(start 117.524783 164.359)
		(end 117.120248 164.76353)
		(width 0.148)
		(layer "In2.Cu")
		(net 65)
	)
	(segment
		(start 112.575006 159.409223)
		(end 112.170471 159.813753)
		(width 0.148)
		(layer "In2.Cu")
		(net 65)
	)
	(segment
		(start 113.282118 160.116333)
		(end 113.282117 160.116334)
		(width 0.148)
		(layer "In2.Cu")
		(net 65)
	)
	(segment
		(start 116.766696 164.409977)
		(end 117.171226 164.005442)
		(width 0.148)
		(layer "In2.Cu")
		(net 65)
	)
	(segment
		(start 118.888028 166.884864)
		(end 118.888027 166.884863)
		(width 0.148)
		(layer "In2.Cu")
		(net 65)
	)
	(segment
		(start 118.888026 166.53131)
		(end 118.888027 166.531309)
		(width 0.148)
		(layer "In2.Cu")
		(net 65)
	)
	(segment
		(start 117.878337 164.358999)
		(end 117.878337 164.359)
		(width 0.148)
		(layer "In2.Cu")
		(net 65)
	)
	(segment
		(start 110.5 157.738749)
		(end 110.5 149.176501)
		(width 0.148)
		(layer "In2.Cu")
		(net 65)
	)
	(segment
		(start 132.403501 170.276)
		(end 123.037251 170.276)
		(width 0.148)
		(layer "In2.Cu")
		(net 65)
	)
	(segment
		(start 116.059585 163.702866)
		(end 116.464115 163.298331)
		(width 0.148)
		(layer "In2.Cu")
		(net 65)
	)
	(segment
		(start 114.696339 161.530556)
		(end 114.291804 161.935086)
		(width 0.148)
		(layer "In2.Cu")
		(net 65)
	)
	(segment
		(start 113.282117 160.116334)
		(end 112.877582 160.520864)
		(width 0.148)
		(layer "In2.Cu")
		(net 65)
	)
	(segment
		(start 119.267073 166.859374)
		(end 119.267072 166.859375)
		(width 0.148)
		(layer "In2.Cu")
		(net 65)
	)
	(segment
		(start 115.352474 162.995755)
		(end 115.757004 162.59122)
		(width 0.148)
		(layer "In2.Cu")
		(net 65)
	)
	(segment
		(start 110.900001 148.7765)
		(end 110.900001 147.2775)
		(width 0.148)
		(layer "In2.Cu")
		(net 65)
	)
	(segment
		(start 111.816918 159.460201)
		(end 111.816919 159.4602)
		(width 0.148)
		(layer "In2.Cu")
		(net 65)
	)
	(segment
		(start 113.93825 161.935086)
		(end 113.938252 161.935087)
		(width 0.148)
		(layer "In2.Cu")
		(net 65)
	)
	(segment
		(start 116.817673 163.651888)
		(end 116.817672 163.651889)
		(width 0.148)
		(layer "In2.Cu")
		(net 65)
	)
	(segment
		(start 113.989229 160.823444)
		(end 113.989228 160.823445)
		(width 0.148)
		(layer "In2.Cu")
		(net 65)
	)
	(segment
		(start 117.473805 165.470641)
		(end 117.473807 165.470642)
		(width 0.148)
		(layer "In2.Cu")
		(net 65)
	)
	(segment
		(start 111.842407 159.081155)
		(end 110.5 157.738749)
		(width 0.148)
		(layer "In2.Cu")
		(net 65)
	)
	(segment
		(start 114.645361 162.642197)
		(end 114.645363 162.642198)
		(width 0.148)
		(layer "In2.Cu")
		(net 65)
	)
	(segment
		(start 115.352473 162.995756)
		(end 115.352474 162.995755)
		(width 0.148)
		(layer "In2.Cu")
		(net 65)
	)
	(segment
		(start 112.52403 160.167311)
		(end 112.92856 159.762776)
		(width 0.148)
		(layer "In2.Cu")
		(net 65)
	)
	(segment
		(start 117.171226 163.651888)
		(end 117.171226 163.651889)
		(width 0.148)
		(layer "In2.Cu")
		(net 65)
	)
	(segment
		(start 123.037251 170.276)
		(end 119.620626 166.859375)
		(width 0.148)
		(layer "In2.Cu")
		(net 65)
	)
	(segment
		(start 115.40345 162.237667)
		(end 114.998915 162.642197)
		(width 0.148)
		(layer "In2.Cu")
		(net 65)
	)
	(segment
		(start 116.766694 164.76353)
		(end 116.766696 164.763531)
		(width 0.148)
		(layer "In2.Cu")
		(net 65)
	)
	(segment
		(start 132.877001 169.8025)
		(end 132.403501 170.276)
		(width 0.148)
		(layer "In2.Cu")
		(net 65)
	)
	(segment
		(start 118.231894 165.066111)
		(end 117.827359 165.470641)
		(width 0.148)
		(layer "In2.Cu")
		(net 65)
	)
	(segment
		(start 112.575007 159.409222)
		(end 112.575006 159.409223)
		(width 0.148)
		(layer "In2.Cu")
		(net 65)
	)
	(segment
		(start 112.524028 160.520864)
		(end 112.52403 160.520865)
		(width 0.148)
		(layer "In2.Cu")
		(net 65)
	)
	(segment
		(start 118.180916 166.177752)
		(end 118.180918 166.177753)
		(width 0.148)
		(layer "In2.Cu")
		(net 65)
	)
	(arc
		(start 117.878337 164.712553)
		(mid 117.95156 164.535776)
		(end 117.878337 164.358999)
		(width 0.148)
		(layer "In2.Cu")
		(net 65)
	)
	(arc
		(start 115.706026 163.349308)
		(mid 115.529249 163.422531)
		(end 115.352472 163.349308)
		(width 0.148)
		(layer "In2.Cu")
		(net 65)
	)
	(arc
		(start 112.92856 159.762776)
		(mid 113.001783 159.585999)
		(end 112.92856 159.409222)
		(width 0.148)
		(layer "In2.Cu")
		(net 65)
	)
	(arc
		(start 116.059585 164.05642)
		(mid 115.986361 163.879644)
		(end 116.059584 163.702867)
		(width 0.148)
		(layer "In2.Cu")
		(net 65)
	)
	(arc
		(start 112.92856 159.409223)
		(mid 112.751784 159.335999)
		(end 112.575007 159.409222)
		(width 0.148)
		(layer "In2.Cu")
		(net 65)
	)
	(arc
		(start 111.816919 159.813754)
		(mid 111.743695 159.636978)
		(end 111.816918 159.460201)
		(width 0.148)
		(layer "In2.Cu")
		(net 65)
	)
	(arc
		(start 114.645363 162.642198)
		(mid 114.572139 162.465422)
		(end 114.645362 162.288645)
		(width 0.148)
		(layer "In2.Cu")
		(net 65)
	)
	(arc
		(start 112.170471 159.813753)
		(mid 111.993694 159.886976)
		(end 111.816917 159.813753)
		(width 0.148)
		(layer "In2.Cu")
		(net 65)
	)
	(arc
		(start 118.180918 166.177753)
		(mid 118.107694 166.000977)
		(end 118.180917 165.8242)
		(width 0.148)
		(layer "In2.Cu")
		(net 65)
	)
	(arc
		(start 117.171226 163.651889)
		(mid 116.99445 163.578665)
		(end 116.817673 163.651888)
		(width 0.148)
		(layer "In2.Cu")
		(net 65)
	)
	(arc
		(start 113.231141 161.227976)
		(mid 113.157917 161.0512)
		(end 113.23114 160.874423)
		(width 0.148)
		(layer "In2.Cu")
		(net 65)
	)
	(arc
		(start 115.352474 163.349309)
		(mid 115.27925 163.172533)
		(end 115.352473 162.995756)
		(width 0.148)
		(layer "In2.Cu")
		(net 65)
	)
	(arc
		(start 113.584693 161.227975)
		(mid 113.407916 161.301198)
		(end 113.231139 161.227975)
		(width 0.148)
		(layer "In2.Cu")
		(net 65)
	)
	(arc
		(start 119.292559 165.773222)
		(mid 119.115783 165.699998)
		(end 118.939006 165.773221)
		(width 0.148)
		(layer "In2.Cu")
		(net 65)
	)
	(arc
		(start 115.757004 162.59122)
		(mid 115.830227 162.414443)
		(end 115.757004 162.237666)
		(width 0.148)
		(layer "In2.Cu")
		(net 65)
	)
	(arc
		(start 118.585448 165.419664)
		(mid 118.658671 165.242887)
		(end 118.585448 165.06611)
		(width 0.148)
		(layer "In2.Cu")
		(net 65)
	)
	(arc
		(start 113.938252 161.935087)
		(mid 113.865028 161.758311)
		(end 113.938251 161.581534)
		(width 0.148)
		(layer "In2.Cu")
		(net 65)
	)
	(arc
		(start 119.620626 166.859375)
		(mid 119.44385 166.786151)
		(end 119.267073 166.859374)
		(width 0.148)
		(layer "In2.Cu")
		(net 65)
	)
	(arc
		(start 117.827359 165.470641)
		(mid 117.650582 165.543864)
		(end 117.473805 165.470641)
		(width 0.148)
		(layer "In2.Cu")
		(net 65)
	)
	(arc
		(start 117.473807 165.470642)
		(mid 117.400583 165.293866)
		(end 117.473806 165.117089)
		(width 0.148)
		(layer "In2.Cu")
		(net 65)
	)
	(arc
		(start 119.241581 166.884863)
		(mid 119.064805 166.958087)
		(end 118.888028 166.884864)
		(width 0.148)
		(layer "In2.Cu")
		(net 65)
	)
	(arc
		(start 112.52403 160.520865)
		(mid 112.450806 160.344089)
		(end 112.524029 160.167312)
		(width 0.148)
		(layer "In2.Cu")
		(net 65)
	)
	(arc
		(start 116.464115 163.298331)
		(mid 116.537338 163.121554)
		(end 116.464115 162.944777)
		(width 0.148)
		(layer "In2.Cu")
		(net 65)
	)
	(arc
		(start 118.53447 166.177752)
		(mid 118.357693 166.250975)
		(end 118.180916 166.177752)
		(width 0.148)
		(layer "In2.Cu")
		(net 65)
	)
	(arc
		(start 118.585448 165.066111)
		(mid 118.408672 164.992887)
		(end 118.231895 165.06611)
		(width 0.148)
		(layer "In2.Cu")
		(net 65)
	)
	(arc
		(start 115.049893 161.530556)
		(mid 114.873117 161.457332)
		(end 114.69634 161.530555)
		(width 0.148)
		(layer "In2.Cu")
		(net 65)
	)
	(arc
		(start 111.842407 159.434709)
		(mid 111.915631 159.257933)
		(end 111.842408 159.081156)
		(width 0.148)
		(layer "In2.Cu")
		(net 65)
	)
	(arc
		(start 119.292559 166.126775)
		(mid 119.365782 165.949998)
		(end 119.292559 165.773221)
		(width 0.148)
		(layer "In2.Cu")
		(net 65)
	)
	(arc
		(start 114.342782 161.176998)
		(mid 114.416005 161.000221)
		(end 114.342782 160.823444)
		(width 0.148)
		(layer "In2.Cu")
		(net 65)
	)
	(arc
		(start 116.413137 164.056419)
		(mid 116.23636 164.129642)
		(end 116.059583 164.056419)
		(width 0.148)
		(layer "In2.Cu")
		(net 65)
	)
	(arc
		(start 116.464115 162.944778)
		(mid 116.287339 162.871554)
		(end 116.110562 162.944777)
		(width 0.148)
		(layer "In2.Cu")
		(net 65)
	)
	(arc
		(start 114.291804 161.935086)
		(mid 114.115027 162.008309)
		(end 113.93825 161.935086)
		(width 0.148)
		(layer "In2.Cu")
		(net 65)
	)
	(arc
		(start 117.878337 164.359)
		(mid 117.701561 164.285776)
		(end 117.524784 164.358999)
		(width 0.148)
		(layer "In2.Cu")
		(net 65)
	)
	(arc
		(start 118.888027 166.884863)
		(mid 118.814803 166.708087)
		(end 118.888026 166.53131)
		(width 0.148)
		(layer "In2.Cu")
		(net 65)
	)
	(arc
		(start 113.635671 160.116334)
		(mid 113.458895 160.04311)
		(end 113.282118 160.116333)
		(width 0.148)
		(layer "In2.Cu")
		(net 65)
	)
	(arc
		(start 117.171226 164.005442)
		(mid 117.244449 163.828665)
		(end 117.171226 163.651888)
		(width 0.148)
		(layer "In2.Cu")
		(net 65)
	)
	(arc
		(start 112.877582 160.520864)
		(mid 112.700805 160.594087)
		(end 112.524028 160.520864)
		(width 0.148)
		(layer "In2.Cu")
		(net 65)
	)
	(arc
		(start 115.049893 161.884109)
		(mid 115.123116 161.707332)
		(end 115.049893 161.530555)
		(width 0.148)
		(layer "In2.Cu")
		(net 65)
	)
	(arc
		(start 115.757004 162.237667)
		(mid 115.580228 162.164443)
		(end 115.403451 162.237666)
		(width 0.148)
		(layer "In2.Cu")
		(net 65)
	)
	(arc
		(start 114.998915 162.642197)
		(mid 114.822138 162.71542)
		(end 114.645361 162.642197)
		(width 0.148)
		(layer "In2.Cu")
		(net 65)
	)
	(arc
		(start 116.766696 164.763531)
		(mid 116.693472 164.586755)
		(end 116.766695 164.409978)
		(width 0.148)
		(layer "In2.Cu")
		(net 65)
	)
	(arc
		(start 117.120248 164.76353)
		(mid 116.943471 164.836753)
		(end 116.766694 164.76353)
		(width 0.148)
		(layer "In2.Cu")
		(net 65)
	)
	(arc
		(start 113.635671 160.469887)
		(mid 113.708894 160.29311)
		(end 113.635671 160.116333)
		(width 0.148)
		(layer "In2.Cu")
		(net 65)
	)
	(arc
		(start 114.342782 160.823445)
		(mid 114.166006 160.750221)
		(end 113.989229 160.823444)
		(width 0.148)
		(layer "In2.Cu")
		(net 65)
	)
	(segment
		(start 174.316501 191.56)
		(end 174.900501 191.56)
		(width 0.201)
		(layer "F.Cu")
		(net 67)
	)
	(segment
		(start 173.369501 192.507)
		(end 174.316501 191.56)
		(width 0.201)
		(layer "F.Cu")
		(net 67)
	)
	(segment
		(start 173.369501 192.815501)
		(end 173.369501 192.507)
		(width 0.201)
		(layer "F.Cu")
		(net 67)
	)
	(segment
		(start 111.17 139.892427)
		(end 111.125001 139.937426)
		(width 0.26)
		(layer "F.Cu")
		(net 68)
	)
	(segment
		(start 111.150001 138.8025)
		(end 111.150001 139.4025)
		(width 0.26)
		(layer "F.Cu")
		(net 68)
	)
	(segment
		(start 111.170001 139.4225)
		(end 111.17 139.892427)
		(width 0.26)
		(layer "F.Cu")
		(net 68)
	)
	(segment
		(start 111.150001 139.4025)
		(end 111.170001 139.4225)
		(width 0.26)
		(layer "F.Cu")
		(net 68)
	)
	(segment
		(start 133.376501 169.302)
		(end 132.877001 168.8025)
		(width 0.256)
		(layer "F.Cu")
		(net 68)
	)
	(via
		(at 111.125001 139.937426)
		(size 0.45)
		(drill 0.1)
		(layers "F.Cu" "B.Cu")
		(net 68)
	)
	(via
		(at 132.877001 168.8025)
		(size 0.45)
		(drill 0.1)
		(layers "F.Cu" "B.Cu")
		(net 68)
	)
	(segment
		(start 123.475207 169.181)
		(end 125.400501 169.181)
		(width 0.13)
		(layer "In2.Cu")
		(net 68)
	)
	(segment
		(start 112.1 150.79)
		(end 111.276855 150.79)
		(width 0.13)
		(layer "In2.Cu")
		(net 68)
	)
	(segment
		(start 125.422001 169.2025)
		(end 125.400501 169.181)
		(width 0.1)
		(layer "In2.Cu")
		(net 68)
	)
	(segment
		(start 112.275 139.426506)
		(end 112.012481 139.163987)
		(width 0.1)
		(layer "In2.Cu")
		(net 68)
	)
	(segment
		(start 111.519341 148.200659)
		(end 111.519341 148.708461)
		(width 0.13)
		(layer "In2.Cu")
		(net 68)
	)
	(segment
		(start 111.87 157.575793)
		(end 123.475207 169.181)
		(width 0.13)
		(layer "In2.Cu")
		(net 68)
	)
	(segment
		(start 111.521002 148.198998)
		(end 111.521002 146.507492)
		(width 0.1)
		(layer "In2.Cu")
		(net 68)
	)
	(segment
		(start 111.276855 152.19)
		(end 112.223145 152.19)
		(width 0.13)
		(layer "In2.Cu")
		(net 68)
	)
	(segment
		(start 133.277001 168.897001)
		(end 133.277001 169.008013)
		(width 0.1)
		(layer "In2.Cu")
		(net 68)
	)
	(segment
		(start 111.87 155.92)
		(end 111.87 157.575793)
		(width 0.13)
		(layer "In2.Cu")
		(net 68)
	)
	(segment
		(start 111.295001 139.767426)
		(end 111.125001 139.937426)
		(width 0.1)
		(layer "In2.Cu")
		(net 68)
	)
	(segment
		(start 111.276855 152.65)
		(end 112.223145 152.65)
		(width 0.13)
		(layer "In2.Cu")
		(net 68)
	)
	(segment
		(start 111.276855 155.45)
		(end 111.4 155.45)
		(width 0.13)
		(layer "In2.Cu")
		(net 68)
	)
	(segment
		(start 111.276855 151.25)
		(end 112.223145 151.25)
		(width 0.13)
		(layer "In2.Cu")
		(net 68)
	)
	(segment
		(start 111.60119 139.163987)
		(end 111.295001 139.470176)
		(width 0.1)
		(layer "In2.Cu")
		(net 68)
	)
	(segment
		(start 132.877001 168.8025)
		(end 133.1825 168.8025)
		(width 0.1)
		(layer "In2.Cu")
		(net 68)
	)
	(segment
		(start 111.519341 148.200659)
		(end 111.521002 148.198998)
		(width 0.1)
		(layer "In2.Cu")
		(net 68)
	)
	(segment
		(start 111.295001 139.470176)
		(end 111.295001 139.767426)
		(width 0.1)
		(layer "In2.Cu")
		(net 68)
	)
	(segment
		(start 111.276855 154.05)
		(end 112.223145 154.05)
		(width 0.13)
		(layer "In2.Cu")
		(net 68)
	)
	(segment
		(start 112.1 149.85)
		(end 112.223145 149.85)
		(width 0.13)
		(layer "In2.Cu")
		(net 68)
	)
	(segment
		(start 111.276855 154.99)
		(end 112.223145 154.99)
		(width 0.13)
		(layer "In2.Cu")
		(net 68)
	)
	(segment
		(start 112.005 141.073494)
		(end 112.275 140.803494)
		(width 0.1)
		(layer "In2.Cu")
		(net 68)
	)
	(segment
		(start 133.1825 168.8025)
		(end 133.277001 168.897001)
		(width 0.1)
		(layer "In2.Cu")
		(net 68)
	)
	(segment
		(start 112.012481 139.163987)
		(end 111.60119 139.163987)
		(width 0.1)
		(layer "In2.Cu")
		(net 68)
	)
	(segment
		(start 133.082514 169.2025)
		(end 125.422001 169.2025)
		(width 0.1)
		(layer "In2.Cu")
		(net 68)
	)
	(segment
		(start 111.276855 153.59)
		(end 112.223145 153.59)
		(width 0.13)
		(layer "In2.Cu")
		(net 68)
	)
	(segment
		(start 133.277001 169.008013)
		(end 133.082514 169.2025)
		(width 0.1)
		(layer "In2.Cu")
		(net 68)
	)
	(segment
		(start 112.005 146.023494)
		(end 112.005 141.073494)
		(width 0.1)
		(layer "In2.Cu")
		(net 68)
	)
	(segment
		(start 112.275 140.803494)
		(end 112.275 139.426506)
		(width 0.1)
		(layer "In2.Cu")
		(net 68)
	)
	(segment
		(start 111.521002 146.507492)
		(end 112.005 146.023494)
		(width 0.1)
		(layer "In2.Cu")
		(net 68)
	)
	(segment
		(start 111.519341 148.708461)
		(end 111.87 149.05912)
		(width 0.13)
		(layer "In2.Cu")
		(net 68)
	)
	(segment
		(start 112.223145 150.79)
		(end 112.1 150.79)
		(width 0.13)
		(layer "In2.Cu")
		(net 68)
	)
	(segment
		(start 111.87 149.05912)
		(end 111.87 149.62)
		(width 0.13)
		(layer "In2.Cu")
		(net 68)
	)
	(arc
		(start 111.046855 153.82)
		(mid 111.11422 153.982635)
		(end 111.276855 154.05)
		(width 0.13)
		(layer "In2.Cu")
		(net 68)
	)
	(arc
		(start 112.223145 149.85)
		(mid 112.555485 149.98766)
		(end 112.693145 150.32)
		(width 0.13)
		(layer "In2.Cu")
		(net 68)
	)
	(arc
		(start 112.223145 151.25)
		(mid 112.555485 151.38766)
		(end 112.693145 151.72)
		(width 0.13)
		(layer "In2.Cu")
		(net 68)
	)
	(arc
		(start 112.223145 154.05)
		(mid 112.555485 154.18766)
		(end 112.693145 154.52)
		(width 0.13)
		(layer "In2.Cu")
		(net 68)
	)
	(arc
		(start 111.276855 152.19)
		(mid 111.11422 152.257365)
		(end 111.046855 152.42)
		(width 0.13)
		(layer "In2.Cu")
		(net 68)
	)
	(arc
		(start 112.693145 150.32)
		(mid 112.555485 150.65234)
		(end 112.223145 150.79)
		(width 0.13)
		(layer "In2.Cu")
		(net 68)
	)
	(arc
		(start 111.276855 153.59)
		(mid 111.11422 153.657365)
		(end 111.046855 153.82)
		(width 0.13)
		(layer "In2.Cu")
		(net 68)
	)
	(arc
		(start 111.046855 152.42)
		(mid 111.11422 152.582635)
		(end 111.276855 152.65)
		(width 0.13)
		(layer "In2.Cu")
		(net 68)
	)
	(arc
		(start 112.693145 151.72)
		(mid 112.555485 152.05234)
		(end 112.223145 152.19)
		(width 0.13)
		(layer "In2.Cu")
		(net 68)
	)
	(arc
		(start 111.276855 150.79)
		(mid 111.11422 150.857365)
		(end 111.046855 151.02)
		(width 0.13)
		(layer "In2.Cu")
		(net 68)
	)
	(arc
		(start 112.223145 152.65)
		(mid 112.555485 152.78766)
		(end 112.693145 153.12)
		(width 0.13)
		(layer "In2.Cu")
		(net 68)
	)
	(arc
		(start 111.87 149.62)
		(mid 111.937365 149.782635)
		(end 112.1 149.85)
		(width 0.13)
		(layer "In2.Cu")
		(net 68)
	)
	(arc
		(start 111.046855 155.22)
		(mid 111.11422 155.382635)
		(end 111.276855 155.45)
		(width 0.13)
		(layer "In2.Cu")
		(net 68)
	)
	(arc
		(start 111.4 155.45)
		(mid 111.73234 155.58766)
		(end 111.87 155.92)
		(width 0.13)
		(layer "In2.Cu")
		(net 68)
	)
	(arc
		(start 112.693145 153.12)
		(mid 112.555485 153.45234)
		(end 112.223145 153.59)
		(width 0.13)
		(layer "In2.Cu")
		(net 68)
	)
	(arc
		(start 112.693145 154.52)
		(mid 112.555485 154.85234)
		(end 112.223145 154.99)
		(width 0.13)
		(layer "In2.Cu")
		(net 68)
	)
	(arc
		(start 111.046855 151.02)
		(mid 111.11422 151.182635)
		(end 111.276855 151.25)
		(width 0.13)
		(layer "In2.Cu")
		(net 68)
	)
	(arc
		(start 111.276855 154.99)
		(mid 111.11422 155.057365)
		(end 111.046855 155.22)
		(width 0.13)
		(layer "In2.Cu")
		(net 68)
	)
	(segment
		(start 111.650001 138.8025)
		(end 111.650001 139.4025)
		(width 0.26)
		(layer "F.Cu")
		(net 69)
	)
	(segment
		(start 134.376501 169.302)
		(end 133.877001 168.8025)
		(width 0.256)
		(layer "F.Cu")
		(net 69)
	)
	(segment
		(start 111.630001 139.4225)
		(end 111.630002 139.892427)
		(width 0.26)
		(layer "F.Cu")
		(net 69)
	)
	(segment
		(start 111.630002 139.892427)
		(end 111.675001 139.937426)
		(width 0.26)
		(layer "F.Cu")
		(net 69)
	)
	(segment
		(start 111.650001 139.4025)
		(end 111.630001 139.4225)
		(width 0.26)
		(layer "F.Cu")
		(net 69)
	)
	(via
		(at 111.675001 139.937426)
		(size 0.45)
		(drill 0.1)
		(layers "F.Cu" "B.Cu")
		(net 69)
	)
	(via
		(at 133.877001 168.8025)
		(size 0.45)
		(drill 0.1)
		(layers "F.Cu" "B.Cu")
		(net 69)
	)
	(segment
		(start 133.165358 169.4025)
		(end 125.419001 169.4025)
		(width 0.1)
		(layer "In2.Cu")
		(net 69)
	)
	(segment
		(start 125.419001 169.4025)
		(end 125.400501 169.421)
		(width 0.1)
		(layer "In2.Cu")
		(net 69)
	)
	(segment
		(start 111.281002 146.450504)
		(end 111.795 145.936506)
		(width 0.1)
		(layer "In2.Cu")
		(net 69)
	)
	(segment
		(start 133.477001 168.962374)
		(end 133.477001 169.090857)
		(width 0.1)
		(layer "In2.Cu")
		(net 69)
	)
	(segment
		(start 111.63 157.675205)
		(end 123.375795 169.421)
		(width 0.13)
		(layer "In2.Cu")
		(net 69)
	)
	(segment
		(start 111.63 155.92)
		(end 111.63 157.675205)
		(width 0.13)
		(layer "In2.Cu")
		(net 69)
	)
	(segment
		(start 112.065 140.716506)
		(end 112.065 139.513494)
		(width 0.1)
		(layer "In2.Cu")
		(net 69)
	)
	(segment
		(start 111.279341 148.200659)
		(end 111.279341 148.807873)
		(width 0.13)
		(layer "In2.Cu")
		(net 69)
	)
	(segment
		(start 111.276855 153.35)
		(end 112.223145 153.35)
		(width 0.13)
		(layer "In2.Cu")
		(net 69)
	)
	(segment
		(start 111.281002 148.198998)
		(end 111.281002 146.450504)
		(width 0.1)
		(layer "In2.Cu")
		(net 69)
	)
	(segment
		(start 111.276855 151.49)
		(end 112.223145 151.49)
		(width 0.13)
		(layer "In2.Cu")
		(net 69)
	)
	(segment
		(start 111.276855 151.95)
		(end 112.223145 151.95)
		(width 0.13)
		(layer "In2.Cu")
		(net 69)
	)
	(segment
		(start 111.276855 155.69)
		(end 111.4 155.69)
		(width 0.13)
		(layer "In2.Cu")
		(net 69)
	)
	(segment
		(start 111.279341 148.200659)
		(end 111.281002 148.198998)
		(width 0.1)
		(layer "In2.Cu")
		(net 69)
	)
	(segment
		(start 111.925493 139.373987)
		(end 111.688178 139.373987)
		(width 0.1)
		(layer "In2.Cu")
		(net 69)
	)
	(segment
		(start 112.065 139.513494)
		(end 111.925493 139.373987)
		(width 0.1)
		(layer "In2.Cu")
		(net 69)
	)
	(segment
		(start 111.795 140.986506)
		(end 112.065 140.716506)
		(width 0.1)
		(layer "In2.Cu")
		(net 69)
	)
	(segment
		(start 111.276855 152.89)
		(end 112.223145 152.89)
		(width 0.13)
		(layer "In2.Cu")
		(net 69)
	)
	(segment
		(start 111.795 145.936506)
		(end 111.795 140.986506)
		(width 0.1)
		(layer "In2.Cu")
		(net 69)
	)
	(segment
		(start 112.1 150.09)
		(end 112.223145 150.09)
		(width 0.13)
		(layer "In2.Cu")
		(net 69)
	)
	(segment
		(start 111.276855 154.75)
		(end 112.223145 154.75)
		(width 0.13)
		(layer "In2.Cu")
		(net 69)
	)
	(segment
		(start 133.477001 169.090857)
		(end 133.165358 169.4025)
		(width 0.1)
		(layer "In2.Cu")
		(net 69)
	)
	(segment
		(start 111.505001 139.557164)
		(end 111.505001 139.767426)
		(width 0.1)
		(layer "In2.Cu")
		(net 69)
	)
	(segment
		(start 111.505001 139.767426)
		(end 111.675001 139.937426)
		(width 0.1)
		(layer "In2.Cu")
		(net 69)
	)
	(segment
		(start 112.223145 150.55)
		(end 112.1 150.55)
		(width 0.13)
		(layer "In2.Cu")
		(net 69)
	)
	(segment
		(start 133.877001 168.8025)
		(end 133.636875 168.8025)
		(width 0.1)
		(layer "In2.Cu")
		(net 69)
	)
	(segment
		(start 111.688178 139.373987)
		(end 111.505001 139.557164)
		(width 0.1)
		(layer "In2.Cu")
		(net 69)
	)
	(segment
		(start 123.375795 169.421)
		(end 125.400501 169.421)
		(width 0.13)
		(layer "In2.Cu")
		(net 69)
	)
	(segment
		(start 112.1 150.55)
		(end 111.276855 150.55)
		(width 0.13)
		(layer "In2.Cu")
		(net 69)
	)
	(segment
		(start 133.636875 168.8025)
		(end 133.477001 168.962374)
		(width 0.1)
		(layer "In2.Cu")
		(net 69)
	)
	(segment
		(start 111.276855 154.29)
		(end 112.223145 154.29)
		(width 0.13)
		(layer "In2.Cu")
		(net 69)
	)
	(segment
		(start 111.63 149.158532)
		(end 111.63 149.62)
		(width 0.13)
		(layer "In2.Cu")
		(net 69)
	)
	(segment
		(start 111.279341 148.807873)
		(end 111.63 149.158532)
		(width 0.13)
		(layer "In2.Cu")
		(net 69)
	)
	(arc
		(start 110.806855 152.42)
		(mid 110.944515 152.75234)
		(end 111.276855 152.89)
		(width 0.13)
		(layer "In2.Cu")
		(net 69)
	)
	(arc
		(start 111.276855 154.75)
		(mid 110.944515 154.88766)
		(end 110.806855 155.22)
		(width 0.13)
		(layer "In2.Cu")
		(net 69)
	)
	(arc
		(start 112.223145 154.29)
		(mid 112.38578 154.357365)
		(end 112.453145 154.52)
		(width 0.13)
		(layer "In2.Cu")
		(net 69)
	)
	(arc
		(start 111.63 149.62)
		(mid 111.76766 149.95234)
		(end 112.1 150.09)
		(width 0.13)
		(layer "In2.Cu")
		(net 69)
	)
	(arc
		(start 112.223145 150.09)
		(mid 112.38578 150.157365)
		(end 112.453145 150.32)
		(width 0.13)
		(layer "In2.Cu")
		(net 69)
	)
	(arc
		(start 112.453145 150.32)
		(mid 112.38578 150.482635)
		(end 112.223145 150.55)
		(width 0.13)
		(layer "In2.Cu")
		(net 69)
	)
	(arc
		(start 111.276855 150.55)
		(mid 110.944515 150.68766)
		(end 110.806855 151.02)
		(width 0.13)
		(layer "In2.Cu")
		(net 69)
	)
	(arc
		(start 111.276855 151.95)
		(mid 110.944515 152.08766)
		(end 110.806855 152.42)
		(width 0.13)
		(layer "In2.Cu")
		(net 69)
	)
	(arc
		(start 110.806855 153.82)
		(mid 110.944515 154.15234)
		(end 111.276855 154.29)
		(width 0.13)
		(layer "In2.Cu")
		(net 69)
	)
	(arc
		(start 112.453145 153.12)
		(mid 112.38578 153.282635)
		(end 112.223145 153.35)
		(width 0.13)
		(layer "In2.Cu")
		(net 69)
	)
	(arc
		(start 111.276855 153.35)
		(mid 110.944515 153.48766)
		(end 110.806855 153.82)
		(width 0.13)
		(layer "In2.Cu")
		(net 69)
	)
	(arc
		(start 110.806855 155.22)
		(mid 110.944515 155.55234)
		(end 111.276855 155.69)
		(width 0.13)
		(layer "In2.Cu")
		(net 69)
	)
	(arc
		(start 112.223145 152.89)
		(mid 112.38578 152.957365)
		(end 112.453145 153.12)
		(width 0.13)
		(layer "In2.Cu")
		(net 69)
	)
	(arc
		(start 110.806855 151.02)
		(mid 110.944515 151.35234)
		(end 111.276855 151.49)
		(width 0.13)
		(layer "In2.Cu")
		(net 69)
	)
	(arc
		(start 112.453145 151.72)
		(mid 112.38578 151.882635)
		(end 112.223145 151.95)
		(width 0.13)
		(layer "In2.Cu")
		(net 69)
	)
	(arc
		(start 112.453145 154.52)
		(mid 112.38578 154.682635)
		(end 112.223145 154.75)
		(width 0.13)
		(layer "In2.Cu")
		(net 69)
	)
	(arc
		(start 112.223145 151.49)
		(mid 112.38578 151.557365)
		(end 112.453145 151.72)
		(width 0.13)
		(layer "In2.Cu")
		(net 69)
	)
	(arc
		(start 111.4 155.69)
		(mid 111.562635 155.757365)
		(end 111.63 155.92)
		(width 0.13)
		(layer "In2.Cu")
		(net 69)
	)
	(segment
		(start 137.376501 169.302)
		(end 136.877001 168.8025)
		(width 0.256)
		(layer "F.Cu")
		(net 70)
	)
	(segment
		(start 111.900001 146.2025)
		(end 111.900001 147.2775)
		(width 0.201)
		(layer "F.Cu")
		(net 70)
	)
	(via
		(at 111.900001 147.2775)
		(size 0.45)
		(drill 0.1)
		(layers "F.Cu" "B.Cu")
		(net 70)
	)
	(via
		(at 136.877001 168.8025)
		(size 0.45)
		(drill 0.1)
		(layers "F.Cu" "B.Cu")
		(net 70)
	)
	(segment
		(start 122.727786 166.54733)
		(end 122.308579 166.966533)
		(width 0.148)
		(layer "In2.Cu")
		(net 70)
	)
	(segment
		(start 114.883914 159.54187)
		(end 114.916742 159.509043)
		(width 0.148)
		(layer "In2.Cu")
		(net 70)
	)
	(segment
		(start 120.960008 164.425998)
		(end 120.960007 164.425997)
		(width 0.148)
		(layer "In2.Cu")
		(net 70)
	)
	(segment
		(start 116.298137 160.956091)
		(end 116.717341 160.536885)
		(width 0.148)
		(layer "In2.Cu")
		(net 70)
	)
	(segment
		(start 118.48512 162.304664)
		(end 118.065913 162.723867)
		(width 0.148)
		(layer "In2.Cu")
		(net 70)
	)
	(segment
		(start 115.591026 160.24898)
		(end 116.01023 159.829774)
		(width 0.148)
		(layer "In2.Cu")
		(net 70)
	)
	(segment
		(start 117.005249 162.016757)
		(end 117.005248 162.016756)
		(width 0.148)
		(layer "In2.Cu")
		(net 70)
	)
	(segment
		(start 119.899343 163.718885)
		(end 119.899342 163.718886)
		(width 0.148)
		(layer "In2.Cu")
		(net 70)
	)
	(segment
		(start 115.591027 160.602535)
		(end 115.591026 160.602534)
		(width 0.148)
		(layer "In2.Cu")
		(net 70)
	)
	(segment
		(start 122.020676 165.840218)
		(end 122.020675 165.840219)
		(width 0.148)
		(layer "In2.Cu")
		(net 70)
	)
	(segment
		(start 117.424453 160.890443)
		(end 117.424452 160.890442)
		(width 0.148)
		(layer "In2.Cu")
		(net 70)
	)
	(segment
		(start 132.773001 168.276)
		(end 124.037251 168.276)
		(width 0.148)
		(layer "In2.Cu")
		(net 70)
	)
	(segment
		(start 116.717342 160.183332)
		(end 116.717341 160.183331)
		(width 0.148)
		(layer "In2.Cu")
		(net 70)
	)
	(segment
		(start 120.540803 165.198757)
		(end 120.960007 164.779551)
		(width 0.148)
		(layer "In2.Cu")
		(net 70)
	)
	(segment
		(start 117.005247 161.663203)
		(end 117.005248 161.663202)
		(width 0.148)
		(layer "In2.Cu")
		(net 70)
	)
	(segment
		(start 120.606454 164.425996)
		(end 120.606453 164.425997)
		(width 0.148)
		(layer "In2.Cu")
		(net 70)
	)
	(segment
		(start 121.247914 165.905868)
		(end 121.667118 165.486662)
		(width 0.148)
		(layer "In2.Cu")
		(net 70)
	)
	(segment
		(start 115.656676 159.47622)
		(end 115.237469 159.895423)
		(width 0.148)
		(layer "In2.Cu")
		(net 70)
	)
	(segment
		(start 116.298136 160.956092)
		(end 116.298137 160.956091)
		(width 0.148)
		(layer "In2.Cu")
		(net 70)
	)
	(segment
		(start 117.77801 161.597552)
		(end 117.778009 161.597553)
		(width 0.148)
		(layer "In2.Cu")
		(net 70)
	)
	(segment
		(start 119.192231 163.011775)
		(end 118.773024 163.430978)
		(width 0.148)
		(layer "In2.Cu")
		(net 70)
	)
	(segment
		(start 114.916741 159.15549)
		(end 114.916741 159.155489)
		(width 0.148)
		(layer "In2.Cu")
		(net 70)
	)
	(segment
		(start 118.838675 162.304665)
		(end 118.838674 162.304664)
		(width 0.148)
		(layer "In2.Cu")
		(net 70)
	)
	(segment
		(start 122.662136 167.32009)
		(end 123.08134 166.900884)
		(width 0.148)
		(layer "In2.Cu")
		(net 70)
	)
	(segment
		(start 134.350501 169.026)
		(end 134.350501 168.576)
		(width 0.1)
		(layer "In2.Cu")
		(net 70)
	)
	(segment
		(start 134.650501 169.326)
		(end 134.350501 169.026)
		(width 0.1)
		(layer "In2.Cu")
		(net 70)
	)
	(segment
		(start 121.955025 166.612979)
		(end 122.374229 166.193773)
		(width 0.148)
		(layer "In2.Cu")
		(net 70)
	)
	(segment
		(start 117.070899 160.890441)
		(end 117.070898 160.890442)
		(width 0.148)
		(layer "In2.Cu")
		(net 70)
	)
	(segment
		(start 122.662135 167.320091)
		(end 122.662136 167.32009)
		(width 0.148)
		(layer "In2.Cu")
		(net 70)
	)
	(segment
		(start 120.252897 163.718887)
		(end 120.252896 163.718886)
		(width 0.148)
		(layer "In2.Cu")
		(net 70)
	)
	(segment
		(start 123.081341 166.547331)
		(end 123.08134 166.54733)
		(width 0.148)
		(layer "In2.Cu")
		(net 70)
	)
	(segment
		(start 120.540804 165.552312)
		(end 120.540803 165.552311)
		(width 0.148)
		(layer "In2.Cu")
		(net 70)
	)
	(segment
		(start 120.606453 164.425997)
		(end 120.187246 164.8452)
		(width 0.148)
		(layer "In2.Cu")
		(net 70)
	)
	(segment
		(start 116.363787 160.183331)
		(end 115.94458 160.602534)
		(width 0.148)
		(layer "In2.Cu")
		(net 70)
	)
	(segment
		(start 114.916741 159.155489)
		(end 113.25 157.488748)
		(width 0.148)
		(layer "In2.Cu")
		(net 70)
	)
	(segment
		(start 134.350501 168.576)
		(end 134.202001 168.4275)
		(width 0.1)
		(layer "In2.Cu")
		(net 70)
	)
	(segment
		(start 117.712358 162.370314)
		(end 117.712359 162.370313)
		(width 0.148)
		(layer "In2.Cu")
		(net 70)
	)
	(segment
		(start 119.833692 164.491646)
		(end 120.252896 164.07244)
		(width 0.148)
		(layer "In2.Cu")
		(net 70)
	)
	(segment
		(start 121.313564 165.133108)
		(end 120.894357 165.552311)
		(width 0.148)
		(layer "In2.Cu")
		(net 70)
	)
	(segment
		(start 121.247915 166.259423)
		(end 121.247914 166.259422)
		(width 0.148)
		(layer "In2.Cu")
		(net 70)
	)
	(segment
		(start 120.540802 165.198758)
		(end 120.540803 165.198757)
		(width 0.148)
		(layer "In2.Cu")
		(net 70)
	)
	(segment
		(start 132.900501 168.4035)
		(end 132.773001 168.276)
		(width 0.148)
		(layer "In2.Cu")
		(net 70)
	)
	(segment
		(start 116.363788 160.18333)
		(end 116.363787 160.183331)
		(width 0.148)
		(layer "In2.Cu")
		(net 70)
	)
	(segment
		(start 119.126581 163.784535)
		(end 119.545785 163.365329)
		(width 0.148)
		(layer "In2.Cu")
		(net 70)
	)
	(segment
		(start 134.202001 168.4275)
		(end 132.924501 168.4275)
		(width 0.1)
		(layer "In2.Cu")
		(net 70)
	)
	(segment
		(start 122.727787 166.547329)
		(end 122.727786 166.54733)
		(width 0.148)
		(layer "In2.Cu")
		(net 70)
	)
	(segment
		(start 115.656677 159.476219)
		(end 115.656676 159.47622)
		(width 0.148)
		(layer "In2.Cu")
		(net 70)
	)
	(segment
		(start 121.955026 166.966534)
		(end 121.955025 166.966533)
		(width 0.148)
		(layer "In2.Cu")
		(net 70)
	)
	(segment
		(start 117.778009 161.597553)
		(end 117.358802 162.016756)
		(width 0.148)
		(layer "In2.Cu")
		(net 70)
	)
	(segment
		(start 122.662137 167.673645)
		(end 122.662136 167.673644)
		(width 0.148)
		(layer "In2.Cu")
		(net 70)
	)
	(segment
		(start 119.899342 163.718886)
		(end 119.480135 164.138089)
		(width 0.148)
		(layer "In2.Cu")
		(net 70)
	)
	(segment
		(start 119.12658 163.784536)
		(end 119.126581 163.784535)
		(width 0.148)
		(layer "In2.Cu")
		(net 70)
	)
	(segment
		(start 121.955024 166.61298)
		(end 121.955025 166.612979)
		(width 0.148)
		(layer "In2.Cu")
		(net 70)
	)
	(segment
		(start 115.591025 160.248981)
		(end 115.591026 160.24898)
		(width 0.148)
		(layer "In2.Cu")
		(net 70)
	)
	(segment
		(start 118.419469 163.077425)
		(end 118.41947 163.077424)
		(width 0.148)
		(layer "In2.Cu")
		(net 70)
	)
	(segment
		(start 119.833693 164.845201)
		(end 119.833692 164.8452)
		(width 0.148)
		(layer "In2.Cu")
		(net 70)
	)
	(segment
		(start 123.434899 167.25444)
		(end 123.434898 167.254441)
		(width 0.148)
		(layer "In2.Cu")
		(net 70)
	)
	(segment
		(start 117.71236 162.723868)
		(end 117.712359 162.723867)
		(width 0.148)
		(layer "In2.Cu")
		(net 70)
	)
	(segment
		(start 132.924501 168.4275)
		(end 132.900501 168.4035)
		(width 0.1)
		(layer "In2.Cu")
		(net 70)
	)
	(segment
		(start 122.020675 165.840219)
		(end 121.601468 166.259422)
		(width 0.148)
		(layer "In2.Cu")
		(net 70)
	)
	(segment
		(start 111.900001 148.4775)
		(end 111.900001 147.2775)
		(width 0.148)
		(layer "In2.Cu")
		(net 70)
	)
	(segment
		(start 136.877001 168.8025)
		(end 136.353501 169.326)
		(width 0.1)
		(layer "In2.Cu")
		(net 70)
	)
	(segment
		(start 121.667119 165.133109)
		(end 121.667118 165.133108)
		(width 0.148)
		(layer "In2.Cu")
		(net 70)
	)
	(segment
		(start 136.353501 169.326)
		(end 134.650501 169.326)
		(width 0.1)
		(layer "In2.Cu")
		(net 70)
	)
	(segment
		(start 117.070898 160.890442)
		(end 116.651691 161.309645)
		(width 0.148)
		(layer "In2.Cu")
		(net 70)
	)
	(segment
		(start 119.545786 163.011776)
		(end 119.545785 163.011775)
		(width 0.148)
		(layer "In2.Cu")
		(net 70)
	)
	(segment
		(start 119.833691 164.491647)
		(end 119.833692 164.491646)
		(width 0.148)
		(layer "In2.Cu")
		(net 70)
	)
	(segment
		(start 117.712359 162.370313)
		(end 118.131563 161.951107)
		(width 0.148)
		(layer "In2.Cu")
		(net 70)
	)
	(segment
		(start 116.010231 159.476221)
		(end 116.01023 159.47622)
		(width 0.148)
		(layer "In2.Cu")
		(net 70)
	)
	(segment
		(start 121.313565 165.133107)
		(end 121.313564 165.133108)
		(width 0.148)
		(layer "In2.Cu")
		(net 70)
	)
	(segment
		(start 123.755625 167.640822)
		(end 123.788452 167.607994)
		(width 0.148)
		(layer "In2.Cu")
		(net 70)
	)
	(segment
		(start 113.25 149.827499)
		(end 111.900001 148.4775)
		(width 0.148)
		(layer "In2.Cu")
		(net 70)
	)
	(segment
		(start 118.485121 162.304663)
		(end 118.48512 162.304664)
		(width 0.148)
		(layer "In2.Cu")
		(net 70)
	)
	(segment
		(start 123.788451 167.254441)
		(end 123.788452 167.254441)
		(width 0.148)
		(layer "In2.Cu")
		(net 70)
	)
	(segment
		(start 118.419471 163.430979)
		(end 118.41947 163.430978)
		(width 0.148)
		(layer "In2.Cu")
		(net 70)
	)
	(segment
		(start 118.41947 163.077424)
		(end 118.838674 162.658218)
		(width 0.148)
		(layer "In2.Cu")
		(net 70)
	)
	(segment
		(start 122.37423 165.84022)
		(end 122.374229 165.840219)
		(width 0.148)
		(layer "In2.Cu")
		(net 70)
	)
	(segment
		(start 119.192232 163.011774)
		(end 119.192231 163.011775)
		(width 0.148)
		(layer "In2.Cu")
		(net 70)
	)
	(segment
		(start 121.247913 165.905869)
		(end 121.247914 165.905868)
		(width 0.148)
		(layer "In2.Cu")
		(net 70)
	)
	(segment
		(start 118.131564 161.597554)
		(end 118.131563 161.597553)
		(width 0.148)
		(layer "In2.Cu")
		(net 70)
	)
	(segment
		(start 119.126582 164.13809)
		(end 119.126581 164.138089)
		(width 0.148)
		(layer "In2.Cu")
		(net 70)
	)
	(segment
		(start 114.883916 159.895424)
		(end 114.883915 159.895423)
		(width 0.148)
		(layer "In2.Cu")
		(net 70)
	)
	(segment
		(start 124.037251 168.276)
		(end 123.755626 167.994375)
		(width 0.148)
		(layer "In2.Cu")
		(net 70)
	)
	(segment
		(start 113.25 157.488748)
		(end 113.25 149.827499)
		(width 0.148)
		(layer "In2.Cu")
		(net 70)
	)
	(segment
		(start 123.434898 167.254441)
		(end 123.01569 167.673644)
		(width 0.148)
		(layer "In2.Cu")
		(net 70)
	)
	(segment
		(start 116.298138 161.309646)
		(end 116.298137 161.309645)
		(width 0.148)
		(layer "In2.Cu")
		(net 70)
	)
	(segment
		(start 117.005248 161.663202)
		(end 117.424452 161.243996)
		(width 0.148)
		(layer "In2.Cu")
		(net 70)
	)
	(arc
		(start 123.788452 167.254441)
		(mid 123.611676 167.181217)
		(end 123.434899 167.25444)
		(width 0.148)
		(layer "In2.Cu")
		(net 70)
	)
	(arc
		(start 123.788452 167.607994)
		(mid 123.861675 167.431217)
		(end 123.788451 167.254441)
		(width 0.148)
		(layer "In2.Cu")
		(net 70)
	)
	(arc
		(start 120.894357 165.552311)
		(mid 120.717581 165.625535)
		(end 120.540804 165.552312)
		(width 0.148)
		(layer "In2.Cu")
		(net 70)
	)
	(arc
		(start 120.187246 164.8452)
		(mid 120.01047 164.918424)
		(end 119.833693 164.845201)
		(width 0.148)
		(layer "In2.Cu")
		(net 70)
	)
	(arc
		(start 122.308579 166.966533)
		(mid 122.131803 167.039757)
		(end 121.955026 166.966534)
		(width 0.148)
		(layer "In2.Cu")
		(net 70)
	)
	(arc
		(start 123.01569 167.673644)
		(mid 122.838914 167.746868)
		(end 122.662137 167.673645)
		(width 0.148)
		(layer "In2.Cu")
		(net 70)
	)
	(arc
		(start 122.374229 166.193773)
		(mid 122.447453 166.016997)
		(end 122.37423 165.84022)
		(width 0.148)
		(layer "In2.Cu")
		(net 70)
	)
	(arc
		(start 118.773024 163.430978)
		(mid 118.596248 163.504202)
		(end 118.419471 163.430979)
		(width 0.148)
		(layer "In2.Cu")
		(net 70)
	)
	(arc
		(start 120.960007 164.779551)
		(mid 121.033231 164.602775)
		(end 120.960008 164.425998)
		(width 0.148)
		(layer "In2.Cu")
		(net 70)
	)
	(arc
		(start 116.651691 161.309645)
		(mid 116.474915 161.382869)
		(end 116.298138 161.309646)
		(width 0.148)
		(layer "In2.Cu")
		(net 70)
	)
	(arc
		(start 121.667118 165.133108)
		(mid 121.490342 165.059884)
		(end 121.313565 165.133107)
		(width 0.148)
		(layer "In2.Cu")
		(net 70)
	)
	(arc
		(start 122.662136 167.673644)
		(mid 122.588912 167.496868)
		(end 122.662135 167.320091)
		(width 0.148)
		(layer "In2.Cu")
		(net 70)
	)
	(arc
		(start 123.08134 166.900884)
		(mid 123.154564 166.724108)
		(end 123.081341 166.547331)
		(width 0.148)
		(layer "In2.Cu")
		(net 70)
	)
	(arc
		(start 121.247914 166.259422)
		(mid 121.17469 166.082646)
		(end 121.247913 165.905869)
		(width 0.148)
		(layer "In2.Cu")
		(net 70)
	)
	(arc
		(start 116.01023 159.47622)
		(mid 115.833454 159.402996)
		(end 115.656677 159.476219)
		(width 0.148)
		(layer "In2.Cu")
		(net 70)
	)
	(arc
		(start 117.424452 160.890442)
		(mid 117.247676 160.817218)
		(end 117.070899 160.890441)
		(width 0.148)
		(layer "In2.Cu")
		(net 70)
	)
	(arc
		(start 116.298137 161.309645)
		(mid 116.224913 161.132869)
		(end 116.298136 160.956092)
		(width 0.148)
		(layer "In2.Cu")
		(net 70)
	)
	(arc
		(start 121.667118 165.486662)
		(mid 121.740342 165.309886)
		(end 121.667119 165.133109)
		(width 0.148)
		(layer "In2.Cu")
		(net 70)
	)
	(arc
		(start 116.717341 160.536885)
		(mid 116.790565 160.360109)
		(end 116.717342 160.183332)
		(width 0.148)
		(layer "In2.Cu")
		(net 70)
	)
	(arc
		(start 115.237469 159.895423)
		(mid 115.060693 159.968647)
		(end 114.883916 159.895424)
		(width 0.148)
		(layer "In2.Cu")
		(net 70)
	)
	(arc
		(start 120.252896 164.07244)
		(mid 120.32612 163.895664)
		(end 120.252897 163.718887)
		(width 0.148)
		(layer "In2.Cu")
		(net 70)
	)
	(arc
		(start 118.838674 162.304664)
		(mid 118.661898 162.23144)
		(end 118.485121 162.304663)
		(width 0.148)
		(layer "In2.Cu")
		(net 70)
	)
	(arc
		(start 117.005248 162.016756)
		(mid 116.932024 161.83998)
		(end 117.005247 161.663203)
		(width 0.148)
		(layer "In2.Cu")
		(net 70)
	)
	(arc
		(start 122.374229 165.840219)
		(mid 122.197453 165.766995)
		(end 122.020676 165.840218)
		(width 0.148)
		(layer "In2.Cu")
		(net 70)
	)
	(arc
		(start 121.601468 166.259422)
		(mid 121.424692 166.332646)
		(end 121.247915 166.259423)
		(width 0.148)
		(layer "In2.Cu")
		(net 70)
	)
	(arc
		(start 119.480135 164.138089)
		(mid 119.303359 164.211313)
		(end 119.126582 164.13809)
		(width 0.148)
		(layer "In2.Cu")
		(net 70)
	)
	(arc
		(start 123.08134 166.54733)
		(mid 122.904564 166.474106)
		(end 122.727787 166.547329)
		(width 0.148)
		(layer "In2.Cu")
		(net 70)
	)
	(arc
		(start 116.01023 159.829774)
		(mid 116.083454 159.652998)
		(end 116.010231 159.476221)
		(width 0.148)
		(layer "In2.Cu")
		(net 70)
	)
	(arc
		(start 118.131563 161.597553)
		(mid 117.954787 161.524329)
		(end 117.77801 161.597552)
		(width 0.148)
		(layer "In2.Cu")
		(net 70)
	)
	(arc
		(start 119.833692 164.8452)
		(mid 119.760468 164.668424)
		(end 119.833691 164.491647)
		(width 0.148)
		(layer "In2.Cu")
		(net 70)
	)
	(arc
		(start 115.94458 160.602534)
		(mid 115.767804 160.675758)
		(end 115.591027 160.602535)
		(width 0.148)
		(layer "In2.Cu")
		(net 70)
	)
	(arc
		(start 116.717341 160.183331)
		(mid 116.540565 160.110107)
		(end 116.363788 160.18333)
		(width 0.148)
		(layer "In2.Cu")
		(net 70)
	)
	(arc
		(start 117.358802 162.016756)
		(mid 117.182026 162.08998)
		(end 117.005249 162.016757)
		(width 0.148)
		(layer "In2.Cu")
		(net 70)
	)
	(arc
		(start 118.065913 162.723867)
		(mid 117.889137 162.797091)
		(end 117.71236 162.723868)
		(width 0.148)
		(layer "In2.Cu")
		(net 70)
	)
	(arc
		(start 118.41947 163.430978)
		(mid 118.346246 163.254202)
		(end 118.419469 163.077425)
		(width 0.148)
		(layer "In2.Cu")
		(net 70)
	)
	(arc
		(start 115.591026 160.602534)
		(mid 115.517802 160.425758)
		(end 115.591025 160.248981)
		(width 0.148)
		(layer "In2.Cu")
		(net 70)
	)
	(arc
		(start 114.883915 159.895423)
		(mid 114.810691 159.718647)
		(end 114.883914 159.54187)
		(width 0.148)
		(layer "In2.Cu")
		(net 70)
	)
	(arc
		(start 120.960007 164.425997)
		(mid 120.783231 164.352773)
		(end 120.606454 164.425996)
		(width 0.148)
		(layer "In2.Cu")
		(net 70)
	)
	(arc
		(start 117.712359 162.723867)
		(mid 117.639135 162.547091)
		(end 117.712358 162.370314)
		(width 0.148)
		(layer "In2.Cu")
		(net 70)
	)
	(arc
		(start 118.838674 162.658218)
		(mid 118.911898 162.481442)
		(end 118.838675 162.304665)
		(width 0.148)
		(layer "In2.Cu")
		(net 70)
	)
	(arc
		(start 123.755626 167.994375)
		(mid 123.682402 167.817599)
		(end 123.755625 167.640822)
		(width 0.148)
		(layer "In2.Cu")
		(net 70)
	)
	(arc
		(start 121.955025 166.966533)
		(mid 121.881801 166.789757)
		(end 121.955024 166.61298)
		(width 0.148)
		(layer "In2.Cu")
		(net 70)
	)
	(arc
		(start 120.540803 165.552311)
		(mid 120.467579 165.375535)
		(end 120.540802 165.198758)
		(width 0.148)
		(layer "In2.Cu")
		(net 70)
	)
	(arc
		(start 117.424452 161.243996)
		(mid 117.497676 161.06722)
		(end 117.424453 160.890443)
		(width 0.148)
		(layer "In2.Cu")
		(net 70)
	)
	(arc
		(start 119.545785 163.365329)
		(mid 119.619009 163.188553)
		(end 119.545786 163.011776)
		(width 0.148)
		(layer "In2.Cu")
		(net 70)
	)
	(arc
		(start 119.545785 163.011775)
		(mid 119.369009 162.938551)
		(end 119.192232 163.011774)
		(width 0.148)
		(layer "In2.Cu")
		(net 70)
	)
	(arc
		(start 120.252896 163.718886)
		(mid 120.07612 163.645662)
		(end 119.899343 163.718885)
		(width 0.148)
		(layer "In2.Cu")
		(net 70)
	)
	(arc
		(start 119.126581 164.138089)
		(mid 119.053357 163.961313)
		(end 119.12658 163.784536)
		(width 0.148)
		(layer "In2.Cu")
		(net 70)
	)
	(arc
		(start 114.916742 159.509043)
		(mid 114.989965 159.332266)
		(end 114.916741 159.15549)
		(width 0.148)
		(layer "In2.Cu")
		(net 70)
	)
	(arc
		(start 118.131563 161.951107)
		(mid 118.204787 161.774331)
		(end 118.131564 161.597554)
		(width 0.148)
		(layer "In2.Cu")
		(net 70)
	)
	(segment
		(start 136.3765 169.302)
		(end 135.877001 168.8025)
		(width 0.256)
		(layer "F.Cu")
		(net 71)
	)
	(segment
		(start 112.650001 138.8025)
		(end 112.650001 139.8775)
		(width 0.201)
		(layer "F.Cu")
		(net 71)
	)
	(via
		(at 135.877001 168.8025)
		(size 0.45)
		(drill 0.1)
		(layers "F.Cu" "B.Cu")
		(net 71)
	)
	(via
		(at 112.650001 139.8775)
		(size 0.45)
		(drill 0.1)
		(layers "F.Cu" "B.Cu")
		(net 71)
	)
	(segment
		(start 115.009304 156.45)
		(end 114.75 156.45)
		(width 0.148)
		(layer "In2.Cu")
		(net 71)
	)
	(segment
		(start 112.4 146.7)
		(end 112.4 148)
		(width 0.148)
		(layer "In2.Cu")
		(net 71)
	)
	(segment
		(start 114.5 157.375)
		(end 124.401 167.276)
		(width 0.148)
		(layer "In2.Cu")
		(net 71)
	)
	(segment
		(start 133.290174 167.967673)
		(end 133.5 168.177499)
		(width 0.1)
		(layer "In2.Cu")
		(net 71)
	)
	(segment
		(start 114.75 150.95)
		(end 115.009304 150.95)
		(width 0.148)
		(layer "In2.Cu")
		(net 71)
	)
	(segment
		(start 114.5 150.1)
		(end 114.5 150.7)
		(width 0.148)
		(layer "In2.Cu")
		(net 71)
	)
	(segment
		(start 135.625001 168.8025)
		(end 135.877001 168.8025)
		(width 0.1)
		(layer "In2.Cu")
		(net 71)
	)
	(segment
		(start 132.975001 167.3025)
		(end 133.290174 167.617673)
		(width 0.1)
		(layer "In2.Cu")
		(net 71)
	)
	(segment
		(start 133.5 168.177499)
		(end 135 168.177499)
		(width 0.1)
		(layer "In2.Cu")
		(net 71)
	)
	(segment
		(start 132.948501 167.276)
		(end 132.975001 167.3025)
		(width 0.148)
		(layer "In2.Cu")
		(net 71)
	)
	(segment
		(start 113.990696 151.95)
		(end 115.009304 151.95)
		(width 0.148)
		(layer "In2.Cu")
		(net 71)
	)
	(segment
		(start 113.990696 153.95)
		(end 115.009304 153.95)
		(width 0.148)
		(layer "In2.Cu")
		(net 71)
	)
	(segment
		(start 113.990696 155.95)
		(end 115.009304 155.95)
		(width 0.148)
		(layer "In2.Cu")
		(net 71)
	)
	(segment
		(start 133.290174 167.617673)
		(end 133.290174 167.967673)
		(width 0.1)
		(layer "In2.Cu")
		(net 71)
	)
	(segment
		(start 113.990696 154.95)
		(end 115.009304 154.95)
		(width 0.148)
		(layer "In2.Cu")
		(net 71)
	)
	(segment
		(start 112.650001 139.8775)
		(end 112.9 140.127499)
		(width 0.148)
		(layer "In2.Cu")
		(net 71)
	)
	(segment
		(start 112.9 140.127499)
		(end 112.9 146.2)
		(width 0.148)
		(layer "In2.Cu")
		(net 71)
	)
	(segment
		(start 112.4 148)
		(end 114.5 150.1)
		(width 0.148)
		(layer "In2.Cu")
		(net 71)
	)
	(segment
		(start 112.9 146.2)
		(end 112.4 146.7)
		(width 0.148)
		(layer "In2.Cu")
		(net 71)
	)
	(segment
		(start 113.990696 151.45)
		(end 115.009304 151.45)
		(width 0.148)
		(layer "In2.Cu")
		(net 71)
	)
	(segment
		(start 113.990696 155.45)
		(end 115.009304 155.45)
		(width 0.148)
		(layer "In2.Cu")
		(net 71)
	)
	(segment
		(start 113.990696 152.45)
		(end 115.009304 152.45)
		(width 0.148)
		(layer "In2.Cu")
		(net 71)
	)
	(segment
		(start 113.990696 152.95)
		(end 115.009304 152.95)
		(width 0.148)
		(layer "In2.Cu")
		(net 71)
	)
	(segment
		(start 124.401 167.276)
		(end 132.948501 167.276)
		(width 0.148)
		(layer "In2.Cu")
		(net 71)
	)
	(segment
		(start 113.990696 153.45)
		(end 115.009304 153.45)
		(width 0.148)
		(layer "In2.Cu")
		(net 71)
	)
	(segment
		(start 135 168.177499)
		(end 135.625001 168.8025)
		(width 0.1)
		(layer "In2.Cu")
		(net 71)
	)
	(segment
		(start 114.5 156.7)
		(end 114.5 157.375)
		(width 0.148)
		(layer "In2.Cu")
		(net 71)
	)
	(segment
		(start 113.990696 154.45)
		(end 115.009304 154.45)
		(width 0.148)
		(layer "In2.Cu")
		(net 71)
	)
	(arc
		(start 115.009304 152.95)
		(mid 115.186081 153.023223)
		(end 115.259304 153.2)
		(width 0.148)
		(layer "In2.Cu")
		(net 71)
	)
	(arc
		(start 113.990696 151.45)
		(mid 113.813919 151.523223)
		(end 113.740696 151.7)
		(width 0.148)
		(layer "In2.Cu")
		(net 71)
	)
	(arc
		(start 113.990696 155.45)
		(mid 113.813919 155.523223)
		(end 113.740696 155.7)
		(width 0.148)
		(layer "In2.Cu")
		(net 71)
	)
	(arc
		(start 115.259304 153.2)
		(mid 115.186081 153.376777)
		(end 115.009304 153.45)
		(width 0.148)
		(layer "In2.Cu")
		(net 71)
	)
	(arc
		(start 115.259304 156.2)
		(mid 115.186081 156.376777)
		(end 115.009304 156.45)
		(width 0.148)
		(layer "In2.Cu")
		(net 71)
	)
	(arc
		(start 115.009304 155.95)
		(mid 115.186081 156.023223)
		(end 115.259304 156.2)
		(width 0.148)
		(layer "In2.Cu")
		(net 71)
	)
	(arc
		(start 114.75 156.45)
		(mid 114.573223 156.523223)
		(end 114.5 156.7)
		(width 0.148)
		(layer "In2.Cu")
		(net 71)
	)
	(arc
		(start 113.740696 154.7)
		(mid 113.813919 154.876777)
		(end 113.990696 154.95)
		(width 0.148)
		(layer "In2.Cu")
		(net 71)
	)
	(arc
		(start 115.259304 152.2)
		(mid 115.186081 152.376777)
		(end 115.009304 152.45)
		(width 0.148)
		(layer "In2.Cu")
		(net 71)
	)
	(arc
		(start 115.009304 151.95)
		(mid 115.186081 152.023223)
		(end 115.259304 152.2)
		(width 0.148)
		(layer "In2.Cu")
		(net 71)
	)
	(arc
		(start 115.259304 154.2)
		(mid 115.186081 154.376777)
		(end 115.009304 154.45)
		(width 0.148)
		(layer "In2.Cu")
		(net 71)
	)
	(arc
		(start 115.009304 153.95)
		(mid 115.186081 154.023223)
		(end 115.259304 154.2)
		(width 0.148)
		(layer "In2.Cu")
		(net 71)
	)
	(arc
		(start 115.009304 154.95)
		(mid 115.186081 155.023223)
		(end 115.259304 155.2)
		(width 0.148)
		(layer "In2.Cu")
		(net 71)
	)
	(arc
		(start 113.990696 153.45)
		(mid 113.813919 153.523223)
		(end 113.740696 153.7)
		(width 0.148)
		(layer "In2.Cu")
		(net 71)
	)
	(arc
		(start 115.009304 150.95)
		(mid 115.186081 151.023223)
		(end 115.259304 151.2)
		(width 0.148)
		(layer "In2.Cu")
		(net 71)
	)
	(arc
		(start 113.740696 151.7)
		(mid 113.813919 151.876777)
		(end 113.990696 151.95)
		(width 0.148)
		(layer "In2.Cu")
		(net 71)
	)
	(arc
		(start 113.990696 152.45)
		(mid 113.813919 152.523223)
		(end 113.740696 152.7)
		(width 0.148)
		(layer "In2.Cu")
		(net 71)
	)
	(arc
		(start 113.740696 155.7)
		(mid 113.813919 155.876777)
		(end 113.990696 155.95)
		(width 0.148)
		(layer "In2.Cu")
		(net 71)
	)
	(arc
		(start 115.259304 155.2)
		(mid 115.186081 155.376777)
		(end 115.009304 155.45)
		(width 0.148)
		(layer "In2.Cu")
		(net 71)
	)
	(arc
		(start 115.259304 151.2)
		(mid 115.186081 151.376777)
		(end 115.009304 151.45)
		(width 0.148)
		(layer "In2.Cu")
		(net 71)
	)
	(arc
		(start 113.740696 152.7)
		(mid 113.813919 152.876777)
		(end 113.990696 152.95)
		(width 0.148)
		(layer "In2.Cu")
		(net 71)
	)
	(arc
		(start 113.990696 154.45)
		(mid 113.813919 154.523223)
		(end 113.740696 154.7)
		(width 0.148)
		(layer "In2.Cu")
		(net 71)
	)
	(arc
		(start 114.5 150.7)
		(mid 114.573223 150.876777)
		(end 114.75 150.95)
		(width 0.148)
		(layer "In2.Cu")
		(net 71)
	)
	(arc
		(start 113.740696 153.7)
		(mid 113.813919 153.876777)
		(end 113.990696 153.95)
		(width 0.148)
		(layer "In2.Cu")
		(net 71)
	)
	(segment
		(start 135.376501 168.302)
		(end 134.877001 167.8025)
		(width 0.256)
		(layer "F.Cu")
		(net 72)
	)
	(segment
		(start 112.900001 146.2025)
		(end 112.900001 147.2775)
		(width 0.201)
		(layer "F.Cu")
		(net 72)
	)
	(via
		(at 134.877001 167.8025)
		(size 0.45)
		(drill 0.1)
		(layers "F.Cu" "B.Cu")
		(net 72)
	)
	(via
		(at 112.900001 147.2775)
		(size 0.45)
		(drill 0.1)
		(layers "F.Cu" "B.Cu")
		(net 72)
	)
	(segment
		(start 133.5 167.427499)
		(end 133.252001 167.1795)
		(width 0.1)
		(layer "In2.Cu")
		(net 72)
	)
	(segment
		(start 119.194541 159.784592)
		(end 119.19454 159.784591)
		(width 0.148)
		(layer "In2.Cu")
		(net 72)
	)
	(segment
		(start 134.157333 167.5525)
		(end 134.032332 167.427499)
		(width 0.1)
		(layer "In2.Cu")
		(net 72)
	)
	(segment
		(start 118.487431 159.077482)
		(end 118.48743 159.077481)
		(width 0.148)
		(layer "In2.Cu")
		(net 72)
	)
	(segment
		(start 120.255206 161.198811)
		(end 119.698809 161.755204)
		(width 0.148)
		(layer "In2.Cu")
		(net 72)
	)
	(segment
		(start 122.730091 163.320142)
		(end 122.73009 163.320141)
		(width 0.148)
		(layer "In2.Cu")
		(net 72)
	)
	(segment
		(start 115.8 157.299999)
		(end 115.8 150.177499)
		(width 0.148)
		(layer "In2.Cu")
		(net 72)
	)
	(segment
		(start 118.840986 159.784591)
		(end 118.284589 160.340984)
		(width 0.148)
		(layer "In2.Cu")
		(net 72)
	)
	(segment
		(start 123.083646 164.027251)
		(end 122.527249 164.583644)
		(width 0.148)
		(layer "In2.Cu")
		(net 72)
	)
	(segment
		(start 119.548096 160.491701)
		(end 118.991699 161.048094)
		(width 0.148)
		(layer "In2.Cu")
		(net 72)
	)
	(segment
		(start 118.133876 159.077481)
		(end 117.577479 159.633874)
		(width 0.148)
		(layer "In2.Cu")
		(net 72)
	)
	(segment
		(start 124.144311 164.734362)
		(end 124.14431 164.734361)
		(width 0.148)
		(layer "In2.Cu")
		(net 72)
	)
	(segment
		(start 123.587914 165.644311)
		(end 124.14431 165.087915)
		(width 0.148)
		(layer "In2.Cu")
		(net 72)
	)
	(segment
		(start 123.587916 165.997865)
		(end 123.587915 165.997864)
		(width 0.148)
		(layer "In2.Cu")
		(net 72)
	)
	(segment
		(start 122.173694 164.230091)
		(end 122.73009 163.673695)
		(width 0.148)
		(layer "In2.Cu")
		(net 72)
	)
	(segment
		(start 119.548097 160.4917)
		(end 119.548096 160.491701)
		(width 0.148)
		(layer "In2.Cu")
		(net 72)
	)
	(segment
		(start 122.173696 164.583645)
		(end 122.173695 164.583644)
		(width 0.148)
		(layer "In2.Cu")
		(net 72)
	)
	(segment
		(start 117.426766 158.370371)
		(end 116.870369 158.926764)
		(width 0.148)
		(layer "In2.Cu")
		(net 72)
	)
	(segment
		(start 123.790756 164.734361)
		(end 123.234359 165.290754)
		(width 0.148)
		(layer "In2.Cu")
		(net 72)
	)
	(segment
		(start 120.759474 162.815871)
		(end 121.31587 162.259475)
		(width 0.148)
		(layer "In2.Cu")
		(net 72)
	)
	(segment
		(start 124.497867 165.441471)
		(end 123.941469 165.997864)
		(width 0.148)
		(layer "In2.Cu")
		(net 72)
	)
	(segment
		(start 123.083647 164.02725)
		(end 123.083646 164.027251)
		(width 0.148)
		(layer "In2.Cu")
		(net 72)
	)
	(segment
		(start 120.052364 162.108761)
		(end 120.60876 161.552365)
		(width 0.148)
		(layer "In2.Cu")
		(net 72)
	)
	(segment
		(start 134.877001 167.8025)
		(end 134.627001 167.5525)
		(width 0.1)
		(layer "In2.Cu")
		(net 72)
	)
	(segment
		(start 124.85142 165.441471)
		(end 124.851421 165.441471)
		(width 0.148)
		(layer "In2.Cu")
		(net 72)
	)
	(segment
		(start 119.901651 160.491702)
		(end 119.90165 160.491701)
		(width 0.148)
		(layer "In2.Cu")
		(net 72)
	)
	(segment
		(start 122.880804 164.937201)
		(end 123.4372 164.380805)
		(width 0.148)
		(layer "In2.Cu")
		(net 72)
	)
	(segment
		(start 134.627001 167.5525)
		(end 134.157333 167.5525)
		(width 0.1)
		(layer "In2.Cu")
		(net 72)
	)
	(segment
		(start 122.880806 165.290755)
		(end 122.880805 165.290754)
		(width 0.148)
		(layer "In2.Cu")
		(net 72)
	)
	(segment
		(start 116.618236 158.118236)
		(end 116.618236 158.118235)
		(width 0.148)
		(layer "In2.Cu")
		(net 72)
	)
	(segment
		(start 121.466586 163.876535)
		(end 121.466585 163.876534)
		(width 0.148)
		(layer "In2.Cu")
		(net 72)
	)
	(segment
		(start 120.759476 163.169425)
		(end 120.759475 163.169424)
		(width 0.148)
		(layer "In2.Cu")
		(net 72)
	)
	(segment
		(start 120.608761 161.198812)
		(end 120.60876 161.198811)
		(width 0.148)
		(layer "In2.Cu")
		(net 72)
	)
	(segment
		(start 132.075001 166.3025)
		(end 124.8025 166.3025)
		(width 0.148)
		(layer "In2.Cu")
		(net 72)
	)
	(segment
		(start 132.175001 166.4025)
		(end 132.075001 166.3025)
		(width 0.1)
		(layer "In2.Cu")
		(net 72)
	)
	(segment
		(start 118.638144 160.694541)
		(end 119.19454 160.138145)
		(width 0.148)
		(layer "In2.Cu")
		(net 72)
	)
	(segment
		(start 123.437201 164.027252)
		(end 123.4372 164.027251)
		(width 0.148)
		(layer "In2.Cu")
		(net 72)
	)
	(segment
		(start 116.516816 158.926765)
		(end 116.516815 158.926764)
		(width 0.148)
		(layer "In2.Cu")
		(net 72)
	)
	(segment
		(start 118.133877 159.07748)
		(end 118.133876 159.077481)
		(width 0.148)
		(layer "In2.Cu")
		(net 72)
	)
	(segment
		(start 117.931036 160.340985)
		(end 117.931035 160.340984)
		(width 0.148)
		(layer "In2.Cu")
		(net 72)
	)
	(segment
		(start 122.376537 163.32014)
		(end 122.376536 163.320141)
		(width 0.148)
		(layer "In2.Cu")
		(net 72)
	)
	(segment
		(start 134.032332 167.427499)
		(end 133.5 167.427499)
		(width 0.1)
		(layer "In2.Cu")
		(net 72)
	)
	(segment
		(start 121.466584 163.522981)
		(end 122.02298 162.966585)
		(width 0.148)
		(layer "In2.Cu")
		(net 72)
	)
	(segment
		(start 116.516814 158.573211)
		(end 116.618237 158.471789)
		(width 0.148)
		(layer "In2.Cu")
		(net 72)
	)
	(segment
		(start 133.252001 166.647169)
		(end 133.007332 166.4025)
		(width 0.1)
		(layer "In2.Cu")
		(net 72)
	)
	(segment
		(start 115.8 150.177499)
		(end 112.900001 147.2775)
		(width 0.148)
		(layer "In2.Cu")
		(net 72)
	)
	(segment
		(start 133.007332 166.4025)
		(end 132.175001 166.4025)
		(width 0.1)
		(layer "In2.Cu")
		(net 72)
	)
	(segment
		(start 120.255207 161.19881)
		(end 120.255206 161.198811)
		(width 0.148)
		(layer "In2.Cu")
		(net 72)
	)
	(segment
		(start 123.790757 164.73436)
		(end 123.790756 164.734361)
		(width 0.148)
		(layer "In2.Cu")
		(net 72)
	)
	(segment
		(start 121.315871 161.905922)
		(end 121.31587 161.905921)
		(width 0.148)
		(layer "In2.Cu")
		(net 72)
	)
	(segment
		(start 119.345256 161.755205)
		(end 119.345255 161.755204)
		(width 0.148)
		(layer "In2.Cu")
		(net 72)
	)
	(segment
		(start 117.780321 158.370372)
		(end 117.78032 158.370371)
		(width 0.148)
		(layer "In2.Cu")
		(net 72)
	)
	(segment
		(start 133.252001 167.1795)
		(end 133.252001 166.647169)
		(width 0.1)
		(layer "In2.Cu")
		(net 72)
	)
	(segment
		(start 118.638146 161.048095)
		(end 118.638145 161.048094)
		(width 0.148)
		(layer "In2.Cu")
		(net 72)
	)
	(segment
		(start 124.8025 166.3025)
		(end 124.75 166.25)
		(width 0.148)
		(layer "In2.Cu")
		(net 72)
	)
	(segment
		(start 124.749999 165.896447)
		(end 124.851421 165.795024)
		(width 0.148)
		(layer "In2.Cu")
		(net 72)
	)
	(segment
		(start 122.022981 162.613032)
		(end 122.02298 162.613031)
		(width 0.148)
		(layer "In2.Cu")
		(net 72)
	)
	(segment
		(start 117.931034 159.987431)
		(end 118.48743 159.431035)
		(width 0.148)
		(layer "In2.Cu")
		(net 72)
	)
	(segment
		(start 122.376536 163.320141)
		(end 121.820139 163.876534)
		(width 0.148)
		(layer "In2.Cu")
		(net 72)
	)
	(segment
		(start 120.052366 162.462315)
		(end 120.052365 162.462314)
		(width 0.148)
		(layer "In2.Cu")
		(net 72)
	)
	(segment
		(start 120.962316 161.905921)
		(end 120.405919 162.462314)
		(width 0.148)
		(layer "In2.Cu")
		(net 72)
	)
	(segment
		(start 117.223926 159.633875)
		(end 117.223925 159.633874)
		(width 0.148)
		(layer "In2.Cu")
		(net 72)
	)
	(segment
		(start 124.497868 165.44147)
		(end 124.497867 165.441471)
		(width 0.148)
		(layer "In2.Cu")
		(net 72)
	)
	(segment
		(start 120.962317 161.90592)
		(end 120.962316 161.905921)
		(width 0.148)
		(layer "In2.Cu")
		(net 72)
	)
	(segment
		(start 117.426767 158.37037)
		(end 117.426766 158.370371)
		(width 0.148)
		(layer "In2.Cu")
		(net 72)
	)
	(segment
		(start 118.840987 159.78459)
		(end 118.840986 159.784591)
		(width 0.148)
		(layer "In2.Cu")
		(net 72)
	)
	(segment
		(start 116.618236 158.118235)
		(end 115.8 157.299999)
		(width 0.148)
		(layer "In2.Cu")
		(net 72)
	)
	(segment
		(start 117.223924 159.280321)
		(end 117.78032 158.723925)
		(width 0.148)
		(layer "In2.Cu")
		(net 72)
	)
	(segment
		(start 121.669427 162.61303)
		(end 121.669426 162.613031)
		(width 0.148)
		(layer "In2.Cu")
		(net 72)
	)
	(segment
		(start 119.345254 161.401651)
		(end 119.90165 160.845255)
		(width 0.148)
		(layer "In2.Cu")
		(net 72)
	)
	(segment
		(start 121.669426 162.613031)
		(end 121.113029 163.169424)
		(width 0.148)
		(layer "In2.Cu")
		(net 72)
	)
	(arc
		(start 120.405919 162.462314)
		(mid 120.229143 162.535538)
		(end 120.052366 162.462315)
		(width 0.148)
		(layer "In2.Cu")
		(net 72)
	)
	(arc
		(start 118.48743 159.431035)
		(mid 118.560654 159.254259)
		(end 118.487431 159.077482)
		(width 0.148)
		(layer "In2.Cu")
		(net 72)
	)
	(arc
		(start 116.618237 158.471789)
		(mid 116.69146 158.295012)
		(end 116.618236 158.118236)
		(width 0.148)
		(layer "In2.Cu")
		(net 72)
	)
	(arc
		(start 122.880805 165.290754)
		(mid 122.807581 165.113978)
		(end 122.880804 164.937201)
		(width 0.148)
		(layer "In2.Cu")
		(net 72)
	)
	(arc
		(start 124.14431 165.087915)
		(mid 124.217534 164.911139)
		(end 124.144311 164.734362)
		(width 0.148)
		(layer "In2.Cu")
		(net 72)
	)
	(arc
		(start 118.991699 161.048094)
		(mid 118.814923 161.121318)
		(end 118.638146 161.048095)
		(width 0.148)
		(layer "In2.Cu")
		(net 72)
	)
	(arc
		(start 120.60876 161.552365)
		(mid 120.681984 161.375589)
		(end 120.608761 161.198812)
		(width 0.148)
		(layer "In2.Cu")
		(net 72)
	)
	(arc
		(start 123.234359 165.290754)
		(mid 123.057583 165.363978)
		(end 122.880806 165.290755)
		(width 0.148)
		(layer "In2.Cu")
		(net 72)
	)
	(arc
		(start 120.759475 163.169424)
		(mid 120.686251 162.992648)
		(end 120.759474 162.815871)
		(width 0.148)
		(layer "In2.Cu")
		(net 72)
	)
	(arc
		(start 122.02298 162.966585)
		(mid 122.096204 162.789809)
		(end 122.022981 162.613032)
		(width 0.148)
		(layer "In2.Cu")
		(net 72)
	)
	(arc
		(start 119.90165 160.491701)
		(mid 119.724874 160.418477)
		(end 119.548097 160.4917)
		(width 0.148)
		(layer "In2.Cu")
		(net 72)
	)
	(arc
		(start 119.19454 159.784591)
		(mid 119.017764 159.711367)
		(end 118.840987 159.78459)
		(width 0.148)
		(layer "In2.Cu")
		(net 72)
	)
	(arc
		(start 122.73009 163.320141)
		(mid 122.553314 163.246917)
		(end 122.376537 163.32014)
		(width 0.148)
		(layer "In2.Cu")
		(net 72)
	)
	(arc
		(start 122.173695 164.583644)
		(mid 122.100471 164.406868)
		(end 122.173694 164.230091)
		(width 0.148)
		(layer "In2.Cu")
		(net 72)
	)
	(arc
		(start 120.60876 161.198811)
		(mid 120.431984 161.125587)
		(end 120.255207 161.19881)
		(width 0.148)
		(layer "In2.Cu")
		(net 72)
	)
	(arc
		(start 118.284589 160.340984)
		(mid 118.107813 160.414208)
		(end 117.931036 160.340985)
		(width 0.148)
		(layer "In2.Cu")
		(net 72)
	)
	(arc
		(start 116.516815 158.926764)
		(mid 116.443591 158.749988)
		(end 116.516814 158.573211)
		(width 0.148)
		(layer "In2.Cu")
		(net 72)
	)
	(arc
		(start 119.698809 161.755204)
		(mid 119.522033 161.828428)
		(end 119.345256 161.755205)
		(width 0.148)
		(layer "In2.Cu")
		(net 72)
	)
	(arc
		(start 123.587915 165.997864)
		(mid 123.514691 165.821088)
		(end 123.587914 165.644311)
		(width 0.148)
		(layer "In2.Cu")
		(net 72)
	)
	(arc
		(start 119.345255 161.755204)
		(mid 119.272031 161.578428)
		(end 119.345254 161.401651)
		(width 0.148)
		(layer "In2.Cu")
		(net 72)
	)
	(arc
		(start 119.90165 160.845255)
		(mid 119.974874 160.668479)
		(end 119.901651 160.491702)
		(width 0.148)
		(layer "In2.Cu")
		(net 72)
	)
	(arc
		(start 121.466585 163.876534)
		(mid 121.393361 163.699758)
		(end 121.466584 163.522981)
		(width 0.148)
		(layer "In2.Cu")
		(net 72)
	)
	(arc
		(start 124.14431 164.734361)
		(mid 123.967534 164.661137)
		(end 123.790757 164.73436)
		(width 0.148)
		(layer "In2.Cu")
		(net 72)
	)
	(arc
		(start 120.052365 162.462314)
		(mid 119.979141 162.285538)
		(end 120.052364 162.108761)
		(width 0.148)
		(layer "In2.Cu")
		(net 72)
	)
	(arc
		(start 122.02298 162.613031)
		(mid 121.846204 162.539807)
		(end 121.669427 162.61303)
		(width 0.148)
		(layer "In2.Cu")
		(net 72)
	)
	(arc
		(start 123.4372 164.027251)
		(mid 123.260424 163.954027)
		(end 123.083647 164.02725)
		(width 0.148)
		(layer "In2.Cu")
		(net 72)
	)
	(arc
		(start 117.78032 158.723925)
		(mid 117.853544 158.547149)
		(end 117.780321 158.370372)
		(width 0.148)
		(layer "In2.Cu")
		(net 72)
	)
	(arc
		(start 117.931035 160.340984)
		(mid 117.857811 160.164208)
		(end 117.931034 159.987431)
		(width 0.148)
		(layer "In2.Cu")
		(net 72)
	)
	(arc
		(start 116.870369 158.926764)
		(mid 116.693593 158.999988)
		(end 116.516816 158.926765)
		(width 0.148)
		(layer "In2.Cu")
		(net 72)
	)
	(arc
		(start 123.941469 165.997864)
		(mid 123.764693 166.071088)
		(end 123.587916 165.997865)
		(width 0.148)
		(layer "In2.Cu")
		(net 72)
	)
	(arc
		(start 121.820139 163.876534)
		(mid 121.643363 163.949758)
		(end 121.466586 163.876535)
		(width 0.148)
		(layer "In2.Cu")
		(net 72)
	)
	(arc
		(start 117.223925 159.633874)
		(mid 117.150701 159.457098)
		(end 117.223924 159.280321)
		(width 0.148)
		(layer "In2.Cu")
		(net 72)
	)
	(arc
		(start 124.75 166.25)
		(mid 124.676776 166.073224)
		(end 124.749999 165.896447)
		(width 0.148)
		(layer "In2.Cu")
		(net 72)
	)
	(arc
		(start 123.4372 164.380805)
		(mid 123.510424 164.204029)
		(end 123.437201 164.027252)
		(width 0.148)
		(layer "In2.Cu")
		(net 72)
	)
	(arc
		(start 119.19454 160.138145)
		(mid 119.267764 159.961369)
		(end 119.194541 159.784592)
		(width 0.148)
		(layer "In2.Cu")
		(net 72)
	)
	(arc
		(start 117.78032 158.370371)
		(mid 117.603544 158.297147)
		(end 117.426767 158.37037)
		(width 0.148)
		(layer "In2.Cu")
		(net 72)
	)
	(arc
		(start 117.577479 159.633874)
		(mid 117.400703 159.707098)
		(end 117.223926 159.633875)
		(width 0.148)
		(layer "In2.Cu")
		(net 72)
	)
	(arc
		(start 124.851421 165.795024)
		(mid 124.924644 165.618247)
		(end 124.85142 165.441471)
		(width 0.148)
		(layer "In2.Cu")
		(net 72)
	)
	(arc
		(start 118.638145 161.048094)
		(mid 118.564921 160.871318)
		(end 118.638144 160.694541)
		(width 0.148)
		(layer "In2.Cu")
		(net 72)
	)
	(arc
		(start 121.31587 162.259475)
		(mid 121.389094 162.082699)
		(end 121.315871 161.905922)
		(width 0.148)
		(layer "In2.Cu")
		(net 72)
	)
	(arc
		(start 122.527249 164.583644)
		(mid 122.350473 164.656868)
		(end 122.173696 164.583645)
		(width 0.148)
		(layer "In2.Cu")
		(net 72)
	)
	(arc
		(start 121.113029 163.169424)
		(mid 120.936253 163.242648)
		(end 120.759476 163.169425)
		(width 0.148)
		(layer "In2.Cu")
		(net 72)
	)
	(arc
		(start 121.31587 161.905921)
		(mid 121.139094 161.832697)
		(end 120.962317 161.90592)
		(width 0.148)
		(layer "In2.Cu")
		(net 72)
	)
	(arc
		(start 122.73009 163.673695)
		(mid 122.803314 163.496919)
		(end 122.730091 163.320142)
		(width 0.148)
		(layer "In2.Cu")
		(net 72)
	)
	(arc
		(start 124.851421 165.441471)
		(mid 124.674645 165.368247)
		(end 124.497868 165.44147)
		(width 0.148)
		(layer "In2.Cu")
		(net 72)
	)
	(arc
		(start 118.48743 159.077481)
		(mid 118.310654 159.004257)
		(end 118.133877 159.07748)
		(width 0.148)
		(layer "In2.Cu")
		(net 72)
	)
	(segment
		(start 138.376501 169.302)
		(end 137.877001 168.8025)
		(width 0.256)
		(layer "F.Cu")
		(net 73)
	)
	(segment
		(start 113.650001 138.8025)
		(end 113.650001 139.8775)
		(width 0.201)
		(layer "F.Cu")
		(net 73)
	)
	(via
		(at 113.650001 139.8775)
		(size 0.45)
		(drill 0.1)
		(layers "F.Cu" "B.Cu")
		(net 73)
	)
	(via
		(at 137.877001 168.8025)
		(size 0.45)
		(drill 0.1)
		(layers "F.Cu" "B.Cu")
		(net 73)
	)
	(segment
		(start 135.475001 168.0525)
		(end 135.475001 167.3025)
		(width 0.1)
		(layer "In2.Cu")
		(net 73)
	)
	(segment
		(start 134.59667 167.0525)
		(end 134.157333 167.0525)
		(width 0.1)
		(layer "In2.Cu")
		(net 73)
	)
	(segment
		(start 116.568078 154.85)
		(end 117.431922 154.85)
		(width 0.148)
		(layer "In2.Cu")
		(net 73)
	)
	(segment
		(start 116.568078 149.85)
		(end 117.431922 149.85)
		(width 0.148)
		(layer "In2.Cu")
		(net 73)
	)
	(segment
		(start 116.568078 152.35)
		(end 117.431922 152.35)
		(width 0.148)
		(layer "In2.Cu")
		(net 73)
	)
	(segment
		(start 117 157.085471)
		(end 117 157.125)
		(width 0.148)
		(layer "In2.Cu")
		(net 73)
	)
	(segment
		(start 133.250001 166.1775)
		(end 132.650001 166.1775)
		(width 0.1)
		(layer "In2.Cu")
		(net 73)
	)
	(segment
		(start 116.568078 150.85)
		(end 117.431922 150.85)
		(width 0.148)
		(layer "In2.Cu")
		(net 73)
	)
	(segment
		(start 132.150001 165.3275)
		(end 132.425001 165.6025)
		(width 0.148)
		(layer "In2.Cu")
		(net 73)
	)
	(segment
		(start 115 145.9)
		(end 115.4 146.3)
		(width 0.148)
		(layer "In2.Cu")
		(net 73)
	)
	(segment
		(start 133.72167 167.177501)
		(end 133.502001 166.957832)
		(width 0.1)
		(layer "In2.Cu")
		(net 73)
	)
	(segment
		(start 135.650001 168.2275)
		(end 135.475001 168.0525)
		(width 0.1)
		(layer "In2.Cu")
		(net 73)
	)
	(segment
		(start 134.032332 167.177501)
		(end 133.72167 167.177501)
		(width 0.1)
		(layer "In2.Cu")
		(net 73)
	)
	(segment
		(start 115.9 148.3)
		(end 116.7 148.3)
		(width 0.148)
		(layer "In2.Cu")
		(net 73)
	)
	(segment
		(start 117 157.125)
		(end 125.2025 165.3275)
		(width 0.148)
		(layer "In2.Cu")
		(net 73)
	)
	(segment
		(start 116.568078 153.85)
		(end 117.431922 153.85)
		(width 0.148)
		(layer "In2.Cu")
		(net 73)
	)
	(segment
		(start 133.502001 166.957832)
		(end 133.502001 166.4295)
		(width 0.1)
		(layer "In2.Cu")
		(net 73)
	)
	(segment
		(start 132.650001 166.1775)
		(end 132.425001 165.9525)
		(width 0.1)
		(layer "In2.Cu")
		(net 73)
	)
	(segment
		(start 113.650001 139.8775)
		(end 113.650001 140.150001)
		(width 0.148)
		(layer "In2.Cu")
		(net 73)
	)
	(segment
		(start 117.431922 156.35)
		(end 117.25 156.35)
		(width 0.148)
		(layer "In2.Cu")
		(net 73)
	)
	(segment
		(start 116.75 149.35)
		(end 116.568078 149.35)
		(width 0.148)
		(layer "In2.Cu")
		(net 73)
	)
	(segment
		(start 113.650001 140.150001)
		(end 115 141.5)
		(width 0.148)
		(layer "In2.Cu")
		(net 73)
	)
	(segment
		(start 137.302001 168.2275)
		(end 135.650001 168.2275)
		(width 0.1)
		(layer "In2.Cu")
		(net 73)
	)
	(segment
		(start 117 148.6)
		(end 117 149.1)
		(width 0.148)
		(layer "In2.Cu")
		(net 73)
	)
	(segment
		(start 137.877001 168.8025)
		(end 137.302001 168.2275)
		(width 0.1)
		(layer "In2.Cu")
		(net 73)
	)
	(segment
		(start 116.7 148.3)
		(end 117 148.6)
		(width 0.148)
		(layer "In2.Cu")
		(net 73)
	)
	(segment
		(start 116.568078 153.35)
		(end 117.431922 153.35)
		(width 0.148)
		(layer "In2.Cu")
		(net 73)
	)
	(segment
		(start 115.4 146.3)
		(end 115.4 147.8)
		(width 0.148)
		(layer "In2.Cu")
		(net 73)
	)
	(segment
		(start 132.425001 165.6025)
		(end 132.425001 165.9525)
		(width 0.148)
		(layer "In2.Cu")
		(net 73)
	)
	(segment
		(start 116.568078 150.35)
		(end 117.431922 150.35)
		(width 0.148)
		(layer "In2.Cu")
		(net 73)
	)
	(segment
		(start 116.568078 151.35)
		(end 117.431922 151.35)
		(width 0.148)
		(layer "In2.Cu")
		(net 73)
	)
	(segment
		(start 135.475001 167.3025)
		(end 135.350001 167.1775)
		(width 0.1)
		(layer "In2.Cu")
		(net 73)
	)
	(segment
		(start 134.157333 167.0525)
		(end 134.032332 167.177501)
		(width 0.1)
		(layer "In2.Cu")
		(net 73)
	)
	(segment
		(start 116.568078 154.35)
		(end 117.431922 154.35)
		(width 0.148)
		(layer "In2.Cu")
		(net 73)
	)
	(segment
		(start 135.350001 167.1775)
		(end 134.72167 167.1775)
		(width 0.1)
		(layer "In2.Cu")
		(net 73)
	)
	(segment
		(start 116.568078 155.35)
		(end 117.431922 155.35)
		(width 0.148)
		(layer "In2.Cu")
		(net 73)
	)
	(segment
		(start 116.568078 151.85)
		(end 117.431922 151.85)
		(width 0.148)
		(layer "In2.Cu")
		(net 73)
	)
	(segment
		(start 117 156.6)
		(end 117 157.085471)
		(width 0.148)
		(layer "In2.Cu")
		(net 73)
	)
	(segment
		(start 115 141.5)
		(end 115 145.9)
		(width 0.148)
		(layer "In2.Cu")
		(net 73)
	)
	(segment
		(start 125.2025 165.3275)
		(end 132.150001 165.3275)
		(width 0.148)
		(layer "In2.Cu")
		(net 73)
	)
	(segment
		(start 115.4 147.8)
		(end 115.9 148.3)
		(width 0.148)
		(layer "In2.Cu")
		(net 73)
	)
	(segment
		(start 134.72167 167.1775)
		(end 134.59667 167.0525)
		(width 0.1)
		(layer "In2.Cu")
		(net 73)
	)
	(segment
		(start 116.568078 155.85)
		(end 117.431922 155.85)
		(width 0.148)
		(layer "In2.Cu")
		(net 73)
	)
	(segment
		(start 133.502001 166.4295)
		(end 133.250001 166.1775)
		(width 0.1)
		(layer "In2.Cu")
		(net 73)
	)
	(segment
		(start 116.568078 152.85)
		(end 117.431922 152.85)
		(width 0.148)
		(layer "In2.Cu")
		(net 73)
	)
	(arc
		(start 117.681922 156.1)
		(mid 117.608699 156.276777)
		(end 117.431922 156.35)
		(width 0.148)
		(layer "In2.Cu")
		(net 73)
	)
	(arc
		(start 116.568078 154.35)
		(mid 116.391301 154.423223)
		(end 116.318078 154.6)
		(width 0.148)
		(layer "In2.Cu")
		(net 73)
	)
	(arc
		(start 117.681922 150.1)
		(mid 117.608699 150.276777)
		(end 117.431922 150.35)
		(width 0.148)
		(layer "In2.Cu")
		(net 73)
	)
	(arc
		(start 117.681922 155.1)
		(mid 117.608699 155.276777)
		(end 117.431922 155.35)
		(width 0.148)
		(layer "In2.Cu")
		(net 73)
	)
	(arc
		(start 116.568078 152.35)
		(mid 116.391301 152.423223)
		(end 116.318078 152.6)
		(width 0.148)
		(layer "In2.Cu")
		(net 73)
	)
	(arc
		(start 116.318078 151.6)
		(mid 116.391301 151.776777)
		(end 116.568078 151.85)
		(width 0.148)
		(layer "In2.Cu")
		(net 73)
	)
	(arc
		(start 117.431922 152.85)
		(mid 117.608699 152.923223)
		(end 117.681922 153.1)
		(width 0.148)
		(layer "In2.Cu")
		(net 73)
	)
	(arc
		(start 116.318078 155.6)
		(mid 116.391301 155.776777)
		(end 116.568078 155.85)
		(width 0.148)
		(layer "In2.Cu")
		(net 73)
	)
	(arc
		(start 117.431922 149.85)
		(mid 117.608699 149.923223)
		(end 117.681922 150.1)
		(width 0.148)
		(layer "In2.Cu")
		(net 73)
	)
	(arc
		(start 116.318078 154.6)
		(mid 116.391301 154.776777)
		(end 116.568078 154.85)
		(width 0.148)
		(layer "In2.Cu")
		(net 73)
	)
	(arc
		(start 117.431922 153.85)
		(mid 117.608699 153.923223)
		(end 117.681922 154.1)
		(width 0.148)
		(layer "In2.Cu")
		(net 73)
	)
	(arc
		(start 117 149.1)
		(mid 116.926777 149.276777)
		(end 116.75 149.35)
		(width 0.148)
		(layer "In2.Cu")
		(net 73)
	)
	(arc
		(start 116.568078 153.35)
		(mid 116.391301 153.423223)
		(end 116.318078 153.6)
		(width 0.148)
		(layer "In2.Cu")
		(net 73)
	)
	(arc
		(start 117.431922 150.85)
		(mid 117.608699 150.923223)
		(end 117.681922 151.1)
		(width 0.148)
		(layer "In2.Cu")
		(net 73)
	)
	(arc
		(start 117.431922 155.85)
		(mid 117.608699 155.923223)
		(end 117.681922 156.1)
		(width 0.148)
		(layer "In2.Cu")
		(net 73)
	)
	(arc
		(start 117.681922 154.1)
		(mid 117.608699 154.276777)
		(end 117.431922 154.35)
		(width 0.148)
		(layer "In2.Cu")
		(net 73)
	)
	(arc
		(start 116.318078 153.6)
		(mid 116.391301 153.776777)
		(end 116.568078 153.85)
		(width 0.148)
		(layer "In2.Cu")
		(net 73)
	)
	(arc
		(start 116.318078 152.6)
		(mid 116.391301 152.776777)
		(end 116.568078 152.85)
		(width 0.148)
		(layer "In2.Cu")
		(net 73)
	)
	(arc
		(start 116.568078 151.35)
		(mid 116.391301 151.423223)
		(end 116.318078 151.6)
		(width 0.148)
		(layer "In2.Cu")
		(net 73)
	)
	(arc
		(start 117.431922 151.85)
		(mid 117.608699 151.923223)
		(end 117.681922 152.1)
		(width 0.148)
		(layer "In2.Cu")
		(net 73)
	)
	(arc
		(start 116.568078 150.35)
		(mid 116.391301 150.423223)
		(end 116.318078 150.6)
		(width 0.148)
		(layer "In2.Cu")
		(net 73)
	)
	(arc
		(start 116.568078 155.35)
		(mid 116.391301 155.423223)
		(end 116.318078 155.6)
		(width 0.148)
		(layer "In2.Cu")
		(net 73)
	)
	(arc
		(start 116.568078 149.35)
		(mid 116.391301 149.423223)
		(end 116.318078 149.6)
		(width 0.148)
		(layer "In2.Cu")
		(net 73)
	)
	(arc
		(start 116.318078 149.6)
		(mid 116.391301 149.776777)
		(end 116.568078 149.85)
		(width 0.148)
		(layer "In2.Cu")
		(net 73)
	)
	(arc
		(start 116.318078 150.6)
		(mid 116.391301 150.776777)
		(end 116.568078 150.85)
		(width 0.148)
		(layer "In2.Cu")
		(net 73)
	)
	(arc
		(start 117.681922 151.1)
		(mid 117.608699 151.276777)
		(end 117.431922 151.35)
		(width 0.148)
		(layer "In2.Cu")
		(net 73)
	)
	(arc
		(start 117.431922 154.85)
		(mid 117.608699 154.923223)
		(end 117.681922 155.1)
		(width 0.148)
		(layer "In2.Cu")
		(net 73)
	)
	(arc
		(start 117.681922 153.1)
		(mid 117.608699 153.276777)
		(end 117.431922 153.35)
		(width 0.148)
		(layer "In2.Cu")
		(net 73)
	)
	(arc
		(start 117.681922 152.1)
		(mid 117.608699 152.276777)
		(end 117.431922 152.35)
		(width 0.148)
		(layer "In2.Cu")
		(net 73)
	)
	(arc
		(start 117.25 156.35)
		(mid 117.073223 156.423223)
		(end 117 156.6)
		(width 0.148)
		(layer "In2.Cu")
		(net 73)
	)
	(segment
		(start 133.376502 167.302)
		(end 132.877001 166.8025)
		(width 0.256)
		(layer "F.Cu")
		(net 74)
	)
	(segment
		(start 113.900001 146.2025)
		(end 113.900001 147.2775)
		(width 0.201)
		(layer "F.Cu")
		(net 74)
	)
	(via
		(at 113.900001 147.2775)
		(size 0.45)
		(drill 0.1)
		(layers "F.Cu" "B.Cu")
		(net 74)
	)
	(via
		(at 132.877001 166.8025)
		(size 0.45)
		(drill 0.1)
		(layers "F.Cu" "B.Cu")
		(net 74)
	)
	(segment
		(start 111.75 159)
		(end 112.07 159.32)
		(width 0.148)
		(layer "In4.Cu")
		(net 74)
	)
	(segment
		(start 114.579724 161.406457)
		(end 114.156455 161.829722)
		(width 0.148)
		(layer "In4.Cu")
		(net 74)
	)
	(segment
		(start 116.63132 164.304586)
		(end 116.63132 164.304587)
		(width 0.148)
		(layer "In4.Cu")
		(net 74)
	)
	(segment
		(start 118.115242 164.941976)
		(end 118.115244 164.941977)
		(width 0.148)
		(layer "In4.Cu")
		(net 74)
	)
	(segment
		(start 116.984871 165.011692)
		(end 116.984871 165.011691)
		(width 0.148)
		(layer "In4.Cu")
		(net 74)
	)
	(segment
		(start 114.156455 162.183276)
		(end 114.156455 162.183275)
		(width 0.148)
		(layer "In4.Cu")
		(net 74)
	)
	(segment
		(start 113.0958 160.769066)
		(end 113.0958 160.769067)
		(width 0.148)
		(layer "In4.Cu")
		(net 74)
	)
	(segment
		(start 114.863559 162.89038)
		(end 114.863559 162.890379)
		(width 0.148)
		(layer "In4.Cu")
		(net 74)
	)
	(segment
		(start 118.115245 164.588424)
		(end 118.115243 164.588423)
		(width 0.148)
		(layer "In4.Cu")
		(net 74)
	)
	(segment
		(start 113.165516 159.992249)
		(end 112.742247 160.415514)
		(width 0.148)
		(layer "In4.Cu")
		(net 74)
	)
	(segment
		(start 115.286826 162.11356)
		(end 115.286828 162.113561)
		(width 0.148)
		(layer "In4.Cu")
		(net 74)
	)
	(segment
		(start 116.63132 164.304587)
		(end 117.054585 163.881318)
		(width 0.148)
		(layer "In4.Cu")
		(net 74)
	)
	(segment
		(start 118.045528 165.718794)
		(end 118.045528 165.718795)
		(width 0.148)
		(layer "In4.Cu")
		(net 74)
	)
	(segment
		(start 113.872621 160.3458)
		(end 113.872619 160.345799)
		(width 0.148)
		(layer "In4.Cu")
		(net 74)
	)
	(segment
		(start 118.045528 165.718795)
		(end 118.468793 165.295526)
		(width 0.148)
		(layer "In4.Cu")
		(net 74)
	)
	(segment
		(start 114.579725 161.052904)
		(end 114.579723 161.052903)
		(width 0.148)
		(layer "In4.Cu")
		(net 74)
	)
	(segment
		(start 112.07 159.673553)
		(end 112.035143 159.708409)
		(width 0.148)
		(layer "In4.Cu")
		(net 74)
	)
	(segment
		(start 118.822348 165.649081)
		(end 118.78749 165.683936)
		(width 0.148)
		(layer "In4.Cu")
		(net 74)
	)
	(segment
		(start 117.408141 163.88132)
		(end 117.408139 163.881319)
		(width 0.148)
		(layer "In4.Cu")
		(net 74)
	)
	(segment
		(start 117.338424 165.01169)
		(end 117.338424 165.011691)
		(width 0.148)
		(layer "In4.Cu")
		(net 74)
	)
	(segment
		(start 116.701034 163.527768)
		(end 116.701036 163.527769)
		(width 0.148)
		(layer "In4.Cu")
		(net 74)
	)
	(segment
		(start 115.993933 162.467112)
		(end 115.993931 162.467111)
		(width 0.148)
		(layer "In4.Cu")
		(net 74)
	)
	(segment
		(start 112.388696 160.061963)
		(end 112.811961 159.638694)
		(width 0.148)
		(layer "In4.Cu")
		(net 74)
	)
	(segment
		(start 111.75 149.427501)
		(end 111.75 159)
		(width 0.148)
		(layer "In4.Cu")
		(net 74)
	)
	(segment
		(start 113.0958 160.769067)
		(end 113.519065 160.345798)
		(width 0.148)
		(layer "In4.Cu")
		(net 74)
	)
	(segment
		(start 132.375001 167.3045)
		(end 132.877001 166.8025)
		(width 0.148)
		(layer "In4.Cu")
		(net 74)
	)
	(segment
		(start 114.510008 162.183275)
		(end 114.933273 161.760006)
		(width 0.148)
		(layer "In4.Cu")
		(net 74)
	)
	(segment
		(start 132.075001 168.2525)
		(end 132.375001 167.9525)
		(width 0.148)
		(layer "In4.Cu")
		(net 74)
	)
	(segment
		(start 115.286828 162.113561)
		(end 114.863559 162.536826)
		(width 0.148)
		(layer "In4.Cu")
		(net 74)
	)
	(segment
		(start 113.802904 161.47617)
		(end 113.802904 161.476171)
		(width 0.148)
		(layer "In4.Cu")
		(net 74)
	)
	(segment
		(start 121.0025 168.2525)
		(end 132.075001 168.2525)
		(width 0.148)
		(layer "In4.Cu")
		(net 74)
	)
	(segment
		(start 113.165514 159.992248)
		(end 113.165516 159.992249)
		(width 0.148)
		(layer "In4.Cu")
		(net 74)
	)
	(segment
		(start 118.115244 164.941977)
		(end 117.691975 165.365242)
		(width 0.148)
		(layer "In4.Cu")
		(net 74)
	)
	(segment
		(start 117.691975 165.718796)
		(end 117.691975 165.718795)
		(width 0.148)
		(layer "In4.Cu")
		(net 74)
	)
	(segment
		(start 112.388696 160.061962)
		(end 112.388696 160.061963)
		(width 0.148)
		(layer "In4.Cu")
		(net 74)
	)
	(segment
		(start 113.872618 160.699352)
		(end 113.87262 160.699353)
		(width 0.148)
		(layer "In4.Cu")
		(net 74)
	)
	(segment
		(start 112.742247 160.769068)
		(end 112.742247 160.769067)
		(width 0.148)
		(layer "In4.Cu")
		(net 74)
	)
	(segment
		(start 117.338424 165.011691)
		(end 117.761689 164.588422)
		(width 0.148)
		(layer "In4.Cu")
		(net 74)
	)
	(segment
		(start 118.78749 166.03749)
		(end 121.0025 168.2525)
		(width 0.148)
		(layer "In4.Cu")
		(net 74)
	)
	(segment
		(start 132.375001 167.9525)
		(end 132.375001 167.3045)
		(width 0.148)
		(layer "In4.Cu")
		(net 74)
	)
	(segment
		(start 113.449351 161.476172)
		(end 113.449351 161.476171)
		(width 0.148)
		(layer "In4.Cu")
		(net 74)
	)
	(segment
		(start 116.701037 163.174216)
		(end 116.701035 163.174215)
		(width 0.148)
		(layer "In4.Cu")
		(net 74)
	)
	(segment
		(start 112.069999 159.673553)
		(end 112.07 159.673553)
		(width 0.148)
		(layer "In4.Cu")
		(net 74)
	)
	(segment
		(start 114.510008 162.183274)
		(end 114.510008 162.183275)
		(width 0.148)
		(layer "In4.Cu")
		(net 74)
	)
	(segment
		(start 113.165517 159.638696)
		(end 113.165515 159.638695)
		(width 0.148)
		(layer "In4.Cu")
		(net 74)
	)
	(segment
		(start 115.99393 162.820664)
		(end 115.993932 162.820665)
		(width 0.148)
		(layer "In4.Cu")
		(net 74)
	)
	(segment
		(start 116.701036 163.527769)
		(end 116.277767 163.951034)
		(width 0.148)
		(layer "In4.Cu")
		(net 74)
	)
	(segment
		(start 115.217112 162.890378)
		(end 115.217112 162.890379)
		(width 0.148)
		(layer "In4.Cu")
		(net 74)
	)
	(segment
		(start 115.993932 162.820665)
		(end 115.570663 163.24393)
		(width 0.148)
		(layer "In4.Cu")
		(net 74)
	)
	(segment
		(start 114.579722 161.406456)
		(end 114.579724 161.406457)
		(width 0.148)
		(layer "In4.Cu")
		(net 74)
	)
	(segment
		(start 117.40814 164.234873)
		(end 116.984871 164.658138)
		(width 0.148)
		(layer "In4.Cu")
		(net 74)
	)
	(segment
		(start 112.035142 160.061962)
		(end 112.035143 160.061963)
		(width 0.148)
		(layer "In4.Cu")
		(net 74)
	)
	(segment
		(start 118.787489 166.037489)
		(end 118.78749 166.03749)
		(width 0.148)
		(layer "In4.Cu")
		(net 74)
	)
	(segment
		(start 117.408138 164.234872)
		(end 117.40814 164.234873)
		(width 0.148)
		(layer "In4.Cu")
		(net 74)
	)
	(segment
		(start 115.924216 163.597482)
		(end 115.924216 163.597483)
		(width 0.148)
		(layer "In4.Cu")
		(net 74)
	)
	(segment
		(start 115.286829 161.760008)
		(end 115.286827 161.760007)
		(width 0.148)
		(layer "In4.Cu")
		(net 74)
	)
	(segment
		(start 113.900001 147.2775)
		(end 111.75 149.427501)
		(width 0.148)
		(layer "In4.Cu")
		(net 74)
	)
	(segment
		(start 118.822349 165.295528)
		(end 118.822347 165.295527)
		(width 0.148)
		(layer "In4.Cu")
		(net 74)
	)
	(segment
		(start 113.802904 161.476171)
		(end 114.226169 161.052902)
		(width 0.148)
		(layer "In4.Cu")
		(net 74)
	)
	(segment
		(start 115.924216 163.597483)
		(end 116.347481 163.174214)
		(width 0.148)
		(layer "In4.Cu")
		(net 74)
	)
	(segment
		(start 113.87262 160.699353)
		(end 113.449351 161.122618)
		(width 0.148)
		(layer "In4.Cu")
		(net 74)
	)
	(segment
		(start 115.570663 163.597484)
		(end 115.570663 163.597483)
		(width 0.148)
		(layer "In4.Cu")
		(net 74)
	)
	(segment
		(start 116.277767 164.304588)
		(end 116.277767 164.304587)
		(width 0.148)
		(layer "In4.Cu")
		(net 74)
	)
	(segment
		(start 118.822346 165.64908)
		(end 118.822348 165.649081)
		(width 0.148)
		(layer "In4.Cu")
		(net 74)
	)
	(segment
		(start 115.217112 162.890379)
		(end 115.640377 162.46711)
		(width 0.148)
		(layer "In4.Cu")
		(net 74)
	)
	(arc
		(start 116.277767 164.304587)
		(mid 116.454544 164.37781)
		(end 116.63132 164.304586)
		(width 0.148)
		(layer "In4.Cu")
		(net 74)
	)
	(arc
		(start 116.701035 163.174215)
		(mid 116.774258 163.350992)
		(end 116.701034 163.527768)
		(width 0.148)
		(layer "In4.Cu")
		(net 74)
	)
	(arc
		(start 116.984871 165.011691)
		(mid 117.161648 165.084914)
		(end 117.338424 165.01169)
		(width 0.148)
		(layer "In4.Cu")
		(net 74)
	)
	(arc
		(start 114.933273 161.760006)
		(mid 115.110052 161.686785)
		(end 115.286829 161.760008)
		(width 0.148)
		(layer "In4.Cu")
		(net 74)
	)
	(arc
		(start 112.811961 159.638694)
		(mid 112.98874 159.565473)
		(end 113.165517 159.638696)
		(width 0.148)
		(layer "In4.Cu")
		(net 74)
	)
	(arc
		(start 116.277767 163.951034)
		(mid 116.204544 164.127811)
		(end 116.277767 164.304588)
		(width 0.148)
		(layer "In4.Cu")
		(net 74)
	)
	(arc
		(start 112.07 159.32)
		(mid 112.143223 159.496777)
		(end 112.069999 159.673553)
		(width 0.148)
		(layer "In4.Cu")
		(net 74)
	)
	(arc
		(start 115.286827 161.760007)
		(mid 115.36005 161.936784)
		(end 115.286826 162.11356)
		(width 0.148)
		(layer "In4.Cu")
		(net 74)
	)
	(arc
		(start 113.872619 160.345799)
		(mid 113.945842 160.522576)
		(end 113.872618 160.699352)
		(width 0.148)
		(layer "In4.Cu")
		(net 74)
	)
	(arc
		(start 117.691975 165.718795)
		(mid 117.868752 165.792018)
		(end 118.045528 165.718794)
		(width 0.148)
		(layer "In4.Cu")
		(net 74)
	)
	(arc
		(start 112.035143 160.061963)
		(mid 112.21192 160.135186)
		(end 112.388696 160.061962)
		(width 0.148)
		(layer "In4.Cu")
		(net 74)
	)
	(arc
		(start 118.78749 165.683936)
		(mid 118.714266 165.860712)
		(end 118.787489 166.037489)
		(width 0.148)
		(layer "In4.Cu")
		(net 74)
	)
	(arc
		(start 115.640377 162.46711)
		(mid 115.817156 162.393889)
		(end 115.993933 162.467112)
		(width 0.148)
		(layer "In4.Cu")
		(net 74)
	)
	(arc
		(start 114.156455 161.829722)
		(mid 114.083232 162.006499)
		(end 114.156455 162.183276)
		(width 0.148)
		(layer "In4.Cu")
		(net 74)
	)
	(arc
		(start 114.226169 161.052902)
		(mid 114.402948 160.979681)
		(end 114.579725 161.052904)
		(width 0.148)
		(layer "In4.Cu")
		(net 74)
	)
	(arc
		(start 112.035143 159.708409)
		(mid 111.961919 159.885185)
		(end 112.035142 160.061962)
		(width 0.148)
		(layer "In4.Cu")
		(net 74)
	)
	(arc
		(start 112.742247 160.415514)
		(mid 112.669024 160.592291)
		(end 112.742247 160.769068)
		(width 0.148)
		(layer "In4.Cu")
		(net 74)
	)
	(arc
		(start 115.993931 162.467111)
		(mid 116.067154 162.643888)
		(end 115.99393 162.820664)
		(width 0.148)
		(layer "In4.Cu")
		(net 74)
	)
	(arc
		(start 113.165515 159.638695)
		(mid 113.238738 159.815472)
		(end 113.165514 159.992248)
		(width 0.148)
		(layer "In4.Cu")
		(net 74)
	)
	(arc
		(start 114.863559 162.890379)
		(mid 115.040336 162.963602)
		(end 115.217112 162.890378)
		(width 0.148)
		(layer "In4.Cu")
		(net 74)
	)
	(arc
		(start 117.761689 164.588422)
		(mid 117.938468 164.515201)
		(end 118.115245 164.588424)
		(width 0.148)
		(layer "In4.Cu")
		(net 74)
	)
	(arc
		(start 117.408139 163.881319)
		(mid 117.481362 164.058096)
		(end 117.408138 164.234872)
		(width 0.148)
		(layer "In4.Cu")
		(net 74)
	)
	(arc
		(start 118.468793 165.295526)
		(mid 118.645572 165.222305)
		(end 118.822349 165.295528)
		(width 0.148)
		(layer "In4.Cu")
		(net 74)
	)
	(arc
		(start 114.156455 162.183275)
		(mid 114.333232 162.256498)
		(end 114.510008 162.183274)
		(width 0.148)
		(layer "In4.Cu")
		(net 74)
	)
	(arc
		(start 113.449351 161.476171)
		(mid 113.626128 161.549394)
		(end 113.802904 161.47617)
		(width 0.148)
		(layer "In4.Cu")
		(net 74)
	)
	(arc
		(start 116.984871 164.658138)
		(mid 116.911648 164.834915)
		(end 116.984871 165.011692)
		(width 0.148)
		(layer "In4.Cu")
		(net 74)
	)
	(arc
		(start 114.863559 162.536826)
		(mid 114.790336 162.713603)
		(end 114.863559 162.89038)
		(width 0.148)
		(layer "In4.Cu")
		(net 74)
	)
	(arc
		(start 114.579723 161.052903)
		(mid 114.652946 161.22968)
		(end 114.579722 161.406456)
		(width 0.148)
		(layer "In4.Cu")
		(net 74)
	)
	(arc
		(start 113.519065 160.345798)
		(mid 113.695844 160.272577)
		(end 113.872621 160.3458)
		(width 0.148)
		(layer "In4.Cu")
		(net 74)
	)
	(arc
		(start 112.742247 160.769067)
		(mid 112.919024 160.84229)
		(end 113.0958 160.769066)
		(width 0.148)
		(layer "In4.Cu")
		(net 74)
	)
	(arc
		(start 118.115243 164.588423)
		(mid 118.188466 164.7652)
		(end 118.115242 164.941976)
		(width 0.148)
		(layer "In4.Cu")
		(net 74)
	)
	(arc
		(start 115.570663 163.24393)
		(mid 115.49744 163.420707)
		(end 115.570663 163.597484)
		(width 0.148)
		(layer "In4.Cu")
		(net 74)
	)
	(arc
		(start 113.449351 161.122618)
		(mid 113.376128 161.299395)
		(end 113.449351 161.476172)
		(width 0.148)
		(layer "In4.Cu")
		(net 74)
	)
	(arc
		(start 116.347481 163.174214)
		(mid 116.52426 163.100993)
		(end 116.701037 163.174216)
		(width 0.148)
		(layer "In4.Cu")
		(net 74)
	)
	(arc
		(start 117.054585 163.881318)
		(mid 117.231364 163.808097)
		(end 117.408141 163.88132)
		(width 0.148)
		(layer "In4.Cu")
		(net 74)
	)
	(arc
		(start 115.570663 163.597483)
		(mid 115.74744 163.670706)
		(end 115.924216 163.597482)
		(width 0.148)
		(layer "In4.Cu")
		(net 74)
	)
	(arc
		(start 118.822347 165.295527)
		(mid 118.89557 165.472304)
		(end 118.822346 165.64908)
		(width 0.148)
		(layer "In4.Cu")
		(net 74)
	)
	(arc
		(start 117.691975 165.365242)
		(mid 117.618752 165.542019)
		(end 117.691975 165.718796)
		(width 0.148)
		(layer "In4.Cu")
		(net 74)
	)
	(segment
		(start 175.290327 194.214502)
		(end 175.821826 193.683002)
		(width 0.177)
		(layer "F.Cu")
		(net 75)
	)
	(segment
		(start 174.720501 194.214501)
		(end 175.290327 194.214502)
		(width 0.177)
		(layer "F.Cu")
		(net 75)
	)
	(segment
		(start 176.687002 193.683002)
		(end 177.170502 193.199502)
		(width 0.177)
		(layer "F.Cu")
		(net 75)
	)
	(segment
		(start 175.821826 193.683002)
		(end 176.687002 193.683002)
		(width 0.177)
		(layer "F.Cu")
		(net 75)
	)
	(segment
		(start 193.2 195.347)
		(end 192.603 195.347)
		(width 0.256)
		(layer "F.Cu")
		(net 76)
	)
	(segment
		(start 192.603 195.347)
		(end 192.6 195.35)
		(width 0.256)
		(layer "F.Cu")
		(net 76)
	)
	(via
		(at 192.175 193.725)
		(size 0.45)
		(drill 0.1)
		(layers "F.Cu" "B.Cu")
		(net 76)
	)
	(via
		(at 192.6 195.35)
		(size 0.45)
		(drill 0.1)
		(layers "F.Cu" "B.Cu")
		(net 76)
	)
	(segment
		(start 191.86 196.94)
		(end 191.86 194.04)
		(width 0.15)
		(layer "B.Cu")
		(net 76)
	)
	(segment
		(start 191.86 194.04)
		(end 192.175 193.725)
		(width 0.15)
		(layer "B.Cu")
		(net 76)
	)
	(segment
		(start 192.6 195.35)
		(end 192.6 194.15)
		(width 0.256)
		(layer "In2.Cu")
		(net 76)
	)
	(segment
		(start 192.6 194.15)
		(end 192.175 193.725)
		(width 0.256)
		(layer "In2.Cu")
		(net 76)
	)
	(segment
		(start 114.650001 138.8025)
		(end 114.650001 139.8775)
		(width 0.201)
		(layer "F.Cu")
		(net 77)
	)
	(segment
		(start 135.376501 166.302)
		(end 134.877001 165.8025)
		(width 0.256)
		(layer "F.Cu")
		(net 77)
	)
	(via
		(at 114.650001 139.8775)
		(size 0.45)
		(drill 0.1)
		(layers "F.Cu" "B.Cu")
		(net 77)
	)
	(via
		(at 134.877001 165.8025)
		(size 0.45)
		(drill 0.1)
		(layers "F.Cu" "B.Cu")
		(net 77)
	)
	(segment
		(start 133.775001 166.2525)
		(end 134.427001 166.2525)
		(width 0.148)
		(layer "In4.Cu")
		(net 77)
	)
	(segment
		(start 134.427001 166.2525)
		(end 134.877001 165.8025)
		(width 0.148)
		(layer "In4.Cu")
		(net 77)
	)
	(segment
		(start 112.400501 147.676)
		(end 110.5 149.576501)
		(width 0.148)
		(layer "In4.Cu")
		(net 77)
	)
	(segment
		(start 132.575001 168.3525)
		(end 133.141167 168.3525)
		(width 0.148)
		(layer "In4.Cu")
		(net 77)
	)
	(segment
		(start 120.286 169.306)
		(end 132.140501 169.306)
		(width 0.148)
		(layer "In4.Cu")
		(net 77)
	)
	(segment
		(start 133.375001 166.6525)
		(end 133.775001 166.2525)
		(width 0.148)
		(layer "In4.Cu")
		(net 77)
	)
	(segment
		(start 110.8 150.57)
		(end 110.926396 150.57)
		(width 0.148)
		(layer "In4.Cu")
		(net 77)
	)
	(segment
		(start 132.390501 169.056)
		(end 132.390501 168.537)
		(width 0.148)
		(layer "In4.Cu")
		(net 77)
	)
	(segment
		(start 113.900501 141.36275)
		(end 113.900501 145.476)
		(width 0.148)
		(layer "In4.Cu")
		(net 77)
	)
	(segment
		(start 110.073604 152.37)
		(end 110.926396 152.37)
		(width 0.148)
		(layer "In4.Cu")
		(net 77)
	)
	(segment
		(start 133.141167 168.3525)
		(end 133.375001 168.118666)
		(width 0.148)
		(layer "In4.Cu")
		(net 77)
	)
	(segment
		(start 110.926396 151.17)
		(end 110.8 151.17)
		(width 0.148)
		(layer "In4.Cu")
		(net 77)
	)
	(segment
		(start 110.5 149.576501)
		(end 110.5 150.27)
		(width 0.148)
		(layer "In4.Cu")
		(net 77)
	)
	(segment
		(start 112.400501 146.976)
		(end 112.400501 147.676)
		(width 0.148)
		(layer "In4.Cu")
		(net 77)
	)
	(segment
		(start 110.073604 151.77)
		(end 110.926396 151.77)
		(width 0.148)
		(layer "In4.Cu")
		(net 77)
	)
	(segment
		(start 110.5 159.52)
		(end 120.286 169.306)
		(width 0.148)
		(layer "In4.Cu")
		(net 77)
	)
	(segment
		(start 110.5 153.27)
		(end 110.5 159.52)
		(width 0.148)
		(layer "In4.Cu")
		(net 77)
	)
	(segment
		(start 114.650001 139.8775)
		(end 114.650001 140.61325)
		(width 0.148)
		(layer "In4.Cu")
		(net 77)
	)
	(segment
		(start 132.390501 168.537)
		(end 132.575001 168.3525)
		(width 0.148)
		(layer "In4.Cu")
		(net 77)
	)
	(segment
		(start 114.650001 140.61325)
		(end 113.900501 141.36275)
		(width 0.148)
		(layer "In4.Cu")
		(net 77)
	)
	(segment
		(start 133.375001 168.118666)
		(end 133.375001 166.6525)
		(width 0.148)
		(layer "In4.Cu")
		(net 77)
	)
	(segment
		(start 110.073604 152.97)
		(end 110.2 152.97)
		(width 0.148)
		(layer "In4.Cu")
		(net 77)
	)
	(segment
		(start 110.8 151.17)
		(end 110.073604 151.17)
		(width 0.148)
		(layer "In4.Cu")
		(net 77)
	)
	(segment
		(start 113.900501 145.476)
		(end 112.400501 146.976)
		(width 0.148)
		(layer "In4.Cu")
		(net 77)
	)
	(segment
		(start 132.140501 169.306)
		(end 132.390501 169.056)
		(width 0.148)
		(layer "In4.Cu")
		(net 77)
	)
	(arc
		(start 110.926396 150.57)
		(mid 111.138528 150.657868)
		(end 111.226396 150.87)
		(width 0.148)
		(layer "In4.Cu")
		(net 77)
	)
	(arc
		(start 109.773604 151.47)
		(mid 109.861472 151.682132)
		(end 110.073604 151.77)
		(width 0.148)
		(layer "In4.Cu")
		(net 77)
	)
	(arc
		(start 110.2 152.97)
		(mid 110.412132 153.057868)
		(end 110.5 153.27)
		(width 0.148)
		(layer "In4.Cu")
		(net 77)
	)
	(arc
		(start 110.073604 152.37)
		(mid 109.861472 152.457868)
		(end 109.773604 152.67)
		(width 0.148)
		(layer "In4.Cu")
		(net 77)
	)
	(arc
		(start 110.5 150.27)
		(mid 110.587868 150.482132)
		(end 110.8 150.57)
		(width 0.148)
		(layer "In4.Cu")
		(net 77)
	)
	(arc
		(start 110.073604 151.17)
		(mid 109.861472 151.257868)
		(end 109.773604 151.47)
		(width 0.148)
		(layer "In4.Cu")
		(net 77)
	)
	(arc
		(start 110.926396 151.77)
		(mid 111.138528 151.857868)
		(end 111.226396 152.07)
		(width 0.148)
		(layer "In4.Cu")
		(net 77)
	)
	(arc
		(start 111.226396 150.87)
		(mid 111.138528 151.082132)
		(end 110.926396 151.17)
		(width 0.148)
		(layer "In4.Cu")
		(net 77)
	)
	(arc
		(start 111.226396 152.07)
		(mid 111.138528 152.282132)
		(end 110.926396 152.37)
		(width 0.148)
		(layer "In4.Cu")
		(net 77)
	)
	(arc
		(start 109.773604 152.67)
		(mid 109.861472 152.882132)
		(end 110.073604 152.97)
		(width 0.148)
		(layer "In4.Cu")
		(net 77)
	)
	(segment
		(start 176.085502 195.829501)
		(end 175.470503 195.214502)
		(width 0.177)
		(layer "F.Cu")
		(net 78)
	)
	(segment
		(start 176.080501 197.291)
		(end 176.080501 196.269504)
		(width 0.256)
		(layer "F.Cu")
		(net 78)
	)
	(segment
		(start 176.085501 196.214503)
		(end 176.085502 195.829501)
		(width 0.177)
		(layer "F.Cu")
		(net 78)
	)
	(segment
		(start 176.080501 196.269504)
		(end 176.135502 196.214503)
		(width 0.256)
		(layer "F.Cu")
		(net 78)
	)
	(segment
		(start 174.7205 195.214503)
		(end 175.470503 195.214502)
		(width 0.177)
		(layer "F.Cu")
		(net 78)
	)
	(via
		(at 175.470503 195.214502)
		(size 0.45)
		(drill 0.1)
		(layers "F.Cu" "B.Cu")
		(net 78)
	)
	(via
		(at 166.7 190.9)
		(size 0.45)
		(drill 0.1)
		(layers "F.Cu" "B.Cu")
		(net 78)
	)
	(via
		(at 166.700501 191.576)
		(size 0.45)
		(drill 0.1)
		(layers "F.Cu" "B.Cu")
		(net 78)
	)
	(segment
		(start 166.7 190.9)
		(end 167.1 190.5)
		(width 0.15)
		(layer "B.Cu")
		(net 78)
	)
	(segment
		(start 173.100501 191.576)
		(end 166.700501 191.576)
		(width 0.177)
		(layer "B.Cu")
		(net 78)
	)
	(segment
		(start 167.1 190.5)
		(end 168.7 190.5)
		(width 0.15)
		(layer "B.Cu")
		(net 78)
	)
	(segment
		(start 175.470503 193.946002)
		(end 173.100501 191.576)
		(width 0.177)
		(layer "B.Cu")
		(net 78)
	)
	(segment
		(start 175.470503 195.214502)
		(end 175.470503 193.946002)
		(width 0.177)
		(layer "B.Cu")
		(net 78)
	)
	(segment
		(start 133.376501 166.302)
		(end 132.877001 165.8025)
		(width 0.256)
		(layer "F.Cu")
		(net 79)
	)
	(segment
		(start 114.900001 146.2025)
		(end 114.900001 147.2775)
		(width 0.201)
		(layer "F.Cu")
		(net 79)
	)
	(via
		(at 132.877001 165.8025)
		(size 0.45)
		(drill 0.1)
		(layers "F.Cu" "B.Cu")
		(net 79)
	)
	(via
		(at 114.900001 147.2775)
		(size 0.45)
		(drill 0.1)
		(layers "F.Cu" "B.Cu")
		(net 79)
	)
	(segment
		(start 114.900001 148.0765)
		(end 114.09 148.886501)
		(width 0.148)
		(layer "In4.Cu")
		(net 79)
	)
	(segment
		(start 117.677959 161.09676)
		(end 117.677959 161.096759)
		(width 0.148)
		(layer "In4.Cu")
		(net 79)
	)
	(segment
		(start 117.235668 162.316867)
		(end 117.235668 162.316868)
		(width 0.148)
		(layer "In4.Cu")
		(net 79)
	)
	(segment
		(start 114.09 158.339999)
		(end 114.54 158.79)
		(width 0.148)
		(layer "In4.Cu")
		(net 79)
	)
	(segment
		(start 116.122325 159.541126)
		(end 116.122325 159.541125)
		(width 0.148)
		(layer "In4.Cu")
		(net 79)
	)
	(segment
		(start 120.011409 163.819119)
		(end 120.01141 163.819118)
		(width 0.148)
		(layer "In4.Cu")
		(net 79)
	)
	(segment
		(start 119.180211 163.872501)
		(end 119.18021 163.872502)
		(width 0.148)
		(layer "In4.Cu")
		(net 79)
	)
	(segment
		(start 116.457851 161.53905)
		(end 116.457851 161.539051)
		(width 0.148)
		(layer "In4.Cu")
		(net 79)
	)
	(segment
		(start 119.958028 164.650318)
		(end 119.958027 164.650319)
		(width 0.148)
		(layer "In4.Cu")
		(net 79)
	)
	(segment
		(start 115.344509 158.76331)
		(end 115.344508 158.763309)
		(width 0.148)
		(layer "In4.Cu")
		(net 79)
	)
	(segment
		(start 117.677959 161.485667)
		(end 117.235668 161.927959)
		(width 0.148)
		(layer "In4.Cu")
		(net 79)
	)
	(segment
		(start 116.900142 160.70785)
		(end 116.457851 161.150142)
		(width 0.148)
		(layer "In4.Cu")
		(net 79)
	)
	(segment
		(start 115.123363 159.373363)
		(end 114.902217 159.594508)
		(width 0.148)
		(layer "In4.Cu")
		(net 79)
	)
	(segment
		(start 119.233592 163.041302)
		(end 119.233593 163.041301)
		(width 0.148)
		(layer "In4.Cu")
		(net 79)
	)
	(segment
		(start 118.402394 163.094684)
		(end 118.402393 163.094685)
		(width 0.148)
		(layer "In4.Cu")
		(net 79)
	)
	(segment
		(start 121.567043 165.374753)
		(end 121.567044 165.374752)
		(width 0.148)
		(layer "In4.Cu")
		(net 79)
	)
	(segment
		(start 120.789226 164.596936)
		(end 120.789227 164.596935)
		(width 0.148)
		(layer "In4.Cu")
		(net 79)
	)
	(segment
		(start 121.540353 165.790352)
		(end 122.0525 166.3025)
		(width 0.148)
		(layer "In4.Cu")
		(net 79)
	)
	(segment
		(start 120.01141 163.430211)
		(end 120.01141 163.43021)
		(width 0.148)
		(layer "In4.Cu")
		(net 79)
	)
	(segment
		(start 119.233593 163.041301)
		(end 118.791302 163.483593)
		(width 0.148)
		(layer "In4.Cu")
		(net 79)
	)
	(segment
		(start 118.455776 162.263484)
		(end 118.013485 162.705776)
		(width 0.148)
		(layer "In4.Cu")
		(net 79)
	)
	(segment
		(start 120.789227 164.208028)
		(end 120.789227 164.208027)
		(width 0.148)
		(layer "In4.Cu")
		(net 79)
	)
	(segment
		(start 115.291125 159.983417)
		(end 115.733415 159.541124)
		(width 0.148)
		(layer "In4.Cu")
		(net 79)
	)
	(segment
		(start 121.567044 165.374752)
		(end 121.540353 165.401444)
		(width 0.148)
		(layer "In4.Cu")
		(net 79)
	)
	(segment
		(start 115.680034 160.761233)
		(end 115.680034 160.761234)
		(width 0.148)
		(layer "In4.Cu")
		(net 79)
	)
	(segment
		(start 116.068943 160.761233)
		(end 116.068942 160.761234)
		(width 0.148)
		(layer "In4.Cu")
		(net 79)
	)
	(segment
		(start 119.233593 162.652394)
		(end 119.233593 162.652393)
		(width 0.148)
		(layer "In4.Cu")
		(net 79)
	)
	(segment
		(start 119.18021 163.872502)
		(end 119.6225 163.430209)
		(width 0.148)
		(layer "In4.Cu")
		(net 79)
	)
	(segment
		(start 117.624577 162.316867)
		(end 117.624576 162.316868)
		(width 0.148)
		(layer "In4.Cu")
		(net 79)
	)
	(segment
		(start 118.455775 162.263485)
		(end 118.455776 162.263484)
		(width 0.148)
		(layer "In4.Cu")
		(net 79)
	)
	(segment
		(start 116.122325 159.930033)
		(end 115.680034 160.372325)
		(width 0.148)
		(layer "In4.Cu")
		(net 79)
	)
	(segment
		(start 120.01141 163.819118)
		(end 119.569119 164.26141)
		(width 0.148)
		(layer "In4.Cu")
		(net 79)
	)
	(segment
		(start 117.624576 162.316868)
		(end 118.066866 161.874575)
		(width 0.148)
		(layer "In4.Cu")
		(net 79)
	)
	(segment
		(start 116.900142 160.318943)
		(end 116.900142 160.318942)
		(width 0.148)
		(layer "In4.Cu")
		(net 79)
	)
	(segment
		(start 116.900141 160.707851)
		(end 116.900142 160.70785)
		(width 0.148)
		(layer "In4.Cu")
		(net 79)
	)
	(segment
		(start 121.567044 164.985845)
		(end 121.567044 164.985844)
		(width 0.148)
		(layer "In4.Cu")
		(net 79)
	)
	(segment
		(start 114.900001 147.2775)
		(end 114.900001 148.0765)
		(width 0.148)
		(layer "In4.Cu")
		(net 79)
	)
	(segment
		(start 121.540354 165.790353)
		(end 121.540353 165.790352)
		(width 0.148)
		(layer "In4.Cu")
		(net 79)
	)
	(segment
		(start 114.928909 158.789999)
		(end 114.928908 158.79)
		(width 0.148)
		(layer "In4.Cu")
		(net 79)
	)
	(segment
		(start 114.09 148.886501)
		(end 114.09 158.339999)
		(width 0.148)
		(layer "In4.Cu")
		(net 79)
	)
	(segment
		(start 119.958027 164.650319)
		(end 120.400317 164.208026)
		(width 0.148)
		(layer "In4.Cu")
		(net 79)
	)
	(segment
		(start 115.344508 159.152217)
		(end 115.123361 159.373361)
		(width 0.148)
		(layer "In4.Cu")
		(net 79)
	)
	(segment
		(start 116.84676 161.53905)
		(end 116.846759 161.539051)
		(width 0.148)
		(layer "In4.Cu")
		(net 79)
	)
	(segment
		(start 116.068942 160.761234)
		(end 116.511232 160.318941)
		(width 0.148)
		(layer "In4.Cu")
		(net 79)
	)
	(segment
		(start 118.013485 163.094684)
		(end 118.013485 163.094685)
		(width 0.148)
		(layer "In4.Cu")
		(net 79)
	)
	(segment
		(start 123.4275 165.989753)
		(end 123.4275 166.615247)
		(width 0.148)
		(layer "In4.Cu")
		(net 79)
	)
	(segment
		(start 115.344507 159.152218)
		(end 115.344508 159.152217)
		(width 0.148)
		(layer "In4.Cu")
		(net 79)
	)
	(segment
		(start 124.2525 166.3025)
		(end 132.377001 166.3025)
		(width 0.148)
		(layer "In4.Cu")
		(net 79)
	)
	(segment
		(start 119.569119 164.650318)
		(end 119.569119 164.650319)
		(width 0.148)
		(layer "In4.Cu")
		(net 79)
	)
	(segment
		(start 120.735844 165.428136)
		(end 121.178134 164.985843)
		(width 0.148)
		(layer "In4.Cu")
		(net 79)
	)
	(segment
		(start 122.8775 166.5775)
		(end 122.8775 165.989753)
		(width 0.148)
		(layer "In4.Cu")
		(net 79)
	)
	(segment
		(start 117.677958 161.485668)
		(end 117.677959 161.485667)
		(width 0.148)
		(layer "In4.Cu")
		(net 79)
	)
	(segment
		(start 123.9775 166.615247)
		(end 123.9775 166.5775)
		(width 0.148)
		(layer "In4.Cu")
		(net 79)
	)
	(segment
		(start 115.123361 159.373361)
		(end 115.123363 159.373363)
		(width 0.148)
		(layer "In4.Cu")
		(net 79)
	)
	(segment
		(start 115.291126 159.983416)
		(end 115.291125 159.983417)
		(width 0.148)
		(layer "In4.Cu")
		(net 79)
	)
	(segment
		(start 118.791302 163.872501)
		(end 118.791302 163.872502)
		(width 0.148)
		(layer "In4.Cu")
		(net 79)
	)
	(segment
		(start 118.402393 163.094685)
		(end 118.844683 162.652392)
		(width 0.148)
		(layer "In4.Cu")
		(net 79)
	)
	(segment
		(start 114.902217 159.983416)
		(end 114.902217 159.983417)
		(width 0.148)
		(layer "In4.Cu")
		(net 79)
	)
	(segment
		(start 116.122324 159.930034)
		(end 116.122325 159.930033)
		(width 0.148)
		(layer "In4.Cu")
		(net 79)
	)
	(segment
		(start 122.3275 166.5775)
		(end 122.3275 166.615247)
		(width 0.148)
		(layer "In4.Cu")
		(net 79)
	)
	(segment
		(start 120.346936 165.428135)
		(end 120.346936 165.428136)
		(width 0.148)
		(layer "In4.Cu")
		(net 79)
	)
	(segment
		(start 114.928908 158.79)
		(end 114.9556 158.763309)
		(width 0.148)
		(layer "In4.Cu")
		(net 79)
	)
	(segment
		(start 116.846759 161.539051)
		(end 117.289049 161.096758)
		(width 0.148)
		(layer "In4.Cu")
		(net 79)
	)
	(segment
		(start 122.8775 166.615247)
		(end 122.8775 166.5775)
		(width 0.148)
		(layer "In4.Cu")
		(net 79)
	)
	(segment
		(start 120.735845 165.428135)
		(end 120.735844 165.428136)
		(width 0.148)
		(layer "In4.Cu")
		(net 79)
	)
	(segment
		(start 118.455776 161.874577)
		(end 118.455776 161.874576)
		(width 0.148)
		(layer "In4.Cu")
		(net 79)
	)
	(segment
		(start 132.377001 166.3025)
		(end 132.877001 165.8025)
		(width 0.148)
		(layer "In4.Cu")
		(net 79)
	)
	(segment
		(start 120.789227 164.596935)
		(end 120.346936 165.039227)
		(width 0.148)
		(layer "In4.Cu")
		(net 79)
	)
	(arc
		(start 118.013485 162.705776)
		(mid 117.93294 162.90023)
		(end 118.013485 163.094684)
		(width 0.148)
		(layer "In4.Cu")
		(net 79)
	)
	(arc
		(start 117.235668 161.927959)
		(mid 117.155123 162.122413)
		(end 117.235668 162.316867)
		(width 0.148)
		(layer "In4.Cu")
		(net 79)
	)
	(arc
		(start 121.567044 164.985844)
		(mid 121.647589 165.180299)
		(end 121.567043 165.374753)
		(width 0.148)
		(layer "In4.Cu")
		(net 79)
	)
	(arc
		(start 116.122325 159.541125)
		(mid 116.20287 159.73558)
		(end 116.122324 159.930034)
		(width 0.148)
		(layer "In4.Cu")
		(net 79)
	)
	(arc
		(start 122.6025 166.890247)
		(mid 122.796954 166.809701)
		(end 122.8775 166.615247)
		(width 0.148)
		(layer "In4.Cu")
		(net 79)
	)
	(arc
		(start 114.9556 158.763309)
		(mid 115.150055 158.682764)
		(end 115.344509 158.76331)
		(width 0.148)
		(layer "In4.Cu")
		(net 79)
	)
	(arc
		(start 120.01141 163.43021)
		(mid 120.091955 163.624665)
		(end 120.011409 163.819119)
		(width 0.148)
		(layer "In4.Cu")
		(net 79)
	)
	(arc
		(start 116.511232 160.318941)
		(mid 116.705687 160.238397)
		(end 116.900142 160.318943)
		(width 0.148)
		(layer "In4.Cu")
		(net 79)
	)
	(arc
		(start 115.344508 158.763309)
		(mid 115.425053 158.957764)
		(end 115.344507 159.152218)
		(width 0.148)
		(layer "In4.Cu")
		(net 79)
	)
	(arc
		(start 115.680034 160.761234)
		(mid 115.874489 160.841779)
		(end 116.068943 160.761233)
		(width 0.148)
		(layer "In4.Cu")
		(net 79)
	)
	(arc
		(start 120.346936 165.039227)
		(mid 120.266391 165.233681)
		(end 120.346936 165.428135)
		(width 0.148)
		(layer "In4.Cu")
		(net 79)
	)
	(arc
		(start 123.7025 166.890247)
		(mid 123.896954 166.809701)
		(end 123.9775 166.615247)
		(width 0.148)
		(layer "In4.Cu")
		(net 79)
	)
	(arc
		(start 119.569119 164.26141)
		(mid 119.488574 164.455864)
		(end 119.569119 164.650318)
		(width 0.148)
		(layer "In4.Cu")
		(net 79)
	)
	(arc
		(start 117.289049 161.096758)
		(mid 117.483504 161.016214)
		(end 117.677959 161.09676)
		(width 0.148)
		(layer "In4.Cu")
		(net 79)
	)
	(arc
		(start 118.844683 162.652392)
		(mid 119.039138 162.571848)
		(end 119.233593 162.652394)
		(width 0.148)
		(layer "In4.Cu")
		(net 79)
	)
	(arc
		(start 120.400317 164.208026)
		(mid 120.594772 164.127482)
		(end 120.789227 164.208028)
		(width 0.148)
		(layer "In4.Cu")
		(net 79)
	)
	(arc
		(start 118.066866 161.874575)
		(mid 118.261321 161.794031)
		(end 118.455776 161.874577)
		(width 0.148)
		(layer "In4.Cu")
		(net 79)
	)
	(arc
		(start 122.0525 166.3025)
		(mid 122.246954 166.383046)
		(end 122.3275 166.5775)
		(width 0.148)
		(layer "In4.Cu")
		(net 79)
	)
	(arc
		(start 118.013485 163.094685)
		(mid 118.20794 163.17523)
		(end 118.402394 163.094684)
		(width 0.148)
		(layer "In4.Cu")
		(net 79)
	)
	(arc
		(start 118.791302 163.483593)
		(mid 118.710757 163.678047)
		(end 118.791302 163.872501)
		(width 0.148)
		(layer "In4.Cu")
		(net 79)
	)
	(arc
		(start 123.9775 166.5775)
		(mid 124.058046 166.383046)
		(end 124.2525 166.3025)
		(width 0.148)
		(layer "In4.Cu")
		(net 79)
	)
	(arc
		(start 116.457851 161.150142)
		(mid 116.377306 161.344596)
		(end 116.457851 161.53905)
		(width 0.148)
		(layer "In4.Cu")
		(net 79)
	)
	(arc
		(start 114.902217 159.594508)
		(mid 114.821672 159.788962)
		(end 114.902217 159.983416)
		(width 0.148)
		(layer "In4.Cu")
		(net 79)
	)
	(arc
		(start 118.455776 161.874576)
		(mid 118.536321 162.069031)
		(end 118.455775 162.263485)
		(width 0.148)
		(layer "In4.Cu")
		(net 79)
	)
	(arc
		(start 122.8775 165.989753)
		(mid 122.958046 165.795299)
		(end 123.1525 165.714753)
		(width 0.148)
		(layer "In4.Cu")
		(net 79)
	)
	(arc
		(start 115.733415 159.541124)
		(mid 115.92787 159.46058)
		(end 116.122325 159.541126)
		(width 0.148)
		(layer "In4.Cu")
		(net 79)
	)
	(arc
		(start 123.1525 165.714753)
		(mid 123.346954 165.795299)
		(end 123.4275 165.989753)
		(width 0.148)
		(layer "In4.Cu")
		(net 79)
	)
	(arc
		(start 119.233593 162.652393)
		(mid 119.314138 162.846848)
		(end 119.233592 163.041302)
		(width 0.148)
		(layer "In4.Cu")
		(net 79)
	)
	(arc
		(start 115.680034 160.372325)
		(mid 115.599489 160.566779)
		(end 115.680034 160.761233)
		(width 0.148)
		(layer "In4.Cu")
		(net 79)
	)
	(arc
		(start 117.677959 161.096759)
		(mid 117.758504 161.291214)
		(end 117.677958 161.485668)
		(width 0.148)
		(layer "In4.Cu")
		(net 79)
	)
	(arc
		(start 121.540353 165.401444)
		(mid 121.459808 165.595899)
		(end 121.540354 165.790353)
		(width 0.148)
		(layer "In4.Cu")
		(net 79)
	)
	(arc
		(start 121.178134 164.985843)
		(mid 121.372589 164.905299)
		(end 121.567044 164.985845)
		(width 0.148)
		(layer "In4.Cu")
		(net 79)
	)
	(arc
		(start 122.3275 166.615247)
		(mid 122.408046 166.809701)
		(end 122.6025 166.890247)
		(width 0.148)
		(layer "In4.Cu")
		(net 79)
	)
	(arc
		(start 118.791302 163.872502)
		(mid 118.985757 163.953047)
		(end 119.180211 163.872501)
		(width 0.148)
		(layer "In4.Cu")
		(net 79)
	)
	(arc
		(start 114.54 158.79)
		(mid 114.734455 158.870545)
		(end 114.928909 158.789999)
		(width 0.148)
		(layer "In4.Cu")
		(net 79)
	)
	(arc
		(start 119.569119 164.650319)
		(mid 119.763574 164.730864)
		(end 119.958028 164.650318)
		(width 0.148)
		(layer "In4.Cu")
		(net 79)
	)
	(arc
		(start 114.902217 159.983417)
		(mid 115.096672 160.063962)
		(end 115.291126 159.983416)
		(width 0.148)
		(layer "In4.Cu")
		(net 79)
	)
	(arc
		(start 120.789227 164.208027)
		(mid 120.869772 164.402482)
		(end 120.789226 164.596936)
		(width 0.148)
		(layer "In4.Cu")
		(net 79)
	)
	(arc
		(start 116.457851 161.539051)
		(mid 116.652306 161.619596)
		(end 116.84676 161.53905)
		(width 0.148)
		(layer "In4.Cu")
		(net 79)
	)
	(arc
		(start 116.900142 160.318942)
		(mid 116.980687 160.513397)
		(end 116.900141 160.707851)
		(width 0.148)
		(layer "In4.Cu")
		(net 79)
	)
	(arc
		(start 123.4275 166.615247)
		(mid 123.508046 166.809701)
		(end 123.7025 166.890247)
		(width 0.148)
		(layer "In4.Cu")
		(net 79)
	)
	(arc
		(start 117.235668 162.316868)
		(mid 117.430123 162.397413)
		(end 117.624577 162.316867)
		(width 0.148)
		(layer "In4.Cu")
		(net 79)
	)
	(arc
		(start 119.6225 163.430209)
		(mid 119.816955 163.349665)
		(end 120.01141 163.430211)
		(width 0.148)
		(layer "In4.Cu")
		(net 79)
	)
	(arc
		(start 120.346936 165.428136)
		(mid 120.541391 165.508681)
		(end 120.735845 165.428135)
		(width 0.148)
		(layer "In4.Cu")
		(net 79)
	)
	(segment
		(start 115.650001 138.8025)
		(end 115.650001 139.8775)
		(width 0.201)
		(layer "F.Cu")
		(net 80)
	)
	(segment
		(start 132.376501 167.302)
		(end 131.877001 166.8025)
		(width 0.256)
		(layer "F.Cu")
		(net 80)
	)
	(via
		(at 131.877001 166.8025)
		(size 0.45)
		(drill 0.1)
		(layers "F.Cu" "B.Cu")
		(net 80)
	)
	(via
		(at 115.650001 139.8775)
		(size 0.45)
		(drill 0.1)
		(layers "F.Cu" "B.Cu")
		(net 80)
	)
	(segment
		(start 114.974501 145.653)
		(end 114.37 146.257501)
		(width 0.148)
		(layer "In4.Cu")
		(net 80)
	)
	(segment
		(start 115.650001 139.8775)
		(end 115.650001 140.599999)
		(width 0.148)
		(layer "In4.Cu")
		(net 80)
	)
	(segment
		(start 113 158.75)
		(end 121.5025 167.2525)
		(width 0.148)
		(layer "In4.Cu")
		(net 80)
	)
	(segment
		(start 112.71582 153.83)
		(end 113.28418 153.83)
		(width 0.148)
		(layer "In4.Cu")
		(net 80)
	)
	(segment
		(start 114.974501 141.275499)
		(end 114.974501 145.653)
		(width 0.148)
		(layer "In4.Cu")
		(net 80)
	)
	(segment
		(start 112.71582 150.33)
		(end 112.75 150.33)
		(width 0.148)
		(layer "In4.Cu")
		(net 80)
	)
	(segment
		(start 114.37 146.257501)
		(end 114.37 147.706501)
		(width 0.148)
		(layer "In4.Cu")
		(net 80)
	)
	(segment
		(start 112.71582 154.83)
		(end 113.28418 154.83)
		(width 0.148)
		(layer "In4.Cu")
		(net 80)
	)
	(segment
		(start 112.75 149.83)
		(end 112.71582 149.83)
		(width 0.148)
		(layer "In4.Cu")
		(net 80)
	)
	(segment
		(start 112.71582 153.33)
		(end 113.28418 153.33)
		(width 0.148)
		(layer "In4.Cu")
		(net 80)
	)
	(segment
		(start 131.427001 167.2525)
		(end 131.877001 166.8025)
		(width 0.148)
		(layer "In4.Cu")
		(net 80)
	)
	(segment
		(start 112.71582 151.83)
		(end 113.28418 151.83)
		(width 0.148)
		(layer "In4.Cu")
		(net 80)
	)
	(segment
		(start 112.75 150.33)
		(end 113.28418 150.33)
		(width 0.148)
		(layer "In4.Cu")
		(net 80)
	)
	(segment
		(start 113 156.08)
		(end 113 158.75)
		(width 0.148)
		(layer "In4.Cu")
		(net 80)
	)
	(segment
		(start 112.71582 152.83)
		(end 113.28418 152.83)
		(width 0.148)
		(layer "In4.Cu")
		(net 80)
	)
	(segment
		(start 113.28418 155.83)
		(end 113.25 155.83)
		(width 0.148)
		(layer "In4.Cu")
		(net 80)
	)
	(segment
		(start 112.71582 150.83)
		(end 113.28418 150.83)
		(width 0.148)
		(layer "In4.Cu")
		(net 80)
	)
	(segment
		(start 121.5025 167.2525)
		(end 131.427001 167.2525)
		(width 0.148)
		(layer "In4.Cu")
		(net 80)
	)
	(segment
		(start 114.37 147.706501)
		(end 113 149.076501)
		(width 0.148)
		(layer "In4.Cu")
		(net 80)
	)
	(segment
		(start 112.71582 155.33)
		(end 113.28418 155.33)
		(width 0.148)
		(layer "In4.Cu")
		(net 80)
	)
	(segment
		(start 115.650001 140.599999)
		(end 114.974501 141.275499)
		(width 0.148)
		(layer "In4.Cu")
		(net 80)
	)
	(segment
		(start 112.71582 152.33)
		(end 113.28418 152.33)
		(width 0.148)
		(layer "In4.Cu")
		(net 80)
	)
	(segment
		(start 113 149.076501)
		(end 113 149.58)
		(width 0.148)
		(layer "In4.Cu")
		(net 80)
	)
	(segment
		(start 112.71582 151.33)
		(end 113.28418 151.33)
		(width 0.148)
		(layer "In4.Cu")
		(net 80)
	)
	(segment
		(start 112.71582 154.33)
		(end 113.28418 154.33)
		(width 0.148)
		(layer "In4.Cu")
		(net 80)
	)
	(arc
		(start 112.71582 150.83)
		(mid 112.539043 150.903223)
		(end 112.46582 151.08)
		(width 0.148)
		(layer "In4.Cu")
		(net 80)
	)
	(arc
		(start 112.71582 151.83)
		(mid 112.539043 151.903223)
		(end 112.46582 152.08)
		(width 0.148)
		(layer "In4.Cu")
		(net 80)
	)
	(arc
		(start 112.46582 153.08)
		(mid 112.539043 153.256777)
		(end 112.71582 153.33)
		(width 0.148)
		(layer "In4.Cu")
		(net 80)
	)
	(arc
		(start 112.71582 149.83)
		(mid 112.539043 149.903223)
		(end 112.46582 150.08)
		(width 0.148)
		(layer "In4.Cu")
		(net 80)
	)
	(arc
		(start 112.71582 154.83)
		(mid 112.539043 154.903223)
		(end 112.46582 155.08)
		(width 0.148)
		(layer "In4.Cu")
		(net 80)
	)
	(arc
		(start 113.28418 152.33)
		(mid 113.460957 152.403223)
		(end 113.53418 152.58)
		(width 0.148)
		(layer "In4.Cu")
		(net 80)
	)
	(arc
		(start 113.53418 152.58)
		(mid 113.460957 152.756777)
		(end 113.28418 152.83)
		(width 0.148)
		(layer "In4.Cu")
		(net 80)
	)
	(arc
		(start 112.46582 155.08)
		(mid 112.539043 155.256777)
		(end 112.71582 155.33)
		(width 0.148)
		(layer "In4.Cu")
		(net 80)
	)
	(arc
		(start 113.28418 153.33)
		(mid 113.460957 153.403223)
		(end 113.53418 153.58)
		(width 0.148)
		(layer "In4.Cu")
		(net 80)
	)
	(arc
		(start 112.71582 152.83)
		(mid 112.539043 152.903223)
		(end 112.46582 153.08)
		(width 0.148)
		(layer "In4.Cu")
		(net 80)
	)
	(arc
		(start 113.28418 151.33)
		(mid 113.460957 151.403223)
		(end 113.53418 151.58)
		(width 0.148)
		(layer "In4.Cu")
		(net 80)
	)
	(arc
		(start 112.46582 152.08)
		(mid 112.539043 152.256777)
		(end 112.71582 152.33)
		(width 0.148)
		(layer "In4.Cu")
		(net 80)
	)
	(arc
		(start 113.53418 153.58)
		(mid 113.460957 153.756777)
		(end 113.28418 153.83)
		(width 0.148)
		(layer "In4.Cu")
		(net 80)
	)
	(arc
		(start 112.46582 150.08)
		(mid 112.539043 150.256777)
		(end 112.71582 150.33)
		(width 0.148)
		(layer "In4.Cu")
		(net 80)
	)
	(arc
		(start 113 149.58)
		(mid 112.926777 149.756777)
		(end 112.75 149.83)
		(width 0.148)
		(layer "In4.Cu")
		(net 80)
	)
	(arc
		(start 112.46582 151.08)
		(mid 112.539043 151.256777)
		(end 112.71582 151.33)
		(width 0.148)
		(layer "In4.Cu")
		(net 80)
	)
	(arc
		(start 113.53418 151.58)
		(mid 113.460957 151.756777)
		(end 113.28418 151.83)
		(width 0.148)
		(layer "In4.Cu")
		(net 80)
	)
	(arc
		(start 113.53418 154.58)
		(mid 113.460957 154.756777)
		(end 113.28418 154.83)
		(width 0.148)
		(layer "In4.Cu")
		(net 80)
	)
	(arc
		(start 113.28418 155.33)
		(mid 113.460957 155.403223)
		(end 113.53418 155.58)
		(width 0.148)
		(layer "In4.Cu")
		(net 80)
	)
	(arc
		(start 113.53418 155.58)
		(mid 113.460957 155.756777)
		(end 113.28418 155.83)
		(width 0.148)
		(layer "In4.Cu")
		(net 80)
	)
	(arc
		(start 113.28418 154.33)
		(mid 113.460957 154.403223)
		(end 113.53418 154.58)
		(width 0.148)
		(layer "In4.Cu")
		(net 80)
	)
	(arc
		(start 112.71582 153.83)
		(mid 112.539043 153.903223)
		(end 112.46582 154.08)
		(width 0.148)
		(layer "In4.Cu")
		(net 80)
	)
	(arc
		(start 113.25 155.83)
		(mid 113.073223 155.903223)
		(end 113 156.08)
		(width 0.148)
		(layer "In4.Cu")
		(net 80)
	)
	(arc
		(start 113.28418 150.33)
		(mid 113.460957 150.403223)
		(end 113.53418 150.58)
		(width 0.148)
		(layer "In4.Cu")
		(net 80)
	)
	(arc
		(start 112.46582 154.08)
		(mid 112.539043 154.256777)
		(end 112.71582 154.33)
		(width 0.148)
		(layer "In4.Cu")
		(net 80)
	)
	(arc
		(start 113.53418 150.58)
		(mid 113.460957 150.756777)
		(end 113.28418 150.83)
		(width 0.148)
		(layer "In4.Cu")
		(net 80)
	)
	(segment
		(start 115.900001 146.2025)
		(end 115.900001 146.8025)
		(width 0.26)
		(layer "F.Cu")
		(net 81)
	)
	(segment
		(start 115.92 147.292427)
		(end 115.875001 147.337426)
		(width 0.26)
		(layer "F.Cu")
		(net 81)
	)
	(segment
		(start 115.900001 146.8025)
		(end 115.920001 146.8225)
		(width 0.26)
		(layer "F.Cu")
		(net 81)
	)
	(segment
		(start 115.920001 146.8225)
		(end 115.92 147.292427)
		(width 0.26)
		(layer "F.Cu")
		(net 81)
	)
	(segment
		(start 132.376501 163.302)
		(end 131.877001 162.8025)
		(width 0.256)
		(layer "F.Cu")
		(net 81)
	)
	(via
		(at 131.877001 162.8025)
		(size 0.45)
		(drill 0.1)
		(layers "F.Cu" "B.Cu")
		(net 81)
	)
	(via
		(at 115.875001 147.337426)
		(size 0.45)
		(drill 0.1)
		(layers "F.Cu" "B.Cu")
		(net 81)
	)
	(segment
		(start 125.350501 164.421)
		(end 125.369001 164.4025)
		(width 0.1)
		(layer "In4.Cu")
		(net 81)
	)
	(segment
		(start 131.975001 163.2025)
		(end 131.877001 163.1045)
		(width 0.1)
		(layer "In4.Cu")
		(net 81)
	)
	(segment
		(start 116.030001 147.492426)
		(end 116.030001 149.699707)
		(width 0.13)
		(layer "In4.Cu")
		(net 81)
	)
	(segment
		(start 117.88 151.549706)
		(end 117.88 152.24)
		(width 0.13)
		(layer "In4.Cu")
		(net 81)
	)
	(segment
		(start 117.88 158.925205)
		(end 121.532397 162.577601)
		(width 0.13)
		(layer "In4.Cu")
		(net 81)
	)
	(segment
		(start 132.216422 164.4025)
		(end 132.477001 164.141922)
		(width 0.1)
		(layer "In4.Cu")
		(net 81)
	)
	(segment
		(start 116.88 153.32)
		(end 119.12 153.32)
		(width 0.13)
		(layer "In4.Cu")
		(net 81)
	)
	(segment
		(start 116.88 155.96)
		(end 119.12 155.96)
		(width 0.13)
		(layer "In4.Cu")
		(net 81)
	)
	(segment
		(start 117.88 157.84)
		(end 117.88 158.925205)
		(width 0.13)
		(layer "In4.Cu")
		(net 81)
	)
	(segment
		(start 123.375795 164.421)
		(end 125.350501 164.421)
		(width 0.13)
		(layer "In4.Cu")
		(net 81)
	)
	(segment
		(start 116.88 156.52)
		(end 119.12 156.52)
		(width 0.13)
		(layer "In4.Cu")
		(net 81)
	)
	(segment
		(start 122.267789 162.577603)
		(end 122.267789 162.577602)
		(width 0.13)
		(layer "In4.Cu")
		(net 81)
	)
	(segment
		(start 125.369001 164.4025)
		(end 132.216422 164.4025)
		(width 0.1)
		(layer "In4.Cu")
		(net 81)
	)
	(segment
		(start 132.477001 164.141922)
		(end 132.477001 163.514144)
		(width 0.1)
		(layer "In4.Cu")
		(net 81)
	)
	(segment
		(start 122.663768 163.708971)
		(end 122.663768 163.708972)
		(width 0.13)
		(layer "In4.Cu")
		(net 81)
	)
	(segment
		(start 132.477001 163.514144)
		(end 132.165358 163.2025)
		(width 0.1)
		(layer "In4.Cu")
		(net 81)
	)
	(segment
		(start 124.003498 161.633849)
		(end 124.0035 161.63385)
		(width 0.13)
		(layer "In4.Cu")
		(net 81)
	)
	(segment
		(start 124.003501 161.237871)
		(end 124.003499 161.23787)
		(width 0.13)
		(layer "In4.Cu")
		(net 81)
	)
	(segment
		(start 115.875001 147.337426)
		(end 116.030001 147.492426)
		(width 0.13)
		(layer "In4.Cu")
		(net 81)
	)
	(segment
		(start 116.88 154.36)
		(end 119.12 154.36)
		(width 0.13)
		(layer "In4.Cu")
		(net 81)
	)
	(segment
		(start 131.877001 163.1045)
		(end 131.877001 162.8025)
		(width 0.1)
		(layer "In4.Cu")
		(net 81)
	)
	(segment
		(start 122.663768 163.708972)
		(end 123.375795 164.421)
		(width 0.13)
		(layer "In4.Cu")
		(net 81)
	)
	(segment
		(start 116.030001 149.699707)
		(end 117.88 151.549706)
		(width 0.13)
		(layer "In4.Cu")
		(net 81)
	)
	(segment
		(start 132.165358 163.2025)
		(end 131.975001 163.2025)
		(width 0.1)
		(layer "In4.Cu")
		(net 81)
	)
	(segment
		(start 116.88 157.56)
		(end 117.6 157.56)
		(width 0.13)
		(layer "In4.Cu")
		(net 81)
	)
	(segment
		(start 122.267789 162.577602)
		(end 123.607521 161.237871)
		(width 0.13)
		(layer "In4.Cu")
		(net 81)
	)
	(segment
		(start 118.4 152.76)
		(end 119.12 152.76)
		(width 0.13)
		(layer "In4.Cu")
		(net 81)
	)
	(segment
		(start 116.88 154.92)
		(end 119.12 154.92)
		(width 0.13)
		(layer "In4.Cu")
		(net 81)
	)
	(segment
		(start 124.0035 161.63385)
		(end 122.663767 162.97358)
		(width 0.13)
		(layer "In4.Cu")
		(net 81)
	)
	(arc
		(start 119.12 155.96)
		(mid 119.31799 156.04201)
		(end 119.4 156.24)
		(width 0.13)
		(layer "In4.Cu")
		(net 81)
	)
	(arc
		(start 116.88 153.32)
		(mid 116.512304 153.472304)
		(end 116.36 153.84)
		(width 0.13)
		(layer "In4.Cu")
		(net 81)
	)
	(arc
		(start 119.4 154.64)
		(mid 119.31799 154.83799)
		(end 119.12 154.92)
		(width 0.13)
		(layer "In4.Cu")
		(net 81)
	)
	(arc
		(start 124.003499 161.23787)
		(mid 124.085509 161.435861)
		(end 124.003498 161.633849)
		(width 0.13)
		(layer "In4.Cu")
		(net 81)
	)
	(arc
		(start 123.607521 161.237871)
		(mid 123.805511 161.155861)
		(end 124.003501 161.237871)
		(width 0.13)
		(layer "In4.Cu")
		(net 81)
	)
	(arc
		(start 116.88 154.92)
		(mid 116.512304 155.072304)
		(end 116.36 155.44)
		(width 0.13)
		(layer "In4.Cu")
		(net 81)
	)
	(arc
		(start 116.36 155.44)
		(mid 116.512304 155.807696)
		(end 116.88 155.96)
		(width 0.13)
		(layer "In4.Cu")
		(net 81)
	)
	(arc
		(start 119.12 152.76)
		(mid 119.31799 152.84201)
		(end 119.4 153.04)
		(width 0.13)
		(layer "In4.Cu")
		(net 81)
	)
	(arc
		(start 116.88 156.52)
		(mid 116.512304 156.672304)
		(end 116.36 157.04)
		(width 0.13)
		(layer "In4.Cu")
		(net 81)
	)
	(arc
		(start 119.4 156.24)
		(mid 119.31799 156.43799)
		(end 119.12 156.52)
		(width 0.13)
		(layer "In4.Cu")
		(net 81)
	)
	(arc
		(start 119.4 153.04)
		(mid 119.31799 153.23799)
		(end 119.12 153.32)
		(width 0.13)
		(layer "In4.Cu")
		(net 81)
	)
	(arc
		(start 117.88 152.24)
		(mid 118.032304 152.607696)
		(end 118.4 152.76)
		(width 0.13)
		(layer "In4.Cu")
		(net 81)
	)
	(arc
		(start 122.663767 162.97358)
		(mid 122.511463 163.341276)
		(end 122.663768 163.708971)
		(width 0.13)
		(layer "In4.Cu")
		(net 81)
	)
	(arc
		(start 116.36 153.84)
		(mid 116.512304 154.207696)
		(end 116.88 154.36)
		(width 0.13)
		(layer "In4.Cu")
		(net 81)
	)
	(arc
		(start 119.12 154.36)
		(mid 119.31799 154.44201)
		(end 119.4 154.64)
		(width 0.13)
		(layer "In4.Cu")
		(net 81)
	)
	(arc
		(start 116.36 157.04)
		(mid 116.512304 157.407696)
		(end 116.88 157.56)
		(width 0.13)
		(layer "In4.Cu")
		(net 81)
	)
	(arc
		(start 117.6 157.56)
		(mid 117.79799 157.64201)
		(end 117.88 157.84)
		(width 0.13)
		(layer "In4.Cu")
		(net 81)
	)
	(arc
		(start 121.532397 162.577601)
		(mid 121.900093 162.729906)
		(end 122.267789 162.577603)
		(width 0.13)
		(layer "In4.Cu")
		(net 81)
	)
	(segment
		(start 116.380002 147.292427)
		(end 116.425001 147.337426)
		(width 0.26)
		(layer "F.Cu")
		(net 82)
	)
	(segment
		(start 116.380001 146.8225)
		(end 116.380002 147.292427)
		(width 0.26)
		(layer "F.Cu")
		(net 82)
	)
	(segment
		(start 116.400001 146.2025)
		(end 116.400001 146.8025)
		(width 0.26)
		(layer "F.Cu")
		(net 82)
	)
	(segment
		(start 132.376501 164.302)
		(end 131.877001 163.8025)
		(width 0.256)
		(layer "F.Cu")
		(net 82)
	)
	(segment
		(start 116.400001 146.8025)
		(end 116.380001 146.8225)
		(width 0.26)
		(layer "F.Cu")
		(net 82)
	)
	(via
		(at 116.425001 147.337426)
		(size 0.45)
		(drill 0.1)
		(layers "F.Cu" "B.Cu")
		(net 82)
	)
	(via
		(at 131.877001 163.8025)
		(size 0.45)
		(drill 0.1)
		(layers "F.Cu" "B.Cu")
		(net 82)
	)
	(segment
		(start 124.759 163.832654)
		(end 124.759 163.931)
		(width 0.13)
		(layer "In4.Cu")
		(net 82)
	)
	(segment
		(start 116.88 155.72)
		(end 119.12 155.72)
		(width 0.13)
		(layer "In4.Cu")
		(net 82)
	)
	(segment
		(start 132.082515 163.4025)
		(end 132.277001 163.596987)
		(width 0.1)
		(layer "In4.Cu")
		(net 82)
	)
	(segment
		(start 118.12 151.450294)
		(end 118.12 152.24)
		(width 0.13)
		(layer "In4.Cu")
		(net 82)
	)
	(segment
		(start 132.277001 163.596987)
		(end 132.277001 164.059078)
		(width 0.1)
		(layer "In4.Cu")
		(net 82)
	)
	(segment
		(start 123.475207 164.181)
		(end 124.009 164.181)
		(width 0.13)
		(layer "In4.Cu")
		(net 82)
	)
	(segment
		(start 124.173205 161.068166)
		(end 124.173206 161.068166)
		(width 0.13)
		(layer "In4.Cu")
		(net 82)
	)
	(segment
		(start 131.877001 163.5045)
		(end 131.979001 163.4025)
		(width 0.1)
		(layer "In4.Cu")
		(net 82)
	)
	(segment
		(start 122.098084 162.407898)
		(end 123.437814 161.068165)
		(width 0.13)
		(layer "In4.Cu")
		(net 82)
	)
	(segment
		(start 125.009 164.181)
		(end 125.350501 164.181)
		(width 0.13)
		(layer "In4.Cu")
		(net 82)
	)
	(segment
		(start 118.12 158.825793)
		(end 121.702102 162.407896)
		(width 0.13)
		(layer "In4.Cu")
		(net 82)
	)
	(segment
		(start 116.425001 147.337426)
		(end 116.270001 147.492426)
		(width 0.13)
		(layer "In4.Cu")
		(net 82)
	)
	(segment
		(start 124.173205 161.803557)
		(end 124.173205 161.803556)
		(width 0.13)
		(layer "In4.Cu")
		(net 82)
	)
	(segment
		(start 116.88 154.12)
		(end 119.12 154.12)
		(width 0.13)
		(layer "In4.Cu")
		(net 82)
	)
	(segment
		(start 122.833473 163.539266)
		(end 123.475207 164.181)
		(width 0.13)
		(layer "In4.Cu")
		(net 82)
	)
	(segment
		(start 132.133579 164.2025)
		(end 125.372001 164.2025)
		(width 0.1)
		(layer "In4.Cu")
		(net 82)
	)
	(segment
		(start 116.270001 147.492426)
		(end 116.270001 149.600295)
		(width 0.13)
		(layer "In4.Cu")
		(net 82)
	)
	(segment
		(start 124.173205 161.803556)
		(end 122.833474 163.143288)
		(width 0.13)
		(layer "In4.Cu")
		(net 82)
	)
	(segment
		(start 116.88 157.32)
		(end 117.6 157.32)
		(width 0.13)
		(layer "In4.Cu")
		(net 82)
	)
	(segment
		(start 116.88 153.56)
		(end 119.12 153.56)
		(width 0.13)
		(layer "In4.Cu")
		(net 82)
	)
	(segment
		(start 131.979001 163.4025)
		(end 132.082515 163.4025)
		(width 0.1)
		(layer "In4.Cu")
		(net 82)
	)
	(segment
		(start 125.372001 164.2025)
		(end 125.350501 164.181)
		(width 0.1)
		(layer "In4.Cu")
		(net 82)
	)
	(segment
		(start 122.833474 163.539268)
		(end 122.833473 163.539266)
		(width 0.13)
		(layer "In4.Cu")
		(net 82)
	)
	(segment
		(start 116.88 155.16)
		(end 119.12 155.16)
		(width 0.13)
		(layer "In4.Cu")
		(net 82)
	)
	(segment
		(start 116.270001 149.600295)
		(end 118.12 151.450294)
		(width 0.13)
		(layer "In4.Cu")
		(net 82)
	)
	(segment
		(start 132.277001 164.059078)
		(end 132.133579 164.2025)
		(width 0.1)
		(layer "In4.Cu")
		(net 82)
	)
	(segment
		(start 124.259 163.931)
		(end 124.259 163.832654)
		(width 0.13)
		(layer "In4.Cu")
		(net 82)
	)
	(segment
		(start 116.88 156.76)
		(end 119.12 156.76)
		(width 0.13)
		(layer "In4.Cu")
		(net 82)
	)
	(segment
		(start 118.12 157.84)
		(end 118.12 158.825793)
		(width 0.13)
		(layer "In4.Cu")
		(net 82)
	)
	(segment
		(start 131.877001 163.5045)
		(end 131.877001 163.8025)
		(width 0.1)
		(layer "In4.Cu")
		(net 82)
	)
	(segment
		(start 118.4 152.52)
		(end 119.12 152.52)
		(width 0.13)
		(layer "In4.Cu")
		(net 82)
	)
	(arc
		(start 117.6 157.32)
		(mid 117.967696 157.472304)
		(end 118.12 157.84)
		(width 0.13)
		(layer "In4.Cu")
		(net 82)
	)
	(arc
		(start 116.88 155.16)
		(mid 116.68201 155.24201)
		(end 116.6 155.44)
		(width 0.13)
		(layer "In4.Cu")
		(net 82)
	)
	(arc
		(start 122.833474 163.143288)
		(mid 122.751464 163.341278)
		(end 122.833474 163.539268)
		(width 0.13)
		(layer "In4.Cu")
		(net 82)
	)
	(arc
		(start 119.64 154.64)
		(mid 119.487696 155.007696)
		(end 119.12 155.16)
		(width 0.13)
		(layer "In4.Cu")
		(net 82)
	)
	(arc
		(start 123.437814 161.068165)
		(mid 123.80551 160.915861)
		(end 124.173205 161.068166)
		(width 0.13)
		(layer "In4.Cu")
		(net 82)
	)
	(arc
		(start 124.009 164.181)
		(mid 124.185777 164.107777)
		(end 124.259 163.931)
		(width 0.13)
		(layer "In4.Cu")
		(net 82)
	)
	(arc
		(start 116.6 157.04)
		(mid 116.68201 157.23799)
		(end 116.88 157.32)
		(width 0.13)
		(layer "In4.Cu")
		(net 82)
	)
	(arc
		(start 116.88 156.76)
		(mid 116.68201 156.84201)
		(end 116.6 157.04)
		(width 0.13)
		(layer "In4.Cu")
		(net 82)
	)
	(arc
		(start 118.12 152.24)
		(mid 118.20201 152.43799)
		(end 118.4 152.52)
		(width 0.13)
		(layer "In4.Cu")
		(net 82)
	)
	(arc
		(start 124.759 163.931)
		(mid 124.832223 164.107777)
		(end 125.009 164.181)
		(width 0.13)
		(layer "In4.Cu")
		(net 82)
	)
	(arc
		(start 121.702102 162.407896)
		(mid 121.900094 162.489908)
		(end 122.098084 162.407898)
		(width 0.13)
		(layer "In4.Cu")
		(net 82)
	)
	(arc
		(start 119.64 153.04)
		(mid 119.487696 153.407696)
		(end 119.12 153.56)
		(width 0.13)
		(layer "In4.Cu")
		(net 82)
	)
	(arc
		(start 119.64 156.24)
		(mid 119.487696 156.607696)
		(end 119.12 156.76)
		(width 0.13)
		(layer "In4.Cu")
		(net 82)
	)
	(arc
		(start 119.12 155.72)
		(mid 119.487696 155.872304)
		(end 119.64 156.24)
		(width 0.13)
		(layer "In4.Cu")
		(net 82)
	)
	(arc
		(start 116.6 153.84)
		(mid 116.68201 154.03799)
		(end 116.88 154.12)
		(width 0.13)
		(layer "In4.Cu")
		(net 82)
	)
	(arc
		(start 119.12 154.12)
		(mid 119.487696 154.272304)
		(end 119.64 154.64)
		(width 0.13)
		(layer "In4.Cu")
		(net 82)
	)
	(arc
		(start 124.173206 161.068166)
		(mid 124.32551 161.435862)
		(end 124.173205 161.803557)
		(width 0.13)
		(layer "In4.Cu")
		(net 82)
	)
	(arc
		(start 124.509 163.582654)
		(mid 124.685777 163.655877)
		(end 124.759 163.832654)
		(width 0.13)
		(layer "In4.Cu")
		(net 82)
	)
	(arc
		(start 116.88 153.56)
		(mid 116.68201 153.64201)
		(end 116.6 153.84)
		(width 0.13)
		(layer "In4.Cu")
		(net 82)
	)
	(arc
		(start 124.259 163.832654)
		(mid 124.332223 163.655877)
		(end 124.509 163.582654)
		(width 0.13)
		(layer "In4.Cu")
		(net 82)
	)
	(arc
		(start 116.6 155.44)
		(mid 116.68201 155.63799)
		(end 116.88 155.72)
		(width 0.13)
		(layer "In4.Cu")
		(net 82)
	)
	(arc
		(start 119.12 152.52)
		(mid 119.487696 152.672304)
		(end 119.64 153.04)
		(width 0.13)
		(layer "In4.Cu")
		(net 82)
	)
	(segment
		(start 116.650001 138.8025)
		(end 116.650001 139.8775)
		(width 0.201)
		(layer "F.Cu")
		(net 83)
	)
	(segment
		(start 133.376501 165.302)
		(end 132.877001 164.8025)
		(width 0.256)
		(layer "F.Cu")
		(net 83)
	)
	(via
		(at 132.877001 164.8025)
		(size 0.45)
		(drill 0.1)
		(layers "F.Cu" "B.Cu")
		(net 83)
	)
	(via
		(at 116.650001 139.8775)
		(size 0.45)
		(drill 0.1)
		(layers "F.Cu" "B.Cu")
		(net 83)
	)
	(segment
		(start 114.54 155.785)
		(end 114.54 155.735)
		(width 0.148)
		(layer "In4.Cu")
		(net 83)
	)
	(segment
		(start 115.4 148.35)
		(end 115.4 146.327501)
		(width 0.148)
		(layer "In4.Cu")
		(net 83)
	)
	(segment
		(start 116.359329 143.924999)
		(end 116.325001 143.924999)
		(width 0.148)
		(layer "In4.Cu")
		(net 83)
	)
	(segment
		(start 115.4 146.327501)
		(end 116.075001 145.6525)
		(width 0.148)
		(layer "In4.Cu")
		(net 83)
	)
	(segment
		(start 122.4225 165.3025)
		(end 114.99 157.87)
		(width 0.148)
		(layer "In4.Cu")
		(net 83)
	)
	(segment
		(start 132.577001 165.1025)
		(end 132.575001 165.1025)
		(width 0.148)
		(layer "In4.Cu")
		(net 83)
	)
	(segment
		(start 114.765 152.51)
		(end 115.34 152.51)
		(width 0.148)
		(layer "In4.Cu")
		(net 83)
	)
	(segment
		(start 116.325001 143.924999)
		(end 115.790673 143.924999)
		(width 0.148)
		(layer "In4.Cu")
		(net 83)
	)
	(segment
		(start 114.54 151.785)
		(end 114.54 151.735)
		(width 0.148)
		(layer "In4.Cu")
		(net 83)
	)
	(segment
		(start 132.375001 165.3025)
		(end 122.4225 165.3025)
		(width 0.148)
		(layer "In4.Cu")
		(net 83)
	)
	(segment
		(start 116.075001 143.174999)
		(end 116.075001 141.174999)
		(width 0.148)
		(layer "In4.Cu")
		(net 83)
	)
	(segment
		(start 114.765 155.51)
		(end 115.34 155.51)
		(width 0.148)
		(layer "In4.Cu")
		(net 83)
	)
	(segment
		(start 114.54 150.785)
		(end 114.54 150.735)
		(width 0.148)
		(layer "In4.Cu")
		(net 83)
	)
	(segment
		(start 114.765 153.51)
		(end 115.34 153.51)
		(width 0.148)
		(layer "In4.Cu")
		(net 83)
	)
	(segment
		(start 114.54 153.785)
		(end 114.54 153.735)
		(width 0.148)
		(layer "In4.Cu")
		(net 83)
	)
	(segment
		(start 116.650001 140.599999)
		(end 116.650001 139.8775)
		(width 0.148)
		(layer "In4.Cu")
		(net 83)
	)
	(segment
		(start 116.075001 141.174999)
		(end 116.650001 140.599999)
		(width 0.148)
		(layer "In4.Cu")
		(net 83)
	)
	(segment
		(start 114.765 151.01)
		(end 115.34 151.01)
		(width 0.148)
		(layer "In4.Cu")
		(net 83)
	)
	(segment
		(start 114.765 154.01)
		(end 115.34 154.01)
		(width 0.148)
		(layer "In4.Cu")
		(net 83)
	)
	(segment
		(start 115.34 156.01)
		(end 115.24 156.01)
		(width 0.148)
		(layer "In4.Cu")
		(net 83)
	)
	(segment
		(start 114.765 153.01)
		(end 115.34 153.01)
		(width 0.148)
		(layer "In4.Cu")
		(net 83)
	)
	(segment
		(start 116.075001 145.6525)
		(end 116.075001 144.674999)
		(width 0.148)
		(layer "In4.Cu")
		(net 83)
	)
	(segment
		(start 114.765 152.01)
		(end 115.34 152.01)
		(width 0.148)
		(layer "In4.Cu")
		(net 83)
	)
	(segment
		(start 114.54 152.785)
		(end 114.54 152.735)
		(width 0.148)
		(layer "In4.Cu")
		(net 83)
	)
	(segment
		(start 132.575001 165.1025)
		(end 132.375001 165.3025)
		(width 0.148)
		(layer "In4.Cu")
		(net 83)
	)
	(segment
		(start 114.99 157.87)
		(end 114.99 156.76)
		(width 0.148)
		(layer "In4.Cu")
		(net 83)
	)
	(segment
		(start 114.99 150.285)
		(end 114.99 148.76)
		(width 0.148)
		(layer "In4.Cu")
		(net 83)
	)
	(segment
		(start 116.325001 144.424999)
		(end 116.359329 144.424999)
		(width 0.148)
		(layer "In4.Cu")
		(net 83)
	)
	(segment
		(start 132.877001 164.8025)
		(end 132.577001 165.1025)
		(width 0.148)
		(layer "In4.Cu")
		(net 83)
	)
	(segment
		(start 114.99 148.76)
		(end 115.4 148.35)
		(width 0.148)
		(layer "In4.Cu")
		(net 83)
	)
	(segment
		(start 115.24 156.01)
		(end 114.765 156.01)
		(width 0.148)
		(layer "In4.Cu")
		(net 83)
	)
	(segment
		(start 114.765 151.51)
		(end 115.34 151.51)
		(width 0.148)
		(layer "In4.Cu")
		(net 83)
	)
	(segment
		(start 114.765 154.51)
		(end 115.34 154.51)
		(width 0.148)
		(layer "In4.Cu")
		(net 83)
	)
	(segment
		(start 114.54 154.785)
		(end 114.54 154.735)
		(width 0.148)
		(layer "In4.Cu")
		(net 83)
	)
	(segment
		(start 114.765 155.01)
		(end 115.34 155.01)
		(width 0.148)
		(layer "In4.Cu")
		(net 83)
	)
	(segment
		(start 115.790673 143.424999)
		(end 115.825001 143.424999)
		(width 0.148)
		(layer "In4.Cu")
		(net 83)
	)
	(segment
		(start 115.24 156.51)
		(end 115.34 156.51)
		(width 0.148)
		(layer "In4.Cu")
		(net 83)
	)
	(arc
		(start 115.59 152.26)
		(mid 115.516777 152.083223)
		(end 115.34 152.01)
		(width 0.148)
		(layer "In4.Cu")
		(net 83)
	)
	(arc
		(start 115.34 152.51)
		(mid 115.516777 152.436777)
		(end 115.59 152.26)
		(width 0.148)
		(layer "In4.Cu")
		(net 83)
	)
	(arc
		(start 114.54 155.735)
		(mid 114.605901 155.575901)
		(end 114.765 155.51)
		(width 0.148)
		(layer "In4.Cu")
		(net 83)
	)
	(arc
		(start 116.609329 144.174999)
		(mid 116.536106 143.998222)
		(end 116.359329 143.924999)
		(width 0.148)
		(layer "In4.Cu")
		(net 83)
	)
	(arc
		(start 114.54 152.735)
		(mid 114.605901 152.575901)
		(end 114.765 152.51)
		(width 0.148)
		(layer "In4.Cu")
		(net 83)
	)
	(arc
		(start 115.59 153.26)
		(mid 115.516777 153.083223)
		(end 115.34 153.01)
		(width 0.148)
		(layer "In4.Cu")
		(net 83)
	)
	(arc
		(start 114.765 155.01)
		(mid 114.605901 154.944099)
		(end 114.54 154.785)
		(width 0.148)
		(layer "In4.Cu")
		(net 83)
	)
	(arc
		(start 115.790673 143.924999)
		(mid 115.613896 143.851776)
		(end 115.540673 143.674999)
		(width 0.148)
		(layer "In4.Cu")
		(net 83)
	)
	(arc
		(start 114.765 150.51)
		(mid 114.924099 150.444099)
		(end 114.99 150.285)
		(width 0.148)
		(layer "In4.Cu")
		(net 83)
	)
	(arc
		(start 114.54 151.735)
		(mid 114.605901 151.575901)
		(end 114.765 151.51)
		(width 0.148)
		(layer "In4.Cu")
		(net 83)
	)
	(arc
		(start 115.34 155.51)
		(mid 115.516777 155.436777)
		(end 115.59 155.26)
		(width 0.148)
		(layer "In4.Cu")
		(net 83)
	)
	(arc
		(start 115.59 156.26)
		(mid 115.516777 156.083223)
		(end 115.34 156.01)
		(width 0.148)
		(layer "In4.Cu")
		(net 83)
	)
	(arc
		(start 115.34 156.51)
		(mid 115.516777 156.436777)
		(end 115.59 156.26)
		(width 0.148)
		(layer "In4.Cu")
		(net 83)
	)
	(arc
		(start 115.59 154.26)
		(mid 115.516777 154.083223)
		(end 115.34 154.01)
		(width 0.148)
		(layer "In4.Cu")
		(net 83)
	)
	(arc
		(start 114.765 156.01)
		(mid 114.605901 155.944099)
		(end 114.54 155.785)
		(width 0.148)
		(layer "In4.Cu")
		(net 83)
	)
	(arc
		(start 114.765 151.01)
		(mid 114.605901 150.944099)
		(end 114.54 150.785)
		(width 0.148)
		(layer "In4.Cu")
		(net 83)
	)
	(arc
		(start 116.359329 144.424999)
		(mid 116.536106 144.351776)
		(end 116.609329 144.174999)
		(width 0.148)
		(layer "In4.Cu")
		(net 83)
	)
	(arc
		(start 114.765 154.01)
		(mid 114.605901 153.944099)
		(end 114.54 153.785)
		(width 0.148)
		(layer "In4.Cu")
		(net 83)
	)
	(arc
		(start 115.825001 143.424999)
		(mid 116.001778 143.351776)
		(end 116.075001 143.174999)
		(width 0.148)
		(layer "In4.Cu")
		(net 83)
	)
	(arc
		(start 114.54 154.735)
		(mid 114.605901 154.575901)
		(end 114.765 154.51)
		(width 0.148)
		(layer "In4.Cu")
		(net 83)
	)
	(arc
		(start 115.34 151.51)
		(mid 115.516777 151.436777)
		(end 115.59 151.26)
		(width 0.148)
		(layer "In4.Cu")
		(net 83)
	)
	(arc
		(start 114.99 156.76)
		(mid 115.063223 156.583223)
		(end 115.24 156.51)
		(width 0.148)
		(layer "In4.Cu")
		(net 83)
	)
	(arc
		(start 115.34 153.51)
		(mid 115.516777 153.436777)
		(end 115.59 153.26)
		(width 0.148)
		(layer "In4.Cu")
		(net 83)
	)
	(arc
		(start 115.34 154.51)
		(mid 115.516777 154.436777)
		(end 115.59 154.26)
		(width 0.148)
		(layer "In4.Cu")
		(net 83)
	)
	(arc
		(start 114.765 153.01)
		(mid 114.605901 152.944099)
		(end 114.54 152.785)
		(width 0.148)
		(layer "In4.Cu")
		(net 83)
	)
	(arc
		(start 114.54 153.735)
		(mid 114.605901 153.575901)
		(end 114.765 153.51)
		(width 0.148)
		(layer "In4.Cu")
		(net 83)
	)
	(arc
		(start 115.540673 143.674999)
		(mid 115.613896 143.498222)
		(end 115.790673 143.424999)
		(width 0.148)
		(layer "In4.Cu")
		(net 83)
	)
	(arc
		(start 115.59 155.26)
		(mid 115.516777 155.083223)
		(end 115.34 155.01)
		(width 0.148)
		(layer "In4.Cu")
		(net 83)
	)
	(arc
		(start 116.075001 144.674999)
		(mid 116.148224 144.498222)
		(end 116.325001 144.424999)
		(width 0.148)
		(layer "In4.Cu")
		(net 83)
	)
	(arc
		(start 115.59 151.26)
		(mid 115.516777 151.083223)
		(end 115.34 151.01)
		(width 0.148)
		(layer "In4.Cu")
		(net 83)
	)
	(arc
		(start 114.54 150.735)
		(mid 114.605901 150.575901)
		(end 114.765 150.51)
		(width 0.148)
		(layer "In4.Cu")
		(net 83)
	)
	(arc
		(start 114.765 152.01)
		(mid 114.605901 151.944099)
		(end 114.54 151.785)
		(width 0.148)
		(layer "In4.Cu")
		(net 83)
	)
	(segment
		(start 117.400001 146.2025)
		(end 117.400001 147.2775)
		(width 0.201)
		(layer "F.Cu")
		(net 84)
	)
	(segment
		(start 134.376501 165.302)
		(end 133.877001 164.8025)
		(width 0.256)
		(layer "F.Cu")
		(net 84)
	)
	(via
		(at 117.400001 147.2775)
		(size 0.45)
		(drill 0.1)
		(layers "F.Cu" "B.Cu")
		(net 84)
	)
	(via
		(at 133.877001 164.8025)
		(size 0.45)
		(drill 0.1)
		(layers "F.Cu" "B.Cu")
		(net 84)
	)
	(segment
		(start 129.148144 158.169862)
		(end 128.669859 158.648142)
		(width 0.148)
		(layer "In4.Cu")
		(net 84)
	)
	(segment
		(start 124.780751 154.759035)
		(end 124.780752 154.759034)
		(width 0.148)
		(layer "In4.Cu")
		(net 84)
	)
	(segment
		(start 130.146447 159.999999)
		(end 130.146446 160)
		(width 0.148)
		(layer "In4.Cu")
		(net 84)
	)
	(segment
		(start 122.077035 151.098751)
		(end 122.077034 151.098752)
		(width 0.148)
		(layer "In4.Cu")
		(net 84)
	)
	(segment
		(start 127.609194 157.941031)
		(end 127.609196 157.941032)
		(width 0.148)
		(layer "In4.Cu")
		(net 84)
	)
	(segment
		(start 129.501698 158.169861)
		(end 129.501698 158.169862)
		(width 0.148)
		(layer "In4.Cu")
		(net 84)
	)
	(segment
		(start 126.319701 155.341417)
		(end 126.3197 155.341418)
		(width 0.148)
		(layer "In4.Cu")
		(net 84)
	)
	(segment
		(start 126.194973 156.173257)
		(end 126.194974 156.173256)
		(width 0.148)
		(layer "In4.Cu")
		(net 84)
	)
	(segment
		(start 133.380501 162.7205)
		(end 132.861502 162.201501)
		(width 0.148)
		(layer "In4.Cu")
		(net 84)
	)
	(segment
		(start 120.662813 149.684529)
		(end 120.662812 149.68453)
		(width 0.148)
		(layer "In4.Cu")
		(net 84)
	)
	(segment
		(start 119.6 149.1)
		(end 118 149.1)
		(width 0.148)
		(layer "In4.Cu")
		(net 84)
	)
	(segment
		(start 129.730526 159.708809)
		(end 130.208809 159.230526)
		(width 0.148)
		(layer "In4.Cu")
		(net 84)
	)
	(segment
		(start 132.4 161)
		(end 131.4 160)
		(width 0.148)
		(layer "In4.Cu")
		(net 84)
	)
	(segment
		(start 122.077034 151.098752)
		(end 121.598749 151.577032)
		(width 0.148)
		(layer "In4.Cu")
		(net 84)
	)
	(segment
		(start 126.902084 156.880368)
		(end 126.902085 156.880367)
		(width 0.148)
		(layer "In4.Cu")
		(net 84)
	)
	(segment
		(start 122.659419 152.637701)
		(end 123.137699 152.159416)
		(width 0.148)
		(layer "In4.Cu")
		(net 84)
	)
	(segment
		(start 126.194972 156.526809)
		(end 126.194974 156.52681)
		(width 0.148)
		(layer "In4.Cu")
		(net 84)
	)
	(segment
		(start 128.316306 158.29459)
		(end 128.316307 158.294589)
		(width 0.148)
		(layer "In4.Cu")
		(net 84)
	)
	(segment
		(start 120.662812 149.68453)
		(end 120.184527 150.16281)
		(width 0.148)
		(layer "In4.Cu")
		(net 84)
	)
	(segment
		(start 122.784146 151.805862)
		(end 122.784145 151.805863)
		(width 0.148)
		(layer "In4.Cu")
		(net 84)
	)
	(segment
		(start 129.148145 158.169861)
		(end 129.148144 158.169862)
		(width 0.148)
		(layer "In4.Cu")
		(net 84)
	)
	(segment
		(start 124.198368 153.220084)
		(end 124.198367 153.220085)
		(width 0.148)
		(layer "In4.Cu")
		(net 84)
	)
	(segment
		(start 124.07364 154.051924)
		(end 124.073641 154.051923)
		(width 0.148)
		(layer "In4.Cu")
		(net 84)
	)
	(segment
		(start 124.780752 154.759034)
		(end 125.259032 154.280749)
		(width 0.148)
		(layer "In4.Cu")
		(net 84)
	)
	(segment
		(start 124.905478 153.927196)
		(end 124.427193 154.405476)
		(width 0.148)
		(layer "In4.Cu")
		(net 84)
	)
	(segment
		(start 124.073639 154.405476)
		(end 124.073641 154.405477)
		(width 0.148)
		(layer "In4.Cu")
		(net 84)
	)
	(segment
		(start 127.026812 156.048528)
		(end 127.026811 156.048529)
		(width 0.148)
		(layer "In4.Cu")
		(net 84)
	)
	(segment
		(start 127.733922 156.75564)
		(end 127.255637 157.23392)
		(width 0.148)
		(layer "In4.Cu")
		(net 84)
	)
	(segment
		(start 125.966143 154.634306)
		(end 125.966143 154.634307)
		(width 0.148)
		(layer "In4.Cu")
		(net 84)
	)
	(segment
		(start 128.316307 158.294589)
		(end 128.794587 157.816304)
		(width 0.148)
		(layer "In4.Cu")
		(net 84)
	)
	(segment
		(start 120.538085 150.516369)
		(end 120.538086 150.516368)
		(width 0.148)
		(layer "In4.Cu")
		(net 84)
	)
	(segment
		(start 132.861502 162.201501)
		(end 132.624002 162.201501)
		(width 0.148)
		(layer "In4.Cu")
		(net 84)
	)
	(segment
		(start 126.194974 156.173256)
		(end 126.673254 155.694971)
		(width 0.148)
		(layer "In4.Cu")
		(net 84)
	)
	(segment
		(start 121.369923 150.391641)
		(end 120.891638 150.869921)
		(width 0.148)
		(layer "In4.Cu")
		(net 84)
	)
	(segment
		(start 120.538086 150.516368)
		(end 121.016366 150.038083)
		(width 0.148)
		(layer "In4.Cu")
		(net 84)
	)
	(segment
		(start 124.905479 153.927195)
		(end 124.905478 153.927196)
		(width 0.148)
		(layer "In4.Cu")
		(net 84)
	)
	(segment
		(start 128.441033 157.462751)
		(end 127.962748 157.941031)
		(width 0.148)
		(layer "In4.Cu")
		(net 84)
	)
	(segment
		(start 125.259032 153.927195)
		(end 125.259032 153.927196)
		(width 0.148)
		(layer "In4.Cu")
		(net 84)
	)
	(segment
		(start 121.245197 151.223479)
		(end 121.723477 150.745194)
		(width 0.148)
		(layer "In4.Cu")
		(net 84)
	)
	(segment
		(start 117.400001 148.500001)
		(end 117.400001 147.2775)
		(width 0.148)
		(layer "In4.Cu")
		(net 84)
	)
	(segment
		(start 125.487861 155.819698)
		(end 125.487863 155.819699)
		(width 0.148)
		(layer "In4.Cu")
		(net 84)
	)
	(segment
		(start 123.491257 152.512973)
		(end 123.491256 152.512974)
		(width 0.148)
		(layer "In4.Cu")
		(net 84)
	)
	(segment
		(start 121.952307 151.930591)
		(end 121.952308 151.93059)
		(width 0.148)
		(layer "In4.Cu")
		(net 84)
	)
	(segment
		(start 125.61259 154.634306)
		(end 125.612589 154.634307)
		(width 0.148)
		(layer "In4.Cu")
		(net 84)
	)
	(segment
		(start 128.794587 157.46275)
		(end 128.794587 157.462751)
		(width 0.148)
		(layer "In4.Cu")
		(net 84)
	)
	(segment
		(start 129.730525 159.70881)
		(end 129.730526 159.708809)
		(width 0.148)
		(layer "In4.Cu")
		(net 84)
	)
	(segment
		(start 130.146446 160)
		(end 130.08408 160.062363)
		(width 0.148)
		(layer "In4.Cu")
		(net 84)
	)
	(segment
		(start 127.609196 157.587478)
		(end 128.087476 157.109193)
		(width 0.148)
		(layer "In4.Cu")
		(net 84)
	)
	(segment
		(start 127.026811 156.048529)
		(end 126.548526 156.526809)
		(width 0.148)
		(layer "In4.Cu")
		(net 84)
	)
	(segment
		(start 125.487863 155.466145)
		(end 125.966143 154.98786)
		(width 0.148)
		(layer "In4.Cu")
		(net 84)
	)
	(segment
		(start 120.538084 150.869921)
		(end 120.538086 150.869922)
		(width 0.148)
		(layer "In4.Cu")
		(net 84)
	)
	(segment
		(start 128.441034 157.46275)
		(end 128.441033 157.462751)
		(width 0.148)
		(layer "In4.Cu")
		(net 84)
	)
	(segment
		(start 132.624002 162.201501)
		(end 132.4 161.977499)
		(width 0.148)
		(layer "In4.Cu")
		(net 84)
	)
	(segment
		(start 119.830975 149.809257)
		(end 119.893338 149.746891)
		(width 0.148)
		(layer "In4.Cu")
		(net 84)
	)
	(segment
		(start 125.612589 154.634307)
		(end 125.134304 155.112587)
		(width 0.148)
		(layer "In4.Cu")
		(net 84)
	)
	(segment
		(start 129.023417 159.001701)
		(end 129.023418 159.0017)
		(width 0.148)
		(layer "In4.Cu")
		(net 84)
	)
	(segment
		(start 128.087476 156.755639)
		(end 128.087476 156.75564)
		(width 0.148)
		(layer "In4.Cu")
		(net 84)
	)
	(segment
		(start 124.073641 154.051923)
		(end 124.551921 153.573638)
		(width 0.148)
		(layer "In4.Cu")
		(net 84)
	)
	(segment
		(start 125.487862 155.466146)
		(end 125.487863 155.466145)
		(width 0.148)
		(layer "In4.Cu")
		(net 84)
	)
	(segment
		(start 122.430588 151.098751)
		(end 122.430588 151.098752)
		(width 0.148)
		(layer "In4.Cu")
		(net 84)
	)
	(segment
		(start 123.36653 153.344812)
		(end 123.84481 152.866527)
		(width 0.148)
		(layer "In4.Cu")
		(net 84)
	)
	(segment
		(start 123.491256 152.512974)
		(end 123.012971 152.991254)
		(width 0.148)
		(layer "In4.Cu")
		(net 84)
	)
	(segment
		(start 129.023416 159.355253)
		(end 129.023418 159.355254)
		(width 0.148)
		(layer "In4.Cu")
		(net 84)
	)
	(segment
		(start 128.316305 158.648142)
		(end 128.316307 158.648143)
		(width 0.148)
		(layer "In4.Cu")
		(net 84)
	)
	(segment
		(start 123.366528 153.698365)
		(end 123.36653 153.698366)
		(width 0.148)
		(layer "In4.Cu")
		(net 84)
	)
	(segment
		(start 126.3197 155.341418)
		(end 125.841415 155.819698)
		(width 0.148)
		(layer "In4.Cu")
		(net 84)
	)
	(segment
		(start 123.84481 152.512973)
		(end 123.84481 152.512974)
		(width 0.148)
		(layer "In4.Cu")
		(net 84)
	)
	(segment
		(start 124.551921 153.220084)
		(end 124.551921 153.220085)
		(width 0.148)
		(layer "In4.Cu")
		(net 84)
	)
	(segment
		(start 121.952306 152.284143)
		(end 121.952308 152.284144)
		(width 0.148)
		(layer "In4.Cu")
		(net 84)
	)
	(segment
		(start 119.893338 149.393337)
		(end 119.6 149.1)
		(width 0.148)
		(layer "In4.Cu")
		(net 84)
	)
	(segment
		(start 130.208809 158.876972)
		(end 130.208809 158.876973)
		(width 0.148)
		(layer "In4.Cu")
		(net 84)
	)
	(segment
		(start 121.723477 150.39164)
		(end 121.723477 150.391641)
		(width 0.148)
		(layer "In4.Cu")
		(net 84)
	)
	(segment
		(start 126.902083 157.23392)
		(end 126.902085 157.233921)
		(width 0.148)
		(layer "In4.Cu")
		(net 84)
	)
	(segment
		(start 131.4 160)
		(end 130.5 160)
		(width 0.148)
		(layer "In4.Cu")
		(net 84)
	)
	(segment
		(start 119.830973 150.16281)
		(end 119.830975 150.162811)
		(width 0.148)
		(layer "In4.Cu")
		(net 84)
	)
	(segment
		(start 126.902085 156.880367)
		(end 127.380365 156.402082)
		(width 0.148)
		(layer "In4.Cu")
		(net 84)
	)
	(segment
		(start 121.245195 151.577032)
		(end 121.245197 151.577033)
		(width 0.148)
		(layer "In4.Cu")
		(net 84)
	)
	(segment
		(start 129.730527 160.062364)
		(end 129.730526 160.062363)
		(width 0.148)
		(layer "In4.Cu")
		(net 84)
	)
	(segment
		(start 121.369924 150.39164)
		(end 121.369923 150.391641)
		(width 0.148)
		(layer "In4.Cu")
		(net 84)
	)
	(segment
		(start 133.877001 164.8025)
		(end 133.380501 164.306)
		(width 0.148)
		(layer "In4.Cu")
		(net 84)
	)
	(segment
		(start 121.016366 149.684529)
		(end 121.016366 149.68453)
		(width 0.148)
		(layer "In4.Cu")
		(net 84)
	)
	(segment
		(start 123.137699 151.805862)
		(end 123.137699 151.805863)
		(width 0.148)
		(layer "In4.Cu")
		(net 84)
	)
	(segment
		(start 122.659418 152.637702)
		(end 122.659419 152.637701)
		(width 0.148)
		(layer "In4.Cu")
		(net 84)
	)
	(segment
		(start 119.830974 149.809258)
		(end 119.830975 149.809257)
		(width 0.148)
		(layer "In4.Cu")
		(net 84)
	)
	(segment
		(start 121.952308 151.93059)
		(end 122.430588 151.452305)
		(width 0.148)
		(layer "In4.Cu")
		(net 84)
	)
	(segment
		(start 122.784145 151.805863)
		(end 122.30586 152.284143)
		(width 0.148)
		(layer "In4.Cu")
		(net 84)
	)
	(segment
		(start 129.855256 158.876972)
		(end 129.855255 158.876973)
		(width 0.148)
		(layer "In4.Cu")
		(net 84)
	)
	(segment
		(start 132.4 161.977499)
		(end 132.4 161)
		(width 0.148)
		(layer "In4.Cu")
		(net 84)
	)
	(segment
		(start 127.380365 156.048528)
		(end 127.380365 156.048529)
		(width 0.148)
		(layer "In4.Cu")
		(net 84)
	)
	(segment
		(start 126.673254 155.341417)
		(end 126.673254 155.341418)
		(width 0.148)
		(layer "In4.Cu")
		(net 84)
	)
	(segment
		(start 124.198367 153.220085)
		(end 123.720082 153.698365)
		(width 0.148)
		(layer "In4.Cu")
		(net 84)
	)
	(segment
		(start 129.855255 158.876973)
		(end 129.37697 159.355253)
		(width 0.148)
		(layer "In4.Cu")
		(net 84)
	)
	(segment
		(start 121.245196 151.22348)
		(end 121.245197 151.223479)
		(width 0.148)
		(layer "In4.Cu")
		(net 84)
	)
	(segment
		(start 127.609195 157.587479)
		(end 127.609196 157.587478)
		(width 0.148)
		(layer "In4.Cu")
		(net 84)
	)
	(segment
		(start 133.380501 164.306)
		(end 133.380501 162.7205)
		(width 0.148)
		(layer "In4.Cu")
		(net 84)
	)
	(segment
		(start 124.78075 155.112587)
		(end 124.780752 155.112588)
		(width 0.148)
		(layer "In4.Cu")
		(net 84)
	)
	(segment
		(start 123.366529 153.344813)
		(end 123.36653 153.344812)
		(width 0.148)
		(layer "In4.Cu")
		(net 84)
	)
	(segment
		(start 118 149.1)
		(end 117.400001 148.500001)
		(width 0.148)
		(layer "In4.Cu")
		(net 84)
	)
	(segment
		(start 129.023418 159.0017)
		(end 129.501698 158.523415)
		(width 0.148)
		(layer "In4.Cu")
		(net 84)
	)
	(segment
		(start 127.733923 156.755639)
		(end 127.733922 156.75564)
		(width 0.148)
		(layer "In4.Cu")
		(net 84)
	)
	(segment
		(start 122.659417 152.991254)
		(end 122.659419 152.991255)
		(width 0.148)
		(layer "In4.Cu")
		(net 84)
	)
	(segment
		(start 119.893339 149.393338)
		(end 119.893338 149.393337)
		(width 0.148)
		(layer "In4.Cu")
		(net 84)
	)
	(arc
		(start 119.830975 150.162811)
		(mid 119.757751 149.986035)
		(end 119.830974 149.809258)
		(width 0.148)
		(layer "In4.Cu")
		(net 84)
	)
	(arc
		(start 125.841415 155.819698)
		(mid 125.664638 155.892921)
		(end 125.487861 155.819698)
		(width 0.148)
		(layer "In4.Cu")
		(net 84)
	)
	(arc
		(start 125.487863 155.819699)
		(mid 125.414639 155.642923)
		(end 125.487862 155.466146)
		(width 0.148)
		(layer "In4.Cu")
		(net 84)
	)
	(arc
		(start 129.501698 158.169862)
		(mid 129.324922 158.096638)
		(end 129.148145 158.169861)
		(width 0.148)
		(layer "In4.Cu")
		(net 84)
	)
	(arc
		(start 130.5 160)
		(mid 130.323224 159.926776)
		(end 130.146447 159.999999)
		(width 0.148)
		(layer "In4.Cu")
		(net 84)
	)
	(arc
		(start 123.137699 151.805863)
		(mid 122.960923 151.732639)
		(end 122.784146 151.805862)
		(width 0.148)
		(layer "In4.Cu")
		(net 84)
	)
	(arc
		(start 129.023418 159.355254)
		(mid 128.950194 159.178478)
		(end 129.023417 159.001701)
		(width 0.148)
		(layer "In4.Cu")
		(net 84)
	)
	(arc
		(start 126.673254 155.341418)
		(mid 126.496478 155.268194)
		(end 126.319701 155.341417)
		(width 0.148)
		(layer "In4.Cu")
		(net 84)
	)
	(arc
		(start 121.952308 152.284144)
		(mid 121.879084 152.107368)
		(end 121.952307 151.930591)
		(width 0.148)
		(layer "In4.Cu")
		(net 84)
	)
	(arc
		(start 125.966143 154.634307)
		(mid 125.789367 154.561083)
		(end 125.61259 154.634306)
		(width 0.148)
		(layer "In4.Cu")
		(net 84)
	)
	(arc
		(start 119.893338 149.746891)
		(mid 119.966562 149.570115)
		(end 119.893339 149.393338)
		(width 0.148)
		(layer "In4.Cu")
		(net 84)
	)
	(arc
		(start 122.430588 151.098752)
		(mid 122.253812 151.025528)
		(end 122.077035 151.098751)
		(width 0.148)
		(layer "In4.Cu")
		(net 84)
	)
	(arc
		(start 123.137699 152.159416)
		(mid 123.210922 151.982639)
		(end 123.137699 151.805862)
		(width 0.148)
		(layer "In4.Cu")
		(net 84)
	)
	(arc
		(start 130.208809 158.876973)
		(mid 130.032033 158.803749)
		(end 129.855256 158.876972)
		(width 0.148)
		(layer "In4.Cu")
		(net 84)
	)
	(arc
		(start 128.316307 158.648143)
		(mid 128.243083 158.471367)
		(end 128.316306 158.29459)
		(width 0.148)
		(layer "In4.Cu")
		(net 84)
	)
	(arc
		(start 121.245197 151.577033)
		(mid 121.171973 151.400257)
		(end 121.245196 151.22348)
		(width 0.148)
		(layer "In4.Cu")
		(net 84)
	)
	(arc
		(start 124.551921 153.573638)
		(mid 124.625144 153.396861)
		(end 124.551921 153.220084)
		(width 0.148)
		(layer "In4.Cu")
		(net 84)
	)
	(arc
		(start 120.891638 150.869921)
		(mid 120.714861 150.943144)
		(end 120.538084 150.869921)
		(width 0.148)
		(layer "In4.Cu")
		(net 84)
	)
	(arc
		(start 121.723477 150.391641)
		(mid 121.546701 150.318417)
		(end 121.369924 150.39164)
		(width 0.148)
		(layer "In4.Cu")
		(net 84)
	)
	(arc
		(start 126.548526 156.526809)
		(mid 126.371749 156.600032)
		(end 126.194972 156.526809)
		(width 0.148)
		(layer "In4.Cu")
		(net 84)
	)
	(arc
		(start 126.673254 155.694971)
		(mid 126.746477 155.518194)
		(end 126.673254 155.341417)
		(width 0.148)
		(layer "In4.Cu")
		(net 84)
	)
	(arc
		(start 130.08408 160.062363)
		(mid 129.907304 160.135587)
		(end 129.730527 160.062364)
		(width 0.148)
		(layer "In4.Cu")
		(net 84)
	)
	(arc
		(start 128.794587 157.462751)
		(mid 128.617811 157.389527)
		(end 128.441034 157.46275)
		(width 0.148)
		(layer "In4.Cu")
		(net 84)
	)
	(arc
		(start 126.902085 157.233921)
		(mid 126.828861 157.057145)
		(end 126.902084 156.880368)
		(width 0.148)
		(layer "In4.Cu")
		(net 84)
	)
	(arc
		(start 124.551921 153.220085)
		(mid 124.375145 153.146861)
		(end 124.198368 153.220084)
		(width 0.148)
		(layer "In4.Cu")
		(net 84)
	)
	(arc
		(start 127.380365 156.402082)
		(mid 127.453588 156.225305)
		(end 127.380365 156.048528)
		(width 0.148)
		(layer "In4.Cu")
		(net 84)
	)
	(arc
		(start 124.073641 154.405477)
		(mid 124.000417 154.228701)
		(end 124.07364 154.051924)
		(width 0.148)
		(layer "In4.Cu")
		(net 84)
	)
	(arc
		(start 122.30586 152.284143)
		(mid 122.129083 152.357366)
		(end 121.952306 152.284143)
		(width 0.148)
		(layer "In4.Cu")
		(net 84)
	)
	(arc
		(start 126.194974 156.52681)
		(mid 126.12175 156.350034)
		(end 126.194973 156.173257)
		(width 0.148)
		(layer "In4.Cu")
		(net 84)
	)
	(arc
		(start 127.255637 157.23392)
		(mid 127.07886 157.307143)
		(end 126.902083 157.23392)
		(width 0.148)
		(layer "In4.Cu")
		(net 84)
	)
	(arc
		(start 127.962748 157.941031)
		(mid 127.785971 158.014254)
		(end 127.609194 157.941031)
		(width 0.148)
		(layer "In4.Cu")
		(net 84)
	)
	(arc
		(start 128.794587 157.816304)
		(mid 128.86781 157.639527)
		(end 128.794587 157.46275)
		(width 0.148)
		(layer "In4.Cu")
		(net 84)
	)
	(arc
		(start 129.730526 160.062363)
		(mid 129.657302 159.885587)
		(end 129.730525 159.70881)
		(width 0.148)
		(layer "In4.Cu")
		(net 84)
	)
	(arc
		(start 124.427193 154.405476)
		(mid 124.250416 154.478699)
		(end 124.073639 154.405476)
		(width 0.148)
		(layer "In4.Cu")
		(net 84)
	)
	(arc
		(start 121.016366 150.038083)
		(mid 121.089589 149.861306)
		(end 121.016366 149.684529)
		(width 0.148)
		(layer "In4.Cu")
		(net 84)
	)
	(arc
		(start 127.609196 157.941032)
		(mid 127.535972 157.764256)
		(end 127.609195 157.587479)
		(width 0.148)
		(layer "In4.Cu")
		(net 84)
	)
	(arc
		(start 123.36653 153.698366)
		(mid 123.293306 153.52159)
		(end 123.366529 153.344813)
		(width 0.148)
		(layer "In4.Cu")
		(net 84)
	)
	(arc
		(start 125.966143 154.98786)
		(mid 126.039366 154.811083)
		(end 125.966143 154.634306)
		(width 0.148)
		(layer "In4.Cu")
		(net 84)
	)
	(arc
		(start 122.659419 152.991255)
		(mid 122.586195 152.814479)
		(end 122.659418 152.637702)
		(width 0.148)
		(layer "In4.Cu")
		(net 84)
	)
	(arc
		(start 121.723477 150.745194)
		(mid 121.7967 150.568417)
		(end 121.723477 150.39164)
		(width 0.148)
		(layer "In4.Cu")
		(net 84)
	)
	(arc
		(start 123.720082 153.698365)
		(mid 123.543305 153.771588)
		(end 123.366528 153.698365)
		(width 0.148)
		(layer "In4.Cu")
		(net 84)
	)
	(arc
		(start 128.669859 158.648142)
		(mid 128.493082 158.721365)
		(end 128.316305 158.648142)
		(width 0.148)
		(layer "In4.Cu")
		(net 84)
	)
	(arc
		(start 124.780752 155.112588)
		(mid 124.707528 154.935812)
		(end 124.780751 154.759035)
		(width 0.148)
		(layer "In4.Cu")
		(net 84)
	)
	(arc
		(start 128.087476 156.75564)
		(mid 127.9107 156.682416)
		(end 127.733923 156.755639)
		(width 0.148)
		(layer "In4.Cu")
		(net 84)
	)
	(arc
		(start 120.538086 150.869922)
		(mid 120.464862 150.693146)
		(end 120.538085 150.516369)
		(width 0.148)
		(layer "In4.Cu")
		(net 84)
	)
	(arc
		(start 125.134304 155.112587)
		(mid 124.957527 155.18581)
		(end 124.78075 155.112587)
		(width 0.148)
		(layer "In4.Cu")
		(net 84)
	)
	(arc
		(start 127.380365 156.048529)
		(mid 127.203589 155.975305)
		(end 127.026812 156.048528)
		(width 0.148)
		(layer "In4.Cu")
		(net 84)
	)
	(arc
		(start 125.259032 154.280749)
		(mid 125.332255 154.103972)
		(end 125.259032 153.927195)
		(width 0.148)
		(layer "In4.Cu")
		(net 84)
	)
	(arc
		(start 125.259032 153.927196)
		(mid 125.082256 153.853972)
		(end 124.905479 153.927195)
		(width 0.148)
		(layer "In4.Cu")
		(net 84)
	)
	(arc
		(start 123.012971 152.991254)
		(mid 122.836194 153.064477)
		(end 122.659417 152.991254)
		(width 0.148)
		(layer "In4.Cu")
		(net 84)
	)
	(arc
		(start 123.84481 152.512974)
		(mid 123.668034 152.43975)
		(end 123.491257 152.512973)
		(width 0.148)
		(layer "In4.Cu")
		(net 84)
	)
	(arc
		(start 121.598749 151.577032)
		(mid 121.421972 151.650255)
		(end 121.245195 151.577032)
		(width 0.148)
		(layer "In4.Cu")
		(net 84)
	)
	(arc
		(start 123.84481 152.866527)
		(mid 123.918033 152.68975)
		(end 123.84481 152.512973)
		(width 0.148)
		(layer "In4.Cu")
		(net 84)
	)
	(arc
		(start 121.016366 149.68453)
		(mid 120.83959 149.611306)
		(end 120.662813 149.684529)
		(width 0.148)
		(layer "In4.Cu")
		(net 84)
	)
	(arc
		(start 129.37697 159.355253)
		(mid 129.200193 159.428476)
		(end 129.023416 159.355253)
		(width 0.148)
		(layer "In4.Cu")
		(net 84)
	)
	(arc
		(start 122.430588 151.452305)
		(mid 122.503811 151.275528)
		(end 122.430588 151.098751)
		(width 0.148)
		(layer "In4.Cu")
		(net 84)
	)
	(arc
		(start 120.184527 150.16281)
		(mid 120.00775 150.236033)
		(end 119.830973 150.16281)
		(width 0.148)
		(layer "In4.Cu")
		(net 84)
	)
	(arc
		(start 129.501698 158.523415)
		(mid 129.574921 158.346638)
		(end 129.501698 158.169861)
		(width 0.148)
		(layer "In4.Cu")
		(net 84)
	)
	(arc
		(start 128.087476 157.109193)
		(mid 128.160699 156.932416)
		(end 128.087476 156.755639)
		(width 0.148)
		(layer "In4.Cu")
		(net 84)
	)
	(arc
		(start 130.208809 159.230526)
		(mid 130.282032 159.053749)
		(end 130.208809 158.876972)
		(width 0.148)
		(layer "In4.Cu")
		(net 84)
	)
	(segment
		(start 133.376501 164.302)
		(end 132.877001 163.8025)
		(width 0.256)
		(layer "F.Cu")
		(net 85)
	)
	(segment
		(start 117.650001 138.8025)
		(end 117.650001 139.8775)
		(width 0.201)
		(layer "F.Cu")
		(net 85)
	)
	(via
		(at 117.650001 139.8775)
		(size 0.45)
		(drill 0.1)
		(layers "F.Cu" "B.Cu")
		(net 85)
	)
	(via
		(at 132.877001 163.8025)
		(size 0.45)
		(drill 0.1)
		(layers "F.Cu" "B.Cu")
		(net 85)
	)
	(segment
		(start 117.4 140.85)
		(end 117.4 141.14)
		(width 0.148)
		(layer "In4.Cu")
		(net 85)
	)
	(segment
		(start 126.790175 158.921968)
		(end 126.827833 158.959626)
		(width 0.148)
		(layer "In4.Cu")
		(net 85)
	)
	(segment
		(start 128.363497 159.863497)
		(end 128.205548 160.021445)
		(width 0.148)
		(layer "In4.Cu")
		(net 85)
	)
	(segment
		(start 126.361304 157.229511)
		(end 126.398962 157.267169)
		(width 0.148)
		(layer "In4.Cu")
		(net 85)
	)
	(segment
		(start 126.083065 158.214858)
		(end 126.120723 158.252516)
		(width 0.148)
		(layer "In4.Cu")
		(net 85)
	)
	(segment
		(start 132.877001 163.4045)
		(end 132.877001 163.8025)
		(width 0.148)
		(layer "In4.Cu")
		(net 85)
	)
	(segment
		(start 117.4 145.877501)
		(end 116.975001 146.3025)
		(width 0.148)
		(layer "In4.Cu")
		(net 85)
	)
	(segment
		(start 122.118644 152.986851)
		(end 122.156302 153.024509)
		(width 0.148)
		(layer "In4.Cu")
		(net 85)
	)
	(segment
		(start 122.547515 154.679308)
		(end 122.585173 154.716966)
		(width 0.148)
		(layer "In4.Cu")
		(net 85)
	)
	(segment
		(start 128.875 160.375)
		(end 129.25 160.75)
		(width 0.148)
		(layer "In4.Cu")
		(net 85)
	)
	(segment
		(start 129.25 160.75)
		(end 130.875 160.75)
		(width 0.148)
		(layer "In4.Cu")
		(net 85)
	)
	(segment
		(start 124.668845 156.484742)
		(end 124.984742 156.168845)
		(width 0.148)
		(layer "In4.Cu")
		(net 85)
	)
	(segment
		(start 130.875 160.75)
		(end 131.400501 161.275501)
		(width 0.148)
		(layer "In4.Cu")
		(net 85)
	)
	(segment
		(start 121.133295 153.265088)
		(end 121.170953 153.302746)
		(width 0.148)
		(layer "In4.Cu")
		(net 85)
	)
	(segment
		(start 117.650001 139.8775)
		(end 117.650001 140.599999)
		(width 0.148)
		(layer "In4.Cu")
		(net 85)
	)
	(segment
		(start 125.375955 157.191852)
		(end 125.691852 156.875955)
		(width 0.148)
		(layer "In4.Cu")
		(net 85)
	)
	(segment
		(start 132.325001 162.8525)
		(end 132.877001 163.4045)
		(width 0.148)
		(layer "In4.Cu")
		(net 85)
	)
	(segment
		(start 124.315289 156.131186)
		(end 124.631188 155.815291)
		(width 0.148)
		(layer "In4.Cu")
		(net 85)
	)
	(segment
		(start 117.5 149.75)
		(end 118.25 149.75)
		(width 0.148)
		(layer "In4.Cu")
		(net 85)
	)
	(segment
		(start 118.25 149.75)
		(end 120.426186 151.926186)
		(width 0.148)
		(layer "In4.Cu")
		(net 85)
	)
	(segment
		(start 121.840405 153.972198)
		(end 121.878063 154.009856)
		(width 0.148)
		(layer "In4.Cu")
		(net 85)
	)
	(segment
		(start 117.15 141.89)
		(end 117.725186 141.89)
		(width 0.148)
		(layer "In4.Cu")
		(net 85)
	)
	(segment
		(start 122.193959 154.009856)
		(end 122.509858 153.693961)
		(width 0.148)
		(layer "In4.Cu")
		(net 85)
	)
	(segment
		(start 128.482634 159.350841)
		(end 128.520292 159.388499)
		(width 0.148)
		(layer "In4.Cu")
		(net 85)
	)
	(segment
		(start 116.975001 149.225001)
		(end 117.5 149.75)
		(width 0.148)
		(layer "In4.Cu")
		(net 85)
	)
	(segment
		(start 132.125001 162.3025)
		(end 132.325001 162.5025)
		(width 0.148)
		(layer "In4.Cu")
		(net 85)
	)
	(segment
		(start 124.239974 155.108181)
		(end 124.277632 155.145839)
		(width 0.148)
		(layer "In4.Cu")
		(net 85)
	)
	(segment
		(start 117.650001 140.599999)
		(end 117.4 140.85)
		(width 0.148)
		(layer "In4.Cu")
		(net 85)
	)
	(segment
		(start 127.497285 159.629078)
		(end 127.534943 159.666736)
		(width 0.148)
		(layer "In4.Cu")
		(net 85)
	)
	(segment
		(start 124.668845 156.800638)
		(end 124.706503 156.838296)
		(width 0.148)
		(layer "In4.Cu")
		(net 85)
	)
	(segment
		(start 125.375955 157.507748)
		(end 125.413613 157.545406)
		(width 0.148)
		(layer "In4.Cu")
		(net 85)
	)
	(segment
		(start 131.400501 162.076)
		(end 131.627001 162.3025)
		(width 0.148)
		(layer "In4.Cu")
		(net 85)
	)
	(segment
		(start 127.068414 157.936621)
		(end 127.106072 157.974279)
		(width 0.148)
		(layer "In4.Cu")
		(net 85)
	)
	(segment
		(start 117.074814 142.89)
		(end 117.725186 142.89)
		(width 0.148)
		(layer "In4.Cu")
		(net 85)
	)
	(segment
		(start 120.426186 152.242082)
		(end 120.426185 152.242082)
		(width 0.148)
		(layer "In4.Cu")
		(net 85)
	)
	(segment
		(start 122.901069 154.716966)
		(end 123.216968 154.401071)
		(width 0.148)
		(layer "In4.Cu")
		(net 85)
	)
	(segment
		(start 121.840405 153.656302)
		(end 122.156302 153.340405)
		(width 0.148)
		(layer "In4.Cu")
		(net 85)
	)
	(segment
		(start 121.486849 153.302746)
		(end 121.802748 152.986851)
		(width 0.148)
		(layer "In4.Cu")
		(net 85)
	)
	(segment
		(start 117.074814 142.39)
		(end 117.725186 142.39)
		(width 0.148)
		(layer "In4.Cu")
		(net 85)
	)
	(segment
		(start 127.143729 158.959626)
		(end 127.459628 158.643731)
		(width 0.148)
		(layer "In4.Cu")
		(net 85)
	)
	(segment
		(start 127.775524 158.643731)
		(end 127.813182 158.681389)
		(width 0.148)
		(layer "In4.Cu")
		(net 85)
	)
	(segment
		(start 117.074814 141.89)
		(end 117.15 141.89)
		(width 0.148)
		(layer "In4.Cu")
		(net 85)
	)
	(segment
		(start 116.975001 146.3025)
		(end 116.975001 149.225001)
		(width 0.148)
		(layer "In4.Cu")
		(net 85)
	)
	(segment
		(start 122.825754 153.693961)
		(end 122.863412 153.731619)
		(width 0.148)
		(layer "In4.Cu")
		(net 85)
	)
	(segment
		(start 128.559102 160.374999)
		(end 128.559104 160.375)
		(width 0.148)
		(layer "In4.Cu")
		(net 85)
	)
	(segment
		(start 123.961735 155.777632)
		(end 124.277632 155.461735)
		(width 0.148)
		(layer "In4.Cu")
		(net 85)
	)
	(segment
		(start 121.133295 152.949192)
		(end 121.449192 152.633295)
		(width 0.148)
		(layer "In4.Cu")
		(net 85)
	)
	(segment
		(start 117.4 144.14)
		(end 117.4 145.877501)
		(width 0.148)
		(layer "In4.Cu")
		(net 85)
	)
	(segment
		(start 125.729509 157.545406)
		(end 126.045408 157.229511)
		(width 0.148)
		(layer "In4.Cu")
		(net 85)
	)
	(segment
		(start 128.362344 159.862344)
		(end 128.363497 159.863497)
		(width 0.148)
		(layer "In4.Cu")
		(net 85)
	)
	(segment
		(start 123.608179 155.424076)
		(end 123.924078 155.108181)
		(width 0.148)
		(layer "In4.Cu")
		(net 85)
	)
	(segment
		(start 126.790175 158.606072)
		(end 127.106072 158.290175)
		(width 0.148)
		(layer "In4.Cu")
		(net 85)
	)
	(segment
		(start 132.325001 162.5025)
		(end 132.325001 162.8525)
		(width 0.148)
		(layer "In4.Cu")
		(net 85)
	)
	(segment
		(start 124.947084 155.815291)
		(end 124.984742 155.852949)
		(width 0.148)
		(layer "In4.Cu")
		(net 85)
	)
	(segment
		(start 123.254625 155.386418)
		(end 123.292283 155.424076)
		(width 0.148)
		(layer "In4.Cu")
		(net 85)
	)
	(segment
		(start 117.074814 143.39)
		(end 117.725186 143.39)
		(width 0.148)
		(layer "In4.Cu")
		(net 85)
	)
	(segment
		(start 128.559104 160.375)
		(end 128.559105 160.374999)
		(width 0.148)
		(layer "In4.Cu")
		(net 85)
	)
	(segment
		(start 127.850839 159.666736)
		(end 128.166738 159.350841)
		(width 0.148)
		(layer "In4.Cu")
		(net 85)
	)
	(segment
		(start 123.532864 154.401071)
		(end 123.570522 154.438729)
		(width 0.148)
		(layer "In4.Cu")
		(net 85)
	)
	(segment
		(start 126.083065 157.898962)
		(end 126.398962 157.583065)
		(width 0.148)
		(layer "In4.Cu")
		(net 85)
	)
	(segment
		(start 127.497285 159.313182)
		(end 127.813182 158.997285)
		(width 0.148)
		(layer "In4.Cu")
		(net 85)
	)
	(segment
		(start 131.627001 162.3025)
		(end 132.125001 162.3025)
		(width 0.148)
		(layer "In4.Cu")
		(net 85)
	)
	(segment
		(start 131.400501 161.275501)
		(end 131.400501 162.076)
		(width 0.148)
		(layer "In4.Cu")
		(net 85)
	)
	(segment
		(start 126.436619 158.252516)
		(end 126.752518 157.936621)
		(width 0.148)
		(layer "In4.Cu")
		(net 85)
	)
	(segment
		(start 120.779739 152.595636)
		(end 121.095638 152.279741)
		(width 0.148)
		(layer "In4.Cu")
		(net 85)
	)
	(segment
		(start 123.254625 155.070522)
		(end 123.570522 154.754625)
		(width 0.148)
		(layer "In4.Cu")
		(net 85)
	)
	(segment
		(start 123.961735 156.093528)
		(end 123.999393 156.131186)
		(width 0.148)
		(layer "In4.Cu")
		(net 85)
	)
	(segment
		(start 117.074814 143.89)
		(end 117.15 143.89)
		(width 0.148)
		(layer "In4.Cu")
		(net 85)
	)
	(segment
		(start 121.411534 152.279741)
		(end 121.449192 152.317399)
		(width 0.148)
		(layer "In4.Cu")
		(net 85)
	)
	(segment
		(start 117.15 141.39)
		(end 117.074814 141.39)
		(width 0.148)
		(layer "In4.Cu")
		(net 85)
	)
	(segment
		(start 128.205548 160.337341)
		(end 128.243206 160.374999)
		(width 0.148)
		(layer "In4.Cu")
		(net 85)
	)
	(segment
		(start 120.426185 152.557978)
		(end 120.463843 152.595636)
		(width 0.148)
		(layer "In4.Cu")
		(net 85)
	)
	(segment
		(start 125.022399 156.838296)
		(end 125.338298 156.522401)
		(width 0.148)
		(layer "In4.Cu")
		(net 85)
	)
	(segment
		(start 128.520292 159.704395)
		(end 128.362344 159.862344)
		(width 0.148)
		(layer "In4.Cu")
		(net 85)
	)
	(segment
		(start 122.547515 154.363412)
		(end 122.863412 154.047515)
		(width 0.148)
		(layer "In4.Cu")
		(net 85)
	)
	(segment
		(start 125.654194 156.522401)
		(end 125.691852 156.560059)
		(width 0.148)
		(layer "In4.Cu")
		(net 85)
	)
	(arc
		(start 121.133295 152.949192)
		(mid 121.067871 153.10714)
		(end 121.133295 153.265088)
		(width 0.148)
		(layer "In4.Cu")
		(net 85)
	)
	(arc
		(start 116.824814 141.64)
		(mid 116.898037 141.816777)
		(end 117.074814 141.89)
		(width 0.148)
		(layer "In4.Cu")
		(net 85)
	)
	(arc
		(start 120.463843 152.595636)
		(mid 120.621791 152.66106)
		(end 120.779739 152.595636)
		(width 0.148)
		(layer "In4.Cu")
		(net 85)
	)
	(arc
		(start 128.520292 159.388499)
		(mid 128.585716 159.546447)
		(end 128.520292 159.704395)
		(width 0.148)
		(layer "In4.Cu")
		(net 85)
	)
	(arc
		(start 123.924078 155.108181)
		(mid 124.082026 155.042757)
		(end 124.239974 155.108181)
		(width 0.148)
		(layer "In4.Cu")
		(net 85)
	)
	(arc
		(start 116.824814 142.64)
		(mid 116.898037 142.816777)
		(end 117.074814 142.89)
		(width 0.148)
		(layer "In4.Cu")
		(net 85)
	)
	(arc
		(start 117.4 141.14)
		(mid 117.326777 141.316777)
		(end 117.15 141.39)
		(width 0.148)
		(layer "In4.Cu")
		(net 85)
	)
	(arc
		(start 124.706503 156.838296)
		(mid 124.864451 156.90372)
		(end 125.022399 156.838296)
		(width 0.148)
		(layer "In4.Cu")
		(net 85)
	)
	(arc
		(start 117.074814 142.39)
		(mid 116.898037 142.463223)
		(end 116.824814 142.64)
		(width 0.148)
		(layer "In4.Cu")
		(net 85)
	)
	(arc
		(start 121.449192 152.317399)
		(mid 121.514616 152.475347)
		(end 121.449192 152.633295)
		(width 0.148)
		(layer "In4.Cu")
		(net 85)
	)
	(arc
		(start 124.277632 155.145839)
		(mid 124.343056 155.303787)
		(end 124.277632 155.461735)
		(width 0.148)
		(layer "In4.Cu")
		(net 85)
	)
	(arc
		(start 126.083065 157.898962)
		(mid 126.017641 158.05691)
		(end 126.083065 158.214858)
		(width 0.148)
		(layer "In4.Cu")
		(net 85)
	)
	(arc
		(start 125.375955 157.191852)
		(mid 125.310531 157.3498)
		(end 125.375955 157.507748)
		(width 0.148)
		(layer "In4.Cu")
		(net 85)
	)
	(arc
		(start 128.166738 159.350841)
		(mid 128.324686 159.285417)
		(end 128.482634 159.350841)
		(width 0.148)
		(layer "In4.Cu")
		(net 85)
	)
	(arc
		(start 127.497285 159.313182)
		(mid 127.431861 159.47113)
		(end 127.497285 159.629078)
		(width 0.148)
		(layer "In4.Cu")
		(net 85)
	)
	(arc
		(start 117.975186 142.14)
		(mid 117.901963 142.316777)
		(end 117.725186 142.39)
		(width 0.148)
		(layer "In4.Cu")
		(net 85)
	)
	(arc
		(start 127.534943 159.666736)
		(mid 127.692891 159.73216)
		(end 127.850839 159.666736)
		(width 0.148)
		(layer "In4.Cu")
		(net 85)
	)
	(arc
		(start 127.106072 157.974279)
		(mid 127.171496 158.132227)
		(end 127.106072 158.290175)
		(width 0.148)
		(layer "In4.Cu")
		(net 85)
	)
	(arc
		(start 127.459628 158.643731)
		(mid 127.617576 158.578307)
		(end 127.775524 158.643731)
		(width 0.148)
		(layer "In4.Cu")
		(net 85)
	)
	(arc
		(start 121.170953 153.302746)
		(mid 121.328901 153.36817)
		(end 121.486849 153.302746)
		(width 0.148)
		(layer "In4.Cu")
		(net 85)
	)
	(arc
		(start 117.975186 143.14)
		(mid 117.901963 143.316777)
		(end 117.725186 143.39)
		(width 0.148)
		(layer "In4.Cu")
		(net 85)
	)
	(arc
		(start 124.984742 155.852949)
		(mid 125.050166 156.010897)
		(end 124.984742 156.168845)
		(width 0.148)
		(layer "In4.Cu")
		(net 85)
	)
	(arc
		(start 117.725186 141.89)
		(mid 117.901963 141.963223)
		(end 117.975186 142.14)
		(width 0.148)
		(layer "In4.Cu")
		(net 85)
	)
	(arc
		(start 128.559105 160.374999)
		(mid 128.717052 160.309575)
		(end 128.875 160.375)
		(width 0.148)
		(layer "In4.Cu")
		(net 85)
	)
	(arc
		(start 122.509858 153.693961)
		(mid 122.667806 153.628537)
		(end 122.825754 153.693961)
		(width 0.148)
		(layer "In4.Cu")
		(net 85)
	)
	(arc
		(start 123.216968 154.401071)
		(mid 123.374916 154.335647)
		(end 123.532864 154.401071)
		(width 0.148)
		(layer "In4.Cu")
		(net 85)
	)
	(arc
		(start 117.074814 143.39)
		(mid 116.898037 143.463223)
		(end 116.824814 143.64)
		(width 0.148)
		(layer "In4.Cu")
		(net 85)
	)
	(arc
		(start 117.074814 141.39)
		(mid 116.898037 141.463223)
		(end 116.824814 141.64)
		(width 0.148)
		(layer "In4.Cu")
		(net 85)
	)
	(arc
		(start 126.120723 158.252516)
		(mid 126.278671 158.31794)
		(end 126.436619 158.252516)
		(width 0.148)
		(layer "In4.Cu")
		(net 85)
	)
	(arc
		(start 126.790175 158.606072)
		(mid 126.724751 158.76402)
		(end 126.790175 158.921968)
		(width 0.148)
		(layer "In4.Cu")
		(net 85)
	)
	(arc
		(start 121.802748 152.986851)
		(mid 121.960696 152.921427)
		(end 122.118644 152.986851)
		(width 0.148)
		(layer "In4.Cu")
		(net 85)
	)
	(arc
		(start 126.398962 157.267169)
		(mid 126.464386 157.425117)
		(end 126.398962 157.583065)
		(width 0.148)
		(layer "In4.Cu")
		(net 85)
	)
	(arc
		(start 127.813182 158.681389)
		(mid 127.878606 158.839337)
		(end 127.813182 158.997285)
		(width 0.148)
		(layer "In4.Cu")
		(net 85)
	)
	(arc
		(start 117.725186 142.89)
		(mid 117.901963 142.963223)
		(end 117.975186 143.14)
		(width 0.148)
		(layer "In4.Cu")
		(net 85)
	)
	(arc
		(start 125.338298 156.522401)
		(mid 125.496246 156.456977)
		(end 125.654194 156.522401)
		(width 0.148)
		(layer "In4.Cu")
		(net 85)
	)
	(arc
		(start 117.15 143.89)
		(mid 117.326777 143.963223)
		(end 117.4 144.14)
		(width 0.148)
		(layer "In4.Cu")
		(net 85)
	)
	(arc
		(start 123.254625 155.070522)
		(mid 123.189201 155.22847)
		(end 123.254625 155.386418)
		(width 0.148)
		(layer "In4.Cu")
		(net 85)
	)
	(arc
		(start 120.426185 152.242082)
		(mid 120.360761 152.40003)
		(end 120.426185 152.557978)
		(width 0.148)
		(layer "In4.Cu")
		(net 85)
	)
	(arc
		(start 121.095638 152.279741)
		(mid 121.253586 152.214317)
		(end 121.411534 152.279741)
		(width 0.148)
		(layer "In4.Cu")
		(net 85)
	)
	(arc
		(start 122.585173 154.716966)
		(mid 122.743121 154.78239)
		(end 122.901069 154.716966)
		(width 0.148)
		(layer "In4.Cu")
		(net 85)
	)
	(arc
		(start 123.570522 154.438729)
		(mid 123.635946 154.596677)
		(end 123.570522 154.754625)
		(width 0.148)
		(layer "In4.Cu")
		(net 85)
	)
	(arc
		(start 126.752518 157.936621)
		(mid 126.910466 157.871197)
		(end 127.068414 157.936621)
		(width 0.148)
		(layer "In4.Cu")
		(net 85)
	)
	(arc
		(start 120.426186 151.926186)
		(mid 120.49161 152.084134)
		(end 120.426186 152.242082)
		(width 0.148)
		(layer "In4.Cu")
		(net 85)
	)
	(arc
		(start 126.827833 158.959626)
		(mid 126.985781 159.02505)
		(end 127.143729 158.959626)
		(width 0.148)
		(layer "In4.Cu")
		(net 85)
	)
	(arc
		(start 128.205548 160.021445)
		(mid 128.140124 160.179393)
		(end 128.205548 160.337341)
		(width 0.148)
		(layer "In4.Cu")
		(net 85)
	)
	(arc
		(start 122.156302 153.024509)
		(mid 122.221726 153.182457)
		(end 122.156302 153.340405)
		(width 0.148)
		(layer "In4.Cu")
		(net 85)
	)
	(arc
		(start 121.878063 154.009856)
		(mid 122.036011 154.07528)
		(end 122.193959 154.009856)
		(width 0.148)
		(layer "In4.Cu")
		(net 85)
	)
	(arc
		(start 126.045408 157.229511)
		(mid 126.203356 157.164087)
		(end 126.361304 157.229511)
		(width 0.148)
		(layer "In4.Cu")
		(net 85)
	)
	(arc
		(start 124.631188 155.815291)
		(mid 124.789136 155.749867)
		(end 124.947084 155.815291)
		(width 0.148)
		(layer "In4.Cu")
		(net 85)
	)
	(arc
		(start 123.292283 155.424076)
		(mid 123.450231 155.4895)
		(end 123.608179 155.424076)
		(width 0.148)
		(layer "In4.Cu")
		(net 85)
	)
	(arc
		(start 123.999393 156.131186)
		(mid 124.157341 156.19661)
		(end 124.315289 156.131186)
		(width 0.148)
		(layer "In4.Cu")
		(net 85)
	)
	(arc
		(start 116.824814 143.64)
		(mid 116.898037 143.816777)
		(end 117.074814 143.89)
		(width 0.148)
		(layer "In4.Cu")
		(net 85)
	)
	(arc
		(start 125.413613 157.545406)
		(mid 125.571561 157.61083)
		(end 125.729509 157.545406)
		(width 0.148)
		(layer "In4.Cu")
		(net 85)
	)
	(arc
		(start 125.691852 156.560059)
		(mid 125.757276 156.718007)
		(end 125.691852 156.875955)
		(width 0.148)
		(layer "In4.Cu")
		(net 85)
	)
	(arc
		(start 128.243206 160.374999)
		(mid 128.401154 160.440423)
		(end 128.559102 160.374999)
		(width 0.148)
		(layer "In4.Cu")
		(net 85)
	)
	(arc
		(start 121.840405 153.656302)
		(mid 121.774981 153.81425)
		(end 121.840405 153.972198)
		(width 0.148)
		(layer "In4.Cu")
		(net 85)
	)
	(arc
		(start 122.863412 153.731619)
		(mid 122.928836 153.889567)
		(end 122.863412 154.047515)
		(width 0.148)
		(layer "In4.Cu")
		(net 85)
	)
	(arc
		(start 122.547515 154.363412)
		(mid 122.482091 154.52136)
		(end 122.547515 154.679308)
		(width 0.148)
		(layer "In4.Cu")
		(net 85)
	)
	(arc
		(start 124.668845 156.484742)
		(mid 124.603421 156.64269)
		(end 124.668845 156.800638)
		(width 0.148)
		(layer "In4.Cu")
		(net 85)
	)
	(arc
		(start 123.961735 155.777632)
		(mid 123.896311 155.93558)
		(end 123.961735 156.093528)
		(width 0.148)
		(layer "In4.Cu")
		(net 85)
	)
	(segment
		(start 182.637107 187.881607)
		(end 182.637107 186.375)
		(width 0.2)
		(layer "F.Cu")
		(net 86)
	)
	(segment
		(start 182.592606 187.926107)
		(end 182.637107 187.881607)
		(width 0.2)
		(layer "F.Cu")
		(net 86)
	)
	(segment
		(start 189.396 189.099)
		(end 188.973 189.099)
		(width 0.1)
		(layer "F.Cu")
		(net 86)
	)
	(via
		(at 182.592606 187.926107)
		(size 0.45)
		(drill 0.1)
		(layers "F.Cu" "B.Cu")
		(net 86)
	)
	(via
		(at 188.973 189.099)
		(size 0.45)
		(drill 0.1)
		(layers "F.Cu" "B.Cu")
		(net 86)
	)
	(segment
		(start 188.441422 190.6)
		(end 188.798 190.243422)
		(width 0.1)
		(layer "In4.Cu")
		(net 86)
	)
	(segment
		(start 182.784357 188.117858)
		(end 182.784357 188.525779)
		(width 0.1)
		(layer "In4.Cu")
		(net 86)
	)
	(segment
		(start 188.798 189.274)
		(end 188.973 189.099)
		(width 0.1)
		(layer "In4.Cu")
		(net 86)
	)
	(segment
		(start 184.858578 190.6)
		(end 188.441422 190.6)
		(width 0.1)
		(layer "In4.Cu")
		(net 86)
	)
	(segment
		(start 182.784357 188.525779)
		(end 184.858578 190.6)
		(width 0.1)
		(layer "In4.Cu")
		(net 86)
	)
	(segment
		(start 182.592606 187.926107)
		(end 182.784357 188.117858)
		(width 0.1)
		(layer "In4.Cu")
		(net 86)
	)
	(segment
		(start 188.798 190.243422)
		(end 188.798 189.274)
		(width 0.1)
		(layer "In4.Cu")
		(net 86)
	)
	(segment
		(start 135.376502 165.302)
		(end 134.877001 164.8025)
		(width 0.256)
		(layer "F.Cu")
		(net 87)
	)
	(segment
		(start 118.400001 146.2025)
		(end 118.400001 147.2775)
		(width 0.201)
		(layer "F.Cu")
		(net 87)
	)
	(via
		(at 134.877001 164.8025)
		(size 0.45)
		(drill 0.1)
		(layers "F.Cu" "B.Cu")
		(net 87)
	)
	(via
		(at 118.400001 147.2775)
		(size 0.45)
		(drill 0.1)
		(layers "F.Cu" "B.Cu")
		(net 87)
	)
	(segment
		(start 133.78088 158.542349)
		(end 133.292347 159.030878)
		(width 0.148)
		(layer "In4.Cu")
		(net 87)
	)
	(segment
		(start 126.70977 151.471239)
		(end 126.221237 151.959768)
		(width 0.148)
		(layer "In4.Cu")
		(net 87)
	)
	(segment
		(start 132.231683 158.323768)
		(end 132.231682 158.323767)
		(width 0.148)
		(layer "In4.Cu")
		(net 87)
	)
	(segment
		(start 128.831103 153.592572)
		(end 128.34257 154.081101)
		(width 0.148)
		(layer "In4.Cu")
		(net 87)
	)
	(segment
		(start 125.867684 151.959769)
		(end 125.867683 151.959768)
		(width 0.148)
		(layer "In4.Cu")
		(net 87)
	)
	(segment
		(start 124.234881 148.642796)
		(end 124.23488 148.642795)
		(width 0.148)
		(layer "In4.Cu")
		(net 87)
	)
	(segment
		(start 128.696127 154.434658)
		(end 129.184657 153.946126)
		(width 0.148)
		(layer "In4.Cu")
		(net 87)
	)
	(segment
		(start 130.952436 155.713905)
		(end 130.463903 156.202434)
		(width 0.148)
		(layer "In4.Cu")
		(net 87)
	)
	(segment
		(start 129.538214 154.299683)
		(end 129.049681 154.788212)
		(width 0.148)
		(layer "In4.Cu")
		(net 87)
	)
	(segment
		(start 123.746349 149.484882)
		(end 123.74635 149.484881)
		(width 0.148)
		(layer "In4.Cu")
		(net 87)
	)
	(segment
		(start 128.477547 152.885462)
		(end 128.477546 152.885461)
		(width 0.148)
		(layer "In4.Cu")
		(net 87)
	)
	(segment
		(start 125.867682 151.606215)
		(end 125.867683 151.606214)
		(width 0.148)
		(layer "In4.Cu")
		(net 87)
	)
	(segment
		(start 129.403238 155.141769)
		(end 129.891768 154.653237)
		(width 0.148)
		(layer "In4.Cu")
		(net 87)
	)
	(segment
		(start 128.123992 152.885461)
		(end 127.635459 153.37399)
		(width 0.148)
		(layer "In4.Cu")
		(net 87)
	)
	(segment
		(start 134.066948 159.6705)
		(end 134.066947 159.670501)
		(width 0.148)
		(layer "In4.Cu")
		(net 87)
	)
	(segment
		(start 132.938793 158.677324)
		(end 133.427323 158.188792)
		(width 0.148)
		(layer "In4.Cu")
		(net 87)
	)
	(segment
		(start 132.720213 157.128128)
		(end 132.720212 157.128127)
		(width 0.148)
		(layer "In4.Cu")
		(net 87)
	)
	(segment
		(start 125.160572 150.899103)
		(end 125.649102 150.410571)
		(width 0.148)
		(layer "In4.Cu")
		(net 87)
	)
	(segment
		(start 133.645904 159.384436)
		(end 134.134434 158.895903)
		(width 0.148)
		(layer "In4.Cu")
		(net 87)
	)
	(segment
		(start 130.817459 156.555992)
		(end 130.81746 156.555991)
		(width 0.148)
		(layer "In4.Cu")
		(net 87)
	)
	(segment
		(start 123.881327 148.642794)
		(end 123.881326 148.642795)
		(width 0.148)
		(layer "In4.Cu")
		(net 87)
	)
	(segment
		(start 128.123993 152.88546)
		(end 128.123992 152.885461)
		(width 0.148)
		(layer "In4.Cu")
		(net 87)
	)
	(segment
		(start 127.416881 152.17835)
		(end 126.928348 152.666879)
		(width 0.148)
		(layer "In4.Cu")
		(net 87)
	)
	(segment
		(start 127.281904 153.020437)
		(end 127.281905 153.020436)
		(width 0.148)
		(layer "In4.Cu")
		(net 87)
	)
	(segment
		(start 134.134435 158.54235)
		(end 134.134434 158.542349)
		(width 0.148)
		(layer "In4.Cu")
		(net 87)
	)
	(segment
		(start 119.122501 148)
		(end 118.400001 147.2775)
		(width 0.148)
		(layer "In4.Cu")
		(net 87)
	)
	(segment
		(start 130.817461 156.909546)
		(end 130.81746 156.909545)
		(width 0.148)
		(layer "In4.Cu")
		(net 87)
	)
	(segment
		(start 127.281906 153.373991)
		(end 127.281905 153.37399)
		(width 0.148)
		(layer "In4.Cu")
		(net 87)
	)
	(segment
		(start 132.938792 158.677325)
		(end 132.938793 158.677324)
		(width 0.148)
		(layer "In4.Cu")
		(net 87)
	)
	(segment
		(start 130.81746 156.555991)
		(end 131.30599 156.067459)
		(width 0.148)
		(layer "In4.Cu")
		(net 87)
	)
	(segment
		(start 130.952437 155.713904)
		(end 130.952436 155.713905)
		(width 0.148)
		(layer "In4.Cu")
		(net 87)
	)
	(segment
		(start 124.453462 150.545547)
		(end 124.453461 150.545546)
		(width 0.148)
		(layer "In4.Cu")
		(net 87)
	)
	(segment
		(start 123.74635 149.484881)
		(end 124.23488 148.996349)
		(width 0.148)
		(layer "In4.Cu")
		(net 87)
	)
	(segment
		(start 127.989015 153.727548)
		(end 127.989016 153.727547)
		(width 0.148)
		(layer "In4.Cu")
		(net 87)
	)
	(segment
		(start 129.538215 154.299682)
		(end 129.538214 154.299683)
		(width 0.148)
		(layer "In4.Cu")
		(net 87)
	)
	(segment
		(start 135.380501 162.496)
		(end 135.190501 162.306)
		(width 0.148)
		(layer "In4.Cu")
		(net 87)
	)
	(segment
		(start 126.356214 150.764129)
		(end 126.356213 150.764128)
		(width 0.148)
		(layer "In4.Cu")
		(net 87)
	)
	(segment
		(start 126.002659 150.764128)
		(end 125.514126 151.252657)
		(width 0.148)
		(layer "In4.Cu")
		(net 87)
	)
	(segment
		(start 133.073769 157.835238)
		(end 132.585236 158.323767)
		(width 0.148)
		(layer "In4.Cu")
		(net 87)
	)
	(segment
		(start 127.063325 151.47124)
		(end 127.063324 151.471239)
		(width 0.148)
		(layer "In4.Cu")
		(net 87)
	)
	(segment
		(start 131.524571 157.263102)
		(end 132.013101 156.77457)
		(width 0.148)
		(layer "In4.Cu")
		(net 87)
	)
	(segment
		(start 127.770436 152.178351)
		(end 127.770435 152.17835)
		(width 0.148)
		(layer "In4.Cu")
		(net 87)
	)
	(segment
		(start 126.709771 151.471238)
		(end 126.70977 151.471239)
		(width 0.148)
		(layer "In4.Cu")
		(net 87)
	)
	(segment
		(start 125.295549 150.057016)
		(end 125.295548 150.057017)
		(width 0.148)
		(layer "In4.Cu")
		(net 87)
	)
	(segment
		(start 130.245326 155.006793)
		(end 130.245325 155.006794)
		(width 0.148)
		(layer "In4.Cu")
		(net 87)
	)
	(segment
		(start 131.524572 157.616657)
		(end 131.524571 157.616656)
		(width 0.148)
		(layer "In4.Cu")
		(net 87)
	)
	(segment
		(start 126.574793 152.313326)
		(end 126.574794 152.313325)
		(width 0.148)
		(layer "In4.Cu")
		(net 87)
	)
	(segment
		(start 129.403239 155.495324)
		(end 129.403238 155.495323)
		(width 0.148)
		(layer "In4.Cu")
		(net 87)
	)
	(segment
		(start 124.453461 150.191992)
		(end 124.941991 149.70346)
		(width 0.148)
		(layer "In4.Cu")
		(net 87)
	)
	(segment
		(start 133.645903 159.384437)
		(end 133.645904 159.384436)
		(width 0.148)
		(layer "In4.Cu")
		(net 87)
	)
	(segment
		(start 132.366658 157.128127)
		(end 131.878125 157.616656)
		(width 0.148)
		(layer "In4.Cu")
		(net 87)
	)
	(segment
		(start 123.881326 148.642795)
		(end 123.813836 148.710284)
		(width 0.148)
		(layer "In4.Cu")
		(net 87)
	)
	(segment
		(start 131.305991 155.713906)
		(end 131.30599 155.713905)
		(width 0.148)
		(layer "In4.Cu")
		(net 87)
	)
	(segment
		(start 124.45346 150.191993)
		(end 124.453461 150.191992)
		(width 0.148)
		(layer "In4.Cu")
		(net 87)
	)
	(segment
		(start 132.013102 156.421017)
		(end 132.013101 156.421016)
		(width 0.148)
		(layer "In4.Cu")
		(net 87)
	)
	(segment
		(start 134.066947 159.670501)
		(end 133.999456 159.737989)
		(width 0.148)
		(layer "In4.Cu")
		(net 87)
	)
	(segment
		(start 127.989017 154.081102)
		(end 127.989016 154.081101)
		(width 0.148)
		(layer "In4.Cu")
		(net 87)
	)
	(segment
		(start 124.588437 149.349906)
		(end 124.099904 149.838435)
		(width 0.148)
		(layer "In4.Cu")
		(net 87)
	)
	(segment
		(start 130.110349 155.84888)
		(end 130.598879 155.360348)
		(width 0.148)
		(layer "In4.Cu")
		(net 87)
	)
	(segment
		(start 126.574794 152.313325)
		(end 127.063324 151.824793)
		(width 0.148)
		(layer "In4.Cu")
		(net 87)
	)
	(segment
		(start 131.659547 156.421016)
		(end 131.171014 156.909545)
		(width 0.148)
		(layer "In4.Cu")
		(net 87)
	)
	(segment
		(start 126.00266 150.764127)
		(end 126.002659 150.764128)
		(width 0.148)
		(layer "In4.Cu")
		(net 87)
	)
	(segment
		(start 124.941992 149.349907)
		(end 124.941991 149.349906)
		(width 0.148)
		(layer "In4.Cu")
		(net 87)
	)
	(segment
		(start 123.746351 149.838436)
		(end 123.74635 149.838435)
		(width 0.148)
		(layer "In4.Cu")
		(net 87)
	)
	(segment
		(start 125.295548 150.057017)
		(end 124.807015 150.545546)
		(width 0.148)
		(layer "In4.Cu")
		(net 87)
	)
	(segment
		(start 132.366659 157.128126)
		(end 132.366658 157.128127)
		(width 0.148)
		(layer "In4.Cu")
		(net 87)
	)
	(segment
		(start 127.416882 152.178349)
		(end 127.416881 152.17835)
		(width 0.148)
		(layer "In4.Cu")
		(net 87)
	)
	(segment
		(start 129.891769 154.299684)
		(end 129.891768 154.299683)
		(width 0.148)
		(layer "In4.Cu")
		(net 87)
	)
	(segment
		(start 130.59888 155.006795)
		(end 130.598879 155.006794)
		(width 0.148)
		(layer "In4.Cu")
		(net 87)
	)
	(segment
		(start 131.52457 157.263103)
		(end 131.524571 157.263102)
		(width 0.148)
		(layer "In4.Cu")
		(net 87)
	)
	(segment
		(start 132.231681 157.970214)
		(end 132.231682 157.970213)
		(width 0.148)
		(layer "In4.Cu")
		(net 87)
	)
	(segment
		(start 132.938794 159.030879)
		(end 132.938793 159.030878)
		(width 0.148)
		(layer "In4.Cu")
		(net 87)
	)
	(segment
		(start 130.245325 155.006794)
		(end 129.756792 155.495323)
		(width 0.148)
		(layer "In4.Cu")
		(net 87)
	)
	(segment
		(start 123.460283 148.710284)
		(end 122.75 148)
		(width 0.148)
		(layer "In4.Cu")
		(net 87)
	)
	(segment
		(start 128.696126 154.434659)
		(end 128.696127 154.434658)
		(width 0.148)
		(layer "In4.Cu")
		(net 87)
	)
	(segment
		(start 130.110348 155.848881)
		(end 130.110349 155.84888)
		(width 0.148)
		(layer "In4.Cu")
		(net 87)
	)
	(segment
		(start 126.574795 152.66688)
		(end 126.574794 152.666879)
		(width 0.148)
		(layer "In4.Cu")
		(net 87)
	)
	(segment
		(start 129.184658 153.592573)
		(end 129.184657 153.592572)
		(width 0.148)
		(layer "In4.Cu")
		(net 87)
	)
	(segment
		(start 128.831104 153.592571)
		(end 128.831103 153.592572)
		(width 0.148)
		(layer "In4.Cu")
		(net 87)
	)
	(segment
		(start 128.696128 154.788213)
		(end 128.696127 154.788212)
		(width 0.148)
		(layer "In4.Cu")
		(net 87)
	)
	(segment
		(start 135.380501 164.299)
		(end 135.380501 162.496)
		(width 0.148)
		(layer "In4.Cu")
		(net 87)
	)
	(segment
		(start 134.420501 162.036)
		(end 134.420501 159.670501)
		(width 0.148)
		(layer "In4.Cu")
		(net 87)
	)
	(segment
		(start 124.588438 149.349905)
		(end 124.588437 149.349906)
		(width 0.148)
		(layer "In4.Cu")
		(net 87)
	)
	(segment
		(start 125.160573 151.252658)
		(end 125.160572 151.252657)
		(width 0.148)
		(layer "In4.Cu")
		(net 87)
	)
	(segment
		(start 125.160571 150.899104)
		(end 125.160572 150.899103)
		(width 0.148)
		(layer "In4.Cu")
		(net 87)
	)
	(segment
		(start 132.231682 157.970213)
		(end 132.720212 157.481681)
		(width 0.148)
		(layer "In4.Cu")
		(net 87)
	)
	(segment
		(start 133.07377 157.835237)
		(end 133.073769 157.835238)
		(width 0.148)
		(layer "In4.Cu")
		(net 87)
	)
	(segment
		(start 127.281905 153.020436)
		(end 127.770435 152.531904)
		(width 0.148)
		(layer "In4.Cu")
		(net 87)
	)
	(segment
		(start 134.690501 162.306)
		(end 134.420501 162.036)
		(width 0.148)
		(layer "In4.Cu")
		(net 87)
	)
	(segment
		(start 123.460283 148.710283)
		(end 123.460283 148.710284)
		(width 0.148)
		(layer "In4.Cu")
		(net 87)
	)
	(segment
		(start 133.645903 159.737988)
		(end 133.645904 159.73799)
		(width 0.148)
		(layer "In4.Cu")
		(net 87)
	)
	(segment
		(start 127.989016 153.727547)
		(end 128.477546 153.239015)
		(width 0.148)
		(layer "In4.Cu")
		(net 87)
	)
	(segment
		(start 130.11035 156.202435)
		(end 130.110349 156.202434)
		(width 0.148)
		(layer "In4.Cu")
		(net 87)
	)
	(segment
		(start 131.659548 156.421015)
		(end 131.659547 156.421016)
		(width 0.148)
		(layer "In4.Cu")
		(net 87)
	)
	(segment
		(start 133.427324 157.835239)
		(end 133.427323 157.835238)
		(width 0.148)
		(layer "In4.Cu")
		(net 87)
	)
	(segment
		(start 125.649103 150.057018)
		(end 125.649102 150.057017)
		(width 0.148)
		(layer "In4.Cu")
		(net 87)
	)
	(segment
		(start 125.867683 151.606214)
		(end 126.356213 151.117682)
		(width 0.148)
		(layer "In4.Cu")
		(net 87)
	)
	(segment
		(start 129.403237 155.14177)
		(end 129.403238 155.141769)
		(width 0.148)
		(layer "In4.Cu")
		(net 87)
	)
	(segment
		(start 134.877001 164.8025)
		(end 135.380501 164.299)
		(width 0.148)
		(layer "In4.Cu")
		(net 87)
	)
	(segment
		(start 133.780881 158.542348)
		(end 133.78088 158.542349)
		(width 0.148)
		(layer "In4.Cu")
		(net 87)
	)
	(segment
		(start 122.75 148)
		(end 119.122501 148)
		(width 0.148)
		(layer "In4.Cu")
		(net 87)
	)
	(segment
		(start 135.190501 162.306)
		(end 134.690501 162.306)
		(width 0.148)
		(layer "In4.Cu")
		(net 87)
	)
	(arc
		(start 124.099904 149.838435)
		(mid 123.923128 149.911659)
		(end 123.746351 149.838436)
		(width 0.148)
		(layer "In4.Cu")
		(net 87)
	)
	(arc
		(start 126.928348 152.666879)
		(mid 126.751572 152.740103)
		(end 126.574795 152.66688)
		(width 0.148)
		(layer "In4.Cu")
		(net 87)
	)
	(arc
		(start 130.463903 156.202434)
		(mid 130.287127 156.275658)
		(end 130.11035 156.202435)
		(width 0.148)
		(layer "In4.Cu")
		(net 87)
	)
	(arc
		(start 124.453461 150.545546)
		(mid 124.380237 150.36877)
		(end 124.45346 150.191993)
		(width 0.148)
		(layer "In4.Cu")
		(net 87)
	)
	(arc
		(start 129.049681 154.788212)
		(mid 128.872905 154.861436)
		(end 128.696128 154.788213)
		(width 0.148)
		(layer "In4.Cu")
		(net 87)
	)
	(arc
		(start 131.524571 157.616656)
		(mid 131.451347 157.43988)
		(end 131.52457 157.263103)
		(width 0.148)
		(layer "In4.Cu")
		(net 87)
	)
	(arc
		(start 128.477546 153.239015)
		(mid 128.55077 153.062239)
		(end 128.477547 152.885462)
		(width 0.148)
		(layer "In4.Cu")
		(net 87)
	)
	(arc
		(start 133.999456 159.737989)
		(mid 133.822679 159.811212)
		(end 133.645903 159.737988)
		(width 0.148)
		(layer "In4.Cu")
		(net 87)
	)
	(arc
		(start 133.427323 157.835238)
		(mid 133.250547 157.762014)
		(end 133.07377 157.835237)
		(width 0.148)
		(layer "In4.Cu")
		(net 87)
	)
	(arc
		(start 131.30599 156.067459)
		(mid 131.379214 155.890683)
		(end 131.305991 155.713906)
		(width 0.148)
		(layer "In4.Cu")
		(net 87)
	)
	(arc
		(start 123.813836 148.710284)
		(mid 123.637059 148.783507)
		(end 123.460283 148.710283)
		(width 0.148)
		(layer "In4.Cu")
		(net 87)
	)
	(arc
		(start 127.770435 152.17835)
		(mid 127.593659 152.105126)
		(end 127.416882 152.178349)
		(width 0.148)
		(layer "In4.Cu")
		(net 87)
	)
	(arc
		(start 128.696127 154.788212)
		(mid 128.622903 154.611436)
		(end 128.696126 154.434659)
		(width 0.148)
		(layer "In4.Cu")
		(net 87)
	)
	(arc
		(start 125.514126 151.252657)
		(mid 125.33735 151.325881)
		(end 125.160573 151.252658)
		(width 0.148)
		(layer "In4.Cu")
		(net 87)
	)
	(arc
		(start 134.134434 158.895903)
		(mid 134.207658 158.719127)
		(end 134.134435 158.54235)
		(width 0.148)
		(layer "In4.Cu")
		(net 87)
	)
	(arc
		(start 125.867683 151.959768)
		(mid 125.794459 151.782992)
		(end 125.867682 151.606215)
		(width 0.148)
		(layer "In4.Cu")
		(net 87)
	)
	(arc
		(start 127.281905 153.37399)
		(mid 127.208681 153.197214)
		(end 127.281904 153.020437)
		(width 0.148)
		(layer "In4.Cu")
		(net 87)
	)
	(arc
		(start 124.941991 149.70346)
		(mid 125.015215 149.526684)
		(end 124.941992 149.349907)
		(width 0.148)
		(layer "In4.Cu")
		(net 87)
	)
	(arc
		(start 128.477546 152.885461)
		(mid 128.30077 152.812237)
		(end 128.123993 152.88546)
		(width 0.148)
		(layer "In4.Cu")
		(net 87)
	)
	(arc
		(start 131.30599 155.713905)
		(mid 131.129214 155.640681)
		(end 130.952437 155.713904)
		(width 0.148)
		(layer "In4.Cu")
		(net 87)
	)
	(arc
		(start 126.356213 150.764128)
		(mid 126.179437 150.690904)
		(end 126.00266 150.764127)
		(width 0.148)
		(layer "In4.Cu")
		(net 87)
	)
	(arc
		(start 129.403238 155.495323)
		(mid 129.330014 155.318547)
		(end 129.403237 155.14177)
		(width 0.148)
		(layer "In4.Cu")
		(net 87)
	)
	(arc
		(start 130.81746 156.909545)
		(mid 130.744236 156.732769)
		(end 130.817459 156.555992)
		(width 0.148)
		(layer "In4.Cu")
		(net 87)
	)
	(arc
		(start 132.938793 159.030878)
		(mid 132.865569 158.854102)
		(end 132.938792 158.677325)
		(width 0.148)
		(layer "In4.Cu")
		(net 87)
	)
	(arc
		(start 129.184657 153.592572)
		(mid 129.007881 153.519348)
		(end 128.831104 153.592571)
		(width 0.148)
		(layer "In4.Cu")
		(net 87)
	)
	(arc
		(start 123.74635 149.838435)
		(mid 123.673126 149.661659)
		(end 123.746349 149.484882)
		(width 0.148)
		(layer "In4.Cu")
		(net 87)
	)
	(arc
		(start 125.160572 151.252657)
		(mid 125.087348 151.075881)
		(end 125.160571 150.899104)
		(width 0.148)
		(layer "In4.Cu")
		(net 87)
	)
	(arc
		(start 124.941991 149.349906)
		(mid 124.765215 149.276682)
		(end 124.588438 149.349905)
		(width 0.148)
		(layer "In4.Cu")
		(net 87)
	)
	(arc
		(start 127.770435 152.531904)
		(mid 127.843659 152.355128)
		(end 127.770436 152.178351)
		(width 0.148)
		(layer "In4.Cu")
		(net 87)
	)
	(arc
		(start 129.184657 153.946126)
		(mid 129.257881 153.76935)
		(end 129.184658 153.592573)
		(width 0.148)
		(layer "In4.Cu")
		(net 87)
	)
	(arc
		(start 132.720212 157.481681)
		(mid 132.793436 157.304905)
		(end 132.720213 157.128128)
		(width 0.148)
		(layer "In4.Cu")
		(net 87)
	)
	(arc
		(start 127.989016 154.081101)
		(mid 127.915792 153.904325)
		(end 127.989015 153.727548)
		(width 0.148)
		(layer "In4.Cu")
		(net 87)
	)
	(arc
		(start 124.23488 148.996349)
		(mid 124.308104 148.819573)
		(end 124.234881 148.642796)
		(width 0.148)
		(layer "In4.Cu")
		(net 87)
	)
	(arc
		(start 126.356213 151.117682)
		(mid 126.429437 150.940906)
		(end 126.356214 150.764129)
		(width 0.148)
		(layer "In4.Cu")
		(net 87)
	)
	(arc
		(start 133.427323 158.188792)
		(mid 133.500547 158.012016)
		(end 133.427324 157.835239)
		(width 0.148)
		(layer "In4.Cu")
		(net 87)
	)
	(arc
		(start 125.649102 150.057017)
		(mid 125.472326 149.983793)
		(end 125.295549 150.057016)
		(width 0.148)
		(layer "In4.Cu")
		(net 87)
	)
	(arc
		(start 129.891768 154.653237)
		(mid 129.964992 154.476461)
		(end 129.891769 154.299684)
		(width 0.148)
		(layer "In4.Cu")
		(net 87)
	)
	(arc
		(start 127.063324 151.471239)
		(mid 126.886548 151.398015)
		(end 126.709771 151.471238)
		(width 0.148)
		(layer "In4.Cu")
		(net 87)
	)
	(arc
		(start 124.23488 148.642795)
		(mid 124.058104 148.569571)
		(end 123.881327 148.642794)
		(width 0.148)
		(layer "In4.Cu")
		(net 87)
	)
	(arc
		(start 131.878125 157.616656)
		(mid 131.701349 157.68988)
		(end 131.524572 157.616657)
		(width 0.148)
		(layer "In4.Cu")
		(net 87)
	)
	(arc
		(start 127.063324 151.824793)
		(mid 127.136548 151.648017)
		(end 127.063325 151.47124)
		(width 0.148)
		(layer "In4.Cu")
		(net 87)
	)
	(arc
		(start 130.598879 155.006794)
		(mid 130.422103 154.93357)
		(end 130.245326 155.006793)
		(width 0.148)
		(layer "In4.Cu")
		(net 87)
	)
	(arc
		(start 125.649102 150.410571)
		(mid 125.722326 150.233795)
		(end 125.649103 150.057018)
		(width 0.148)
		(layer "In4.Cu")
		(net 87)
	)
	(arc
		(start 133.645904 159.73799)
		(mid 133.57268 159.561214)
		(end 133.645903 159.384437)
		(width 0.148)
		(layer "In4.Cu")
		(net 87)
	)
	(arc
		(start 132.720212 157.128127)
		(mid 132.543436 157.054903)
		(end 132.366659 157.128126)
		(width 0.148)
		(layer "In4.Cu")
		(net 87)
	)
	(arc
		(start 127.635459 153.37399)
		(mid 127.458683 153.447214)
		(end 127.281906 153.373991)
		(width 0.148)
		(layer "In4.Cu")
		(net 87)
	)
	(arc
		(start 132.231682 158.323767)
		(mid 132.158458 158.146991)
		(end 132.231681 157.970214)
		(width 0.148)
		(layer "In4.Cu")
		(net 87)
	)
	(arc
		(start 124.807015 150.545546)
		(mid 124.630239 150.61877)
		(end 124.453462 150.545547)
		(width 0.148)
		(layer "In4.Cu")
		(net 87)
	)
	(arc
		(start 128.34257 154.081101)
		(mid 128.165794 154.154325)
		(end 127.989017 154.081102)
		(width 0.148)
		(layer "In4.Cu")
		(net 87)
	)
	(arc
		(start 126.574794 152.666879)
		(mid 126.50157 152.490103)
		(end 126.574793 152.313326)
		(width 0.148)
		(layer "In4.Cu")
		(net 87)
	)
	(arc
		(start 126.221237 151.959768)
		(mid 126.044461 152.032992)
		(end 125.867684 151.959769)
		(width 0.148)
		(layer "In4.Cu")
		(net 87)
	)
	(arc
		(start 134.134434 158.542349)
		(mid 133.957658 158.469125)
		(end 133.780881 158.542348)
		(width 0.148)
		(layer "In4.Cu")
		(net 87)
	)
	(arc
		(start 133.292347 159.030878)
		(mid 133.115571 159.104102)
		(end 132.938794 159.030879)
		(width 0.148)
		(layer "In4.Cu")
		(net 87)
	)
	(arc
		(start 130.110349 156.202434)
		(mid 130.037125 156.025658)
		(end 130.110348 155.848881)
		(width 0.148)
		(layer "In4.Cu")
		(net 87)
	)
	(arc
		(start 129.756792 155.495323)
		(mid 129.580016 155.568547)
		(end 129.403239 155.495324)
		(width 0.148)
		(layer "In4.Cu")
		(net 87)
	)
	(arc
		(start 132.013101 156.421016)
		(mid 131.836325 156.347792)
		(end 131.659548 156.421015)
		(width 0.148)
		(layer "In4.Cu")
		(net 87)
	)
	(arc
		(start 132.585236 158.323767)
		(mid 132.40846 158.396991)
		(end 132.231683 158.323768)
		(width 0.148)
		(layer "In4.Cu")
		(net 87)
	)
	(arc
		(start 134.420501 159.670501)
		(mid 134.243725 159.597277)
		(end 134.066948 159.6705)
		(width 0.148)
		(layer "In4.Cu")
		(net 87)
	)
	(arc
		(start 131.171014 156.909545)
		(mid 130.994238 156.982769)
		(end 130.817461 156.909546)
		(width 0.148)
		(layer "In4.Cu")
		(net 87)
	)
	(arc
		(start 129.891768 154.299683)
		(mid 129.714992 154.226459)
		(end 129.538215 154.299682)
		(width 0.148)
		(layer "In4.Cu")
		(net 87)
	)
	(arc
		(start 132.013101 156.77457)
		(mid 132.086325 156.597794)
		(end 132.013102 156.421017)
		(width 0.148)
		(layer "In4.Cu")
		(net 87)
	)
	(arc
		(start 130.598879 155.360348)
		(mid 130.672103 155.183572)
		(end 130.59888 155.006795)
		(width 0.148)
		(layer "In4.Cu")
		(net 87)
	)
	(segment
		(start 134.376501 164.302)
		(end 133.877001 163.8025)
		(width 0.256)
		(layer "F.Cu")
		(net 88)
	)
	(segment
		(start 118.650001 138.8025)
		(end 118.650001 139.8775)
		(width 0.201)
		(layer "F.Cu")
		(net 88)
	)
	(via
		(at 118.650001 139.8775)
		(size 0.45)
		(drill 0.1)
		(layers "F.Cu" "B.Cu")
		(net 88)
	)
	(via
		(at 133.877001 163.8025)
		(size 0.45)
		(drill 0.1)
		(layers "F.Cu" "B.Cu")
		(net 88)
	)
	(segment
		(start 117.875001 146.5025)
		(end 117.875001 147.625001)
		(width 0.148)
		(layer "In4.Cu")
		(net 88)
	)
	(segment
		(start 123.304911 150.377059)
		(end 123.304913 150.37706)
		(width 0.148)
		(layer "In4.Cu")
		(net 88)
	)
	(segment
		(start 129.265994 157.497401)
		(end 129.265994 157.4974)
		(width 0.148)
		(layer "In4.Cu")
		(net 88)
	)
	(segment
		(start 127.547535 154.619683)
		(end 127.547537 154.619684)
		(width 0.148)
		(layer "In4.Cu")
		(net 88)
	)
	(segment
		(start 122.597807 149.669955)
		(end 122.597809 149.669956)
		(width 0.148)
		(layer "In4.Cu")
		(net 88)
	)
	(segment
		(start 123.255611 151.133463)
		(end 123.255611 151.133464)
		(width 0.148)
		(layer "In4.Cu")
		(net 88)
	)
	(segment
		(start 134.390501 163.289)
		(end 133.877001 163.8025)
		(width 0.148)
		(layer "In4.Cu")
		(net 88)
	)
	(segment
		(start 125.02337 153.254777)
		(end 125.02337 153.254776)
		(width 0.148)
		(layer "In4.Cu")
		(net 88)
	)
	(segment
		(start 117.875001 147.625001)
		(end 118.75 148.5)
		(width 0.148)
		(layer "In4.Cu")
		(net 88)
	)
	(segment
		(start 127.547537 154.619684)
		(end 127.144682 155.022535)
		(width 0.148)
		(layer "In4.Cu")
		(net 88)
	)
	(segment
		(start 134.390501 162.536)
		(end 134.390501 163.289)
		(width 0.148)
		(layer "In4.Cu")
		(net 88)
	)
	(segment
		(start 123.304914 150.023507)
		(end 123.304912 150.023506)
		(width 0.148)
		(layer "In4.Cu")
		(net 88)
	)
	(segment
		(start 128.961743 156.033891)
		(end 128.961745 156.033892)
		(width 0.148)
		(layer "In4.Cu")
		(net 88)
	)
	(segment
		(start 126.840433 153.91258)
		(end 126.437578 154.315431)
		(width 0.148)
		(layer "In4.Cu")
		(net 88)
	)
	(segment
		(start 127.144682 155.376089)
		(end 127.144682 155.376088)
		(width 0.148)
		(layer "In4.Cu")
		(net 88)
	)
	(segment
		(start 121.841403 149.719255)
		(end 121.841403 149.719256)
		(width 0.148)
		(layer "In4.Cu")
		(net 88)
	)
	(segment
		(start 128.205339 156.083191)
		(end 128.205339 156.083192)
		(width 0.148)
		(layer "In4.Cu")
		(net 88)
	)
	(segment
		(start 127.547538 154.266131)
		(end 127.547536 154.26613)
		(width 0.148)
		(layer "In4.Cu")
		(net 88)
	)
	(segment
		(start 128.205339 156.083192)
		(end 128.60819 155.680337)
		(width 0.148)
		(layer "In4.Cu")
		(net 88)
	)
	(segment
		(start 129.668847 156.740995)
		(end 129.668849 156.740996)
		(width 0.148)
		(layer "In4.Cu")
		(net 88)
	)
	(segment
		(start 126.13333 152.851923)
		(end 126.133328 152.851922)
		(width 0.148)
		(layer "In4.Cu")
		(net 88)
	)
	(segment
		(start 125.426225 152.498372)
		(end 125.02337 152.901223)
		(width 0.148)
		(layer "In4.Cu")
		(net 88)
	)
	(segment
		(start 122.548507 150.426359)
		(end 122.548507 150.42636)
		(width 0.148)
		(layer "In4.Cu")
		(net 88)
	)
	(segment
		(start 121.487849 149.719255)
		(end 121.48785 149.719256)
		(width 0.148)
		(layer "In4.Cu")
		(net 88)
	)
	(segment
		(start 127.498235 155.376087)
		(end 127.498235 155.376088)
		(width 0.148)
		(layer "In4.Cu")
		(net 88)
	)
	(segment
		(start 124.669819 152.547672)
		(end 125.07267 152.144817)
		(width 0.148)
		(layer "In4.Cu")
		(net 88)
	)
	(segment
		(start 134.230501 162.376)
		(end 134.390501 162.536)
		(width 0.148)
		(layer "In4.Cu")
		(net 88)
	)
	(segment
		(start 129.66885 156.387443)
		(end 129.668848 156.387442)
		(width 0.148)
		(layer "In4.Cu")
		(net 88)
	)
	(segment
		(start 128.254641 155.326788)
		(end 127.851786 155.729639)
		(width 0.148)
		(layer "In4.Cu")
		(net 88)
	)
	(segment
		(start 130.351302 157.826302)
		(end 133.380501 160.855501)
		(width 0.148)
		(layer "In4.Cu")
		(net 88)
	)
	(segment
		(start 121.512499 149.341053)
		(end 121.5125 149.341053)
		(width 0.148)
		(layer "In4.Cu")
		(net 88)
	)
	(segment
		(start 123.609162 151.840569)
		(end 123.609162 151.840568)
		(width 0.148)
		(layer "In4.Cu")
		(net 88)
	)
	(segment
		(start 123.255611 151.133464)
		(end 123.658462 150.730609)
		(width 0.148)
		(layer "In4.Cu")
		(net 88)
	)
	(segment
		(start 122.59781 149.316403)
		(end 122.597808 149.316402)
		(width 0.148)
		(layer "In4.Cu")
		(net 88)
	)
	(segment
		(start 133.380501 160.855501)
		(end 133.380501 161.996)
		(width 0.148)
		(layer "In4.Cu")
		(net 88)
	)
	(segment
		(start 133.760501 162.376)
		(end 134.230501 162.376)
		(width 0.148)
		(layer "In4.Cu")
		(net 88)
	)
	(segment
		(start 128.254639 155.326787)
		(end 128.254641 155.326788)
		(width 0.148)
		(layer "In4.Cu")
		(net 88)
	)
	(segment
		(start 126.840431 153.912579)
		(end 126.840433 153.91258)
		(width 0.148)
		(layer "In4.Cu")
		(net 88)
	)
	(segment
		(start 122.548507 150.42636)
		(end 122.951358 150.023505)
		(width 0.148)
		(layer "In4.Cu")
		(net 88)
	)
	(segment
		(start 128.55889 156.790297)
		(end 128.55889 156.790296)
		(width 0.148)
		(layer "In4.Cu")
		(net 88)
	)
	(segment
		(start 121.5125 149.341053)
		(end 121.48785 149.365702)
		(width 0.148)
		(layer "In4.Cu")
		(net 88)
	)
	(segment
		(start 130.375951 157.448099)
		(end 130.375953 157.4481)
		(width 0.148)
		(layer "In4.Cu")
		(net 88)
	)
	(segment
		(start 133.380501 161.996)
		(end 133.760501 162.376)
		(width 0.148)
		(layer "In4.Cu")
		(net 88)
	)
	(segment
		(start 124.316266 152.547673)
		(end 124.316266 152.547672)
		(width 0.148)
		(layer "In4.Cu")
		(net 88)
	)
	(segment
		(start 126.133327 153.205475)
		(end 126.133329 153.205476)
		(width 0.148)
		(layer "In4.Cu")
		(net 88)
	)
	(segment
		(start 126.084027 153.96188)
		(end 126.486878 153.559025)
		(width 0.148)
		(layer "In4.Cu")
		(net 88)
	)
	(segment
		(start 126.084027 153.961879)
		(end 126.084027 153.96188)
		(width 0.148)
		(layer "In4.Cu")
		(net 88)
	)
	(segment
		(start 124.012015 151.084163)
		(end 124.012017 151.084164)
		(width 0.148)
		(layer "In4.Cu")
		(net 88)
	)
	(segment
		(start 125.426223 152.498371)
		(end 125.426225 152.498372)
		(width 0.148)
		(layer "In4.Cu")
		(net 88)
	)
	(segment
		(start 127.498235 155.376088)
		(end 127.901086 154.973233)
		(width 0.148)
		(layer "In4.Cu")
		(net 88)
	)
	(segment
		(start 121.025 148.5)
		(end 121.5125 148.9875)
		(width 0.148)
		(layer "In4.Cu")
		(net 88)
	)
	(segment
		(start 123.962715 151.840567)
		(end 123.962715 151.840568)
		(width 0.148)
		(layer "In4.Cu")
		(net 88)
	)
	(segment
		(start 124.719119 151.791267)
		(end 124.719121 151.791268)
		(width 0.148)
		(layer "In4.Cu")
		(net 88)
	)
	(segment
		(start 128.961746 155.680339)
		(end 128.961744 155.680338)
		(width 0.148)
		(layer "In4.Cu")
		(net 88)
	)
	(segment
		(start 129.619547 157.4974)
		(end 130.022398 157.094545)
		(width 0.148)
		(layer "In4.Cu")
		(net 88)
	)
	(segment
		(start 130.375954 157.094547)
		(end 130.375952 157.094546)
		(width 0.148)
		(layer "In4.Cu")
		(net 88)
	)
	(segment
		(start 122.597809 149.669956)
		(end 122.194954 150.072807)
		(width 0.148)
		(layer "In4.Cu")
		(net 88)
	)
	(segment
		(start 122.902058 151.133465)
		(end 122.902058 151.133464)
		(width 0.148)
		(layer "In4.Cu")
		(net 88)
	)
	(segment
		(start 118.375001 146.0025)
		(end 117.875001 146.5025)
		(width 0.148)
		(layer "In4.Cu")
		(net 88)
	)
	(segment
		(start 123.962715 151.840568)
		(end 124.365566 151.437713)
		(width 0.148)
		(layer "In4.Cu")
		(net 88)
	)
	(segment
		(start 124.669819 152.547671)
		(end 124.669819 152.547672)
		(width 0.148)
		(layer "In4.Cu")
		(net 88)
	)
	(segment
		(start 130.375953 157.4481)
		(end 130.351302 157.472748)
		(width 0.148)
		(layer "In4.Cu")
		(net 88)
	)
	(segment
		(start 128.912443 156.790296)
		(end 129.315294 156.387441)
		(width 0.148)
		(layer "In4.Cu")
		(net 88)
	)
	(segment
		(start 126.791131 154.668983)
		(end 126.791131 154.668984)
		(width 0.148)
		(layer "In4.Cu")
		(net 88)
	)
	(segment
		(start 122.194954 150.426361)
		(end 122.194954 150.42636)
		(width 0.148)
		(layer "In4.Cu")
		(net 88)
	)
	(segment
		(start 129.668849 156.740996)
		(end 129.265994 157.143847)
		(width 0.148)
		(layer "In4.Cu")
		(net 88)
	)
	(segment
		(start 126.437578 154.668985)
		(end 126.437578 154.668984)
		(width 0.148)
		(layer "In4.Cu")
		(net 88)
	)
	(segment
		(start 125.426226 152.144819)
		(end 125.426224 152.144818)
		(width 0.148)
		(layer "In4.Cu")
		(net 88)
	)
	(segment
		(start 130.351301 157.826301)
		(end 130.351302 157.826302)
		(width 0.148)
		(layer "In4.Cu")
		(net 88)
	)
	(segment
		(start 128.254642 154.973235)
		(end 128.25464 154.973234)
		(width 0.148)
		(layer "In4.Cu")
		(net 88)
	)
	(segment
		(start 118.650001 139.8775)
		(end 118.650001 144.599999)
		(width 0.148)
		(layer "In4.Cu")
		(net 88)
	)
	(segment
		(start 118.650001 144.599999)
		(end 118.375001 144.874999)
		(width 0.148)
		(layer "In4.Cu")
		(net 88)
	)
	(segment
		(start 127.851786 156.083193)
		(end 127.851786 156.083192)
		(width 0.148)
		(layer "In4.Cu")
		(net 88)
	)
	(segment
		(start 118.75 148.5)
		(end 121.025 148.5)
		(width 0.148)
		(layer "In4.Cu")
		(net 88)
	)
	(segment
		(start 124.012017 151.084164)
		(end 123.609162 151.487015)
		(width 0.148)
		(layer "In4.Cu")
		(net 88)
	)
	(segment
		(start 124.012018 150.730611)
		(end 124.012016 150.73061)
		(width 0.148)
		(layer "In4.Cu")
		(net 88)
	)
	(segment
		(start 125.730474 153.961881)
		(end 125.730474 153.96188)
		(width 0.148)
		(layer "In4.Cu")
		(net 88)
	)
	(segment
		(start 126.791131 154.668984)
		(end 127.193982 154.266129)
		(width 0.148)
		(layer "In4.Cu")
		(net 88)
	)
	(segment
		(start 118.375001 144.874999)
		(end 118.375001 146.0025)
		(width 0.148)
		(layer "In4.Cu")
		(net 88)
	)
	(segment
		(start 124.719121 151.791268)
		(end 124.316266 152.194119)
		(width 0.148)
		(layer "In4.Cu")
		(net 88)
	)
	(segment
		(start 121.841403 149.719256)
		(end 122.244254 149.316401)
		(width 0.148)
		(layer "In4.Cu")
		(net 88)
	)
	(segment
		(start 123.304913 150.37706)
		(end 122.902058 150.779911)
		(width 0.148)
		(layer "In4.Cu")
		(net 88)
	)
	(segment
		(start 128.912443 156.790295)
		(end 128.912443 156.790296)
		(width 0.148)
		(layer "In4.Cu")
		(net 88)
	)
	(segment
		(start 126.133329 153.205476)
		(end 125.730474 153.608327)
		(width 0.148)
		(layer "In4.Cu")
		(net 88)
	)
	(segment
		(start 126.840434 153.559027)
		(end 126.840432 153.559026)
		(width 0.148)
		(layer "In4.Cu")
		(net 88)
	)
	(segment
		(start 124.719122 151.437715)
		(end 124.71912 151.437714)
		(width 0.148)
		(layer "In4.Cu")
		(net 88)
	)
	(segment
		(start 125.376923 153.254776)
		(end 125.779774 152.851921)
		(width 0.148)
		(layer "In4.Cu")
		(net 88)
	)
	(segment
		(start 125.376923 153.254775)
		(end 125.376923 153.254776)
		(width 0.148)
		(layer "In4.Cu")
		(net 88)
	)
	(segment
		(start 129.619547 157.497399)
		(end 129.619547 157.4974)
		(width 0.148)
		(layer "In4.Cu")
		(net 88)
	)
	(segment
		(start 128.961745 156.033892)
		(end 128.55889 156.436743)
		(width 0.148)
		(layer "In4.Cu")
		(net 88)
	)
	(arc
		(start 123.304912 150.023506)
		(mid 123.378135 150.200283)
		(end 123.304911 150.377059)
		(width 0.148)
		(layer "In4.Cu")
		(net 88)
	)
	(arc
		(start 124.71912 151.437714)
		(mid 124.792343 151.614491)
		(end 124.719119 151.791267)
		(width 0.148)
		(layer "In4.Cu")
		(net 88)
	)
	(arc
		(start 129.315294 156.387441)
		(mid 129.492073 156.31422)
		(end 129.66885 156.387443)
		(width 0.148)
		(layer "In4.Cu")
		(net 88)
	)
	(arc
		(start 126.840432 153.559026)
		(mid 126.913655 153.735803)
		(end 126.840431 153.912579)
		(width 0.148)
		(layer "In4.Cu")
		(net 88)
	)
	(arc
		(start 129.668848 156.387442)
		(mid 129.742071 156.564219)
		(end 129.668847 156.740995)
		(width 0.148)
		(layer "In4.Cu")
		(net 88)
	)
	(arc
		(start 122.194954 150.42636)
		(mid 122.371731 150.499583)
		(end 122.548507 150.426359)
		(width 0.148)
		(layer "In4.Cu")
		(net 88)
	)
	(arc
		(start 124.365566 151.437713)
		(mid 124.542345 151.364492)
		(end 124.719122 151.437715)
		(width 0.148)
		(layer "In4.Cu")
		(net 88)
	)
	(arc
		(start 122.597808 149.316402)
		(mid 122.671031 149.493179)
		(end 122.597807 149.669955)
		(width 0.148)
		(layer "In4.Cu")
		(net 88)
	)
	(arc
		(start 130.375952 157.094546)
		(mid 130.449175 157.271323)
		(end 130.375951 157.448099)
		(width 0.148)
		(layer "In4.Cu")
		(net 88)
	)
	(arc
		(start 129.265994 157.4974)
		(mid 129.442771 157.570623)
		(end 129.619547 157.497399)
		(width 0.148)
		(layer "In4.Cu")
		(net 88)
	)
	(arc
		(start 129.265994 157.143847)
		(mid 129.192771 157.320624)
		(end 129.265994 157.497401)
		(width 0.148)
		(layer "In4.Cu")
		(net 88)
	)
	(arc
		(start 122.902058 150.779911)
		(mid 122.828835 150.956688)
		(end 122.902058 151.133465)
		(width 0.148)
		(layer "In4.Cu")
		(net 88)
	)
	(arc
		(start 123.609162 151.487015)
		(mid 123.535939 151.663792)
		(end 123.609162 151.840569)
		(width 0.148)
		(layer "In4.Cu")
		(net 88)
	)
	(arc
		(start 121.48785 149.719256)
		(mid 121.664627 149.792479)
		(end 121.841403 149.719255)
		(width 0.148)
		(layer "In4.Cu")
		(net 88)
	)
	(arc
		(start 126.437578 154.315431)
		(mid 126.364355 154.492208)
		(end 126.437578 154.668985)
		(width 0.148)
		(layer "In4.Cu")
		(net 88)
	)
	(arc
		(start 123.609162 151.840568)
		(mid 123.785939 151.913791)
		(end 123.962715 151.840567)
		(width 0.148)
		(layer "In4.Cu")
		(net 88)
	)
	(arc
		(start 130.022398 157.094545)
		(mid 130.199177 157.021324)
		(end 130.375954 157.094547)
		(width 0.148)
		(layer "In4.Cu")
		(net 88)
	)
	(arc
		(start 124.012016 150.73061)
		(mid 124.085239 150.907387)
		(end 124.012015 151.084163)
		(width 0.148)
		(layer "In4.Cu")
		(net 88)
	)
	(arc
		(start 121.5125 148.9875)
		(mid 121.585723 149.164277)
		(end 121.512499 149.341053)
		(width 0.148)
		(layer "In4.Cu")
		(net 88)
	)
	(arc
		(start 127.144682 155.376088)
		(mid 127.321459 155.449311)
		(end 127.498235 155.376087)
		(width 0.148)
		(layer "In4.Cu")
		(net 88)
	)
	(arc
		(start 126.437578 154.668984)
		(mid 126.614355 154.742207)
		(end 126.791131 154.668983)
		(width 0.148)
		(layer "In4.Cu")
		(net 88)
	)
	(arc
		(start 122.244254 149.316401)
		(mid 122.421033 149.24318)
		(end 122.59781 149.316403)
		(width 0.148)
		(layer "In4.Cu")
		(net 88)
	)
	(arc
		(start 122.194954 150.072807)
		(mid 122.121731 150.249584)
		(end 122.194954 150.426361)
		(width 0.148)
		(layer "In4.Cu")
		(net 88)
	)
	(arc
		(start 121.48785 149.365702)
		(mid 121.414626 149.542478)
		(end 121.487849 149.719255)
		(width 0.148)
		(layer "In4.Cu")
		(net 88)
	)
	(arc
		(start 128.55889 156.436743)
		(mid 128.485667 156.61352)
		(end 128.55889 156.790297)
		(width 0.148)
		(layer "In4.Cu")
		(net 88)
	)
	(arc
		(start 127.193982 154.266129)
		(mid 127.370761 154.192908)
		(end 127.547538 154.266131)
		(width 0.148)
		(layer "In4.Cu")
		(net 88)
	)
	(arc
		(start 127.851786 156.083192)
		(mid 128.028563 156.156415)
		(end 128.205339 156.083191)
		(width 0.148)
		(layer "In4.Cu")
		(net 88)
	)
	(arc
		(start 125.730474 153.608327)
		(mid 125.657251 153.785104)
		(end 125.730474 153.961881)
		(width 0.148)
		(layer "In4.Cu")
		(net 88)
	)
	(arc
		(start 122.902058 151.133464)
		(mid 123.078835 151.206687)
		(end 123.255611 151.133463)
		(width 0.148)
		(layer "In4.Cu")
		(net 88)
	)
	(arc
		(start 127.144682 155.022535)
		(mid 127.071459 155.199312)
		(end 127.144682 155.376089)
		(width 0.148)
		(layer "In4.Cu")
		(net 88)
	)
	(arc
		(start 126.486878 153.559025)
		(mid 126.663657 153.485804)
		(end 126.840434 153.559027)
		(width 0.148)
		(layer "In4.Cu")
		(net 88)
	)
	(arc
		(start 124.316266 152.194119)
		(mid 124.243043 152.370896)
		(end 124.316266 152.547673)
		(width 0.148)
		(layer "In4.Cu")
		(net 88)
	)
	(arc
		(start 125.426224 152.144818)
		(mid 125.499447 152.321595)
		(end 125.426223 152.498371)
		(width 0.148)
		(layer "In4.Cu")
		(net 88)
	)
	(arc
		(start 125.02337 153.254776)
		(mid 125.200147 153.327999)
		(end 125.376923 153.254775)
		(width 0.148)
		(layer "In4.Cu")
		(net 88)
	)
	(arc
		(start 125.02337 152.901223)
		(mid 124.950147 153.078)
		(end 125.02337 153.254777)
		(width 0.148)
		(layer "In4.Cu")
		(net 88)
	)
	(arc
		(start 123.658462 150.730609)
		(mid 123.835241 150.657388)
		(end 124.012018 150.730611)
		(width 0.148)
		(layer "In4.Cu")
		(net 88)
	)
	(arc
		(start 128.55889 156.790296)
		(mid 128.735667 156.863519)
		(end 128.912443 156.790295)
		(width 0.148)
		(layer "In4.Cu")
		(net 88)
	)
	(arc
		(start 122.951358 150.023505)
		(mid 123.128137 149.950284)
		(end 123.304914 150.023507)
		(width 0.148)
		(layer "In4.Cu")
		(net 88)
	)
	(arc
		(start 127.851786 155.729639)
		(mid 127.778563 155.906416)
		(end 127.851786 156.083193)
		(width 0.148)
		(layer "In4.Cu")
		(net 88)
	)
	(arc
		(start 126.133328 152.851922)
		(mid 126.206551 153.028699)
		(end 126.133327 153.205475)
		(width 0.148)
		(layer "In4.Cu")
		(net 88)
	)
	(arc
		(start 125.730474 153.96188)
		(mid 125.907251 154.035103)
		(end 126.084027 153.961879)
		(width 0.148)
		(layer "In4.Cu")
		(net 88)
	)
	(arc
		(start 127.547536 154.26613)
		(mid 127.620759 154.442907)
		(end 127.547535 154.619683)
		(width 0.148)
		(layer "In4.Cu")
		(net 88)
	)
	(arc
		(start 128.60819 155.680337)
		(mid 128.784969 155.607116)
		(end 128.961746 155.680339)
		(width 0.148)
		(layer "In4.Cu")
		(net 88)
	)
	(arc
		(start 128.25464 154.973234)
		(mid 128.327863 155.150011)
		(end 128.254639 155.326787)
		(width 0.148)
		(layer "In4.Cu")
		(net 88)
	)
	(arc
		(start 127.901086 154.973233)
		(mid 128.077865 154.900012)
		(end 128.254642 154.973235)
		(width 0.148)
		(layer "In4.Cu")
		(net 88)
	)
	(arc
		(start 128.961744 155.680338)
		(mid 129.034967 155.857115)
		(end 128.961743 156.033891)
		(width 0.148)
		(layer "In4.Cu")
		(net 88)
	)
	(arc
		(start 125.779774 152.851921)
		(mid 125.956553 152.7787)
		(end 126.13333 152.851923)
		(width 0.148)
		(layer "In4.Cu")
		(net 88)
	)
	(arc
		(start 130.351302 157.472748)
		(mid 130.278078 157.649524)
		(end 130.351301 157.826301)
		(width 0.148)
		(layer "In4.Cu")
		(net 88)
	)
	(arc
		(start 124.316266 152.547672)
		(mid 124.493043 152.620895)
		(end 124.669819 152.547671)
		(width 0.148)
		(layer "In4.Cu")
		(net 88)
	)
	(arc
		(start 125.07267 152.144817)
		(mid 125.249449 152.071596)
		(end 125.426226 152.144819)
		(width 0.148)
		(layer "In4.Cu")
		(net 88)
	)
	(segment
		(start 119.400001 146.2025)
		(end 119.400001 147.2775)
		(width 0.201)
		(layer "F.Cu")
		(net 89)
	)
	(segment
		(start 134.376501 167.302)
		(end 133.877001 166.802501)
		(width 0.256)
		(layer "F.Cu")
		(net 89)
	)
	(via
		(at 133.877001 166.802501)
		(size 0.45)
		(drill 0.1)
		(layers "F.Cu" "B.Cu")
		(net 89)
	)
	(via
		(at 119.400001 147.2775)
		(size 0.45)
		(drill 0.1)
		(layers "F.Cu" "B.Cu")
		(net 89)
	)
	(segment
		(start 132.032331 164.4275)
		(end 131.750001 164.4275)
		(width 0.1)
		(layer "In2.Cu")
		(net 89)
	)
	(segment
		(start 130.0189 160.824991)
		(end 130.018899 160.82499)
		(width 0.148)
		(layer "In2.Cu")
		(net 89)
	)
	(segment
		(start 125.776236 156.228772)
		(end 126.22877 155.776233)
		(width 0.148)
		(layer "In2.Cu")
		(net 89)
	)
	(segment
		(start 125.875216 155.42268)
		(end 125.825724 155.472171)
		(width 0.148)
		(layer "In2.Cu")
		(net 89)
	)
	(segment
		(start 127.897567 158.703658)
		(end 127.897569 158.703659)
		(width 0.148)
		(layer "In2.Cu")
		(net 89)
	)
	(segment
		(start 131.425001 161.425001)
		(end 130.7755 160.7755)
		(width 0.148)
		(layer "In2.Cu")
		(net 89)
	)
	(segment
		(start 129.057214 158.251123)
		(end 129.057214 158.251124)
		(width 0.148)
		(layer "In2.Cu")
		(net 89)
	)
	(segment
		(start 129.311791 159.764327)
		(end 129.764325 159.311788)
		(width 0.148)
		(layer "In2.Cu")
		(net 89)
	)
	(segment
		(start 126.582328 156.12979)
		(end 126.582327 156.129791)
		(width 0.148)
		(layer "In2.Cu")
		(net 89)
	)
	(segment
		(start 125.776234 156.582325)
		(end 125.776236 156.582326)
		(width 0.148)
		(layer "In2.Cu")
		(net 89)
	)
	(segment
		(start 127.190457 157.642995)
		(end 127.190458 157.642994)
		(width 0.148)
		(layer "In2.Cu")
		(net 89)
	)
	(segment
		(start 132.957332 165.3525)
		(end 132.873669 165.3525)
		(width 0.1)
		(layer "In2.Cu")
		(net 89)
	)
	(segment
		(start 130.018899 160.471436)
		(end 130.471436 160.018899)
		(width 0.148)
		(layer "In2.Cu")
		(net 89)
	)
	(segment
		(start 133.877001 166.4045)
		(end 133.430332 165.957831)
		(width 0.1)
		(layer "In2.Cu")
		(net 89)
	)
	(segment
		(start 125.472171 155.472172)
		(end 125.47217 155.472171)
		(width 0.148)
		(layer "In2.Cu")
		(net 89)
	)
	(segment
		(start 133.430332 165.957831)
		(end 133.430332 165.8255)
		(width 0.1)
		(layer "In2.Cu")
		(net 89)
	)
	(segment
		(start 130.421947 160.775499)
		(end 130.421946 160.7755)
		(width 0.148)
		(layer "In2.Cu")
		(net 89)
	)
	(segment
		(start 127.289438 156.836902)
		(end 126.836899 157.289436)
		(width 0.148)
		(layer "In2.Cu")
		(net 89)
	)
	(segment
		(start 127.642992 156.836901)
		(end 127.642992 156.836902)
		(width 0.148)
		(layer "In2.Cu")
		(net 89)
	)
	(segment
		(start 127.99655 157.544012)
		(end 127.996549 157.544013)
		(width 0.148)
		(layer "In2.Cu")
		(net 89)
	)
	(segment
		(start 129.764325 158.958234)
		(end 129.764325 158.958235)
		(width 0.148)
		(layer "In2.Cu")
		(net 89)
	)
	(segment
		(start 126.582327 156.129791)
		(end 126.129788 156.582325)
		(width 0.148)
		(layer "In2.Cu")
		(net 89)
	)
	(segment
		(start 118.25 148.426501)
		(end 119.399001 147.2775)
		(width 0.148)
		(layer "In2.Cu")
		(net 89)
	)
	(segment
		(start 131.750001 164.4275)
		(end 131.425001 164.1025)
		(width 0.1)
		(layer "In2.Cu")
		(net 89)
	)
	(segment
		(start 130.421946 160.7755)
		(end 130.372453 160.82499)
		(width 0.148)
		(layer "In2.Cu")
		(net 89)
	)
	(segment
		(start 128.703661 158.251123)
		(end 128.70366 158.251124)
		(width 0.148)
		(layer "In2.Cu")
		(net 89)
	)
	(segment
		(start 130.117882 159.665346)
		(end 129.665343 160.11788)
		(width 0.148)
		(layer "In2.Cu")
		(net 89)
	)
	(segment
		(start 133.430332 165.8255)
		(end 132.957332 165.3525)
		(width 0.1)
		(layer "In2.Cu")
		(net 89)
	)
	(segment
		(start 131.425001 164.1025)
		(end 131.425001 161.425001)
		(width 0.148)
		(layer "In2.Cu")
		(net 89)
	)
	(segment
		(start 126.483346 156.935884)
		(end 126.483347 156.935883)
		(width 0.148)
		(layer "In2.Cu")
		(net 89)
	)
	(segment
		(start 126.22877 155.422679)
		(end 126.22877 155.42268)
		(width 0.148)
		(layer "In2.Cu")
		(net 89)
	)
	(segment
		(start 133.877001 166.802501)
		(end 133.877001 166.4045)
		(width 0.1)
		(layer "In2.Cu")
		(net 89)
	)
	(segment
		(start 127.996549 157.544013)
		(end 127.54401 157.996547)
		(width 0.148)
		(layer "In2.Cu")
		(net 89)
	)
	(segment
		(start 127.289439 156.836901)
		(end 127.289438 156.836902)
		(width 0.148)
		(layer "In2.Cu")
		(net 89)
	)
	(segment
		(start 129.410771 158.958235)
		(end 128.958232 159.410769)
		(width 0.148)
		(layer "In2.Cu")
		(net 89)
	)
	(segment
		(start 125.776235 156.228773)
		(end 125.776236 156.228772)
		(width 0.148)
		(layer "In2.Cu")
		(net 89)
	)
	(segment
		(start 128.604679 159.057217)
		(end 128.60468 159.057216)
		(width 0.148)
		(layer "In2.Cu")
		(net 89)
	)
	(segment
		(start 127.897569 158.350105)
		(end 128.350103 157.897566)
		(width 0.148)
		(layer "In2.Cu")
		(net 89)
	)
	(segment
		(start 119.399001 147.2775)
		(end 119.400001 147.2775)
		(width 0.148)
		(layer "In2.Cu")
		(net 89)
	)
	(segment
		(start 130.018898 160.471437)
		(end 130.018899 160.471436)
		(width 0.148)
		(layer "In2.Cu")
		(net 89)
	)
	(segment
		(start 118.25 152)
		(end 118.25 148.426501)
		(width 0.148)
		(layer "In2.Cu")
		(net 89)
	)
	(segment
		(start 126.935881 156.12979)
		(end 126.935881 156.129791)
		(width 0.148)
		(layer "In2.Cu")
		(net 89)
	)
	(segment
		(start 125.47217 155.472171)
		(end 125 155)
		(width 0.148)
		(layer "In2.Cu")
		(net 89)
	)
	(segment
		(start 129.311789 160.11788)
		(end 129.311791 160.117881)
		(width 0.148)
		(layer "In2.Cu")
		(net 89)
	)
	(segment
		(start 132.399335 164.794504)
		(end 132.032331 164.4275)
		(width 0.1)
		(layer "In2.Cu")
		(net 89)
	)
	(segment
		(start 126.483345 157.289436)
		(end 126.483347 157.289437)
		(width 0.148)
		(layer "In2.Cu")
		(net 89)
	)
	(segment
		(start 130.471436 159.665345)
		(end 130.471436 159.665346)
		(width 0.148)
		(layer "In2.Cu")
		(net 89)
	)
	(segment
		(start 130.117883 159.665345)
		(end 130.117882 159.665346)
		(width 0.148)
		(layer "In2.Cu")
		(net 89)
	)
	(segment
		(start 129.410772 158.958234)
		(end 129.410771 158.958235)
		(width 0.148)
		(layer "In2.Cu")
		(net 89)
	)
	(segment
		(start 132.399335 164.878166)
		(end 132.399335 164.794504)
		(width 0.1)
		(layer "In2.Cu")
		(net 89)
	)
	(segment
		(start 127.190458 157.642994)
		(end 127.642992 157.190455)
		(width 0.148)
		(layer "In2.Cu")
		(net 89)
	)
	(segment
		(start 128.60468 159.057216)
		(end 129.057214 158.604677)
		(width 0.148)
		(layer "In2.Cu")
		(net 89)
	)
	(segment
		(start 126.483347 156.935883)
		(end 126.935881 156.483344)
		(width 0.148)
		(layer "In2.Cu")
		(net 89)
	)
	(segment
		(start 128.350103 157.544012)
		(end 128.350103 157.544013)
		(width 0.148)
		(layer "In2.Cu")
		(net 89)
	)
	(segment
		(start 127.190456 157.996547)
		(end 127.190458 157.996548)
		(width 0.148)
		(layer "In2.Cu")
		(net 89)
	)
	(segment
		(start 121.25 155)
		(end 118.25 152)
		(width 0.148)
		(layer "In2.Cu")
		(net 89)
	)
	(segment
		(start 125.875217 155.422679)
		(end 125.875216 155.42268)
		(width 0.148)
		(layer "In2.Cu")
		(net 89)
	)
	(segment
		(start 129.31179 159.764328)
		(end 129.311791 159.764327)
		(width 0.148)
		(layer "In2.Cu")
		(net 89)
	)
	(segment
		(start 127.897568 158.350106)
		(end 127.897569 158.350105)
		(width 0.148)
		(layer "In2.Cu")
		(net 89)
	)
	(segment
		(start 125 155)
		(end 121.25 155)
		(width 0.148)
		(layer "In2.Cu")
		(net 89)
	)
	(segment
		(start 132.873669 165.3525)
		(end 132.399335 164.878166)
		(width 0.1)
		(layer "In2.Cu")
		(net 89)
	)
	(segment
		(start 128.604678 159.410769)
		(end 128.60468 159.41077)
		(width 0.148)
		(layer "In2.Cu")
		(net 89)
	)
	(segment
		(start 128.70366 158.251124)
		(end 128.251121 158.703658)
		(width 0.148)
		(layer "In2.Cu")
		(net 89)
	)
	(arc
		(start 127.54401 157.996547)
		(mid 127.367233 158.06977)
		(end 127.190456 157.996547)
		(width 0.148)
		(layer "In2.Cu")
		(net 89)
	)
	(arc
		(start 127.642992 157.190455)
		(mid 127.716215 157.013678)
		(end 127.642992 156.836901)
		(width 0.148)
		(layer "In2.Cu")
		(net 89)
	)
	(arc
		(start 127.642992 156.836902)
		(mid 127.466216 156.763678)
		(end 127.289439 156.836901)
		(width 0.148)
		(layer "In2.Cu")
		(net 89)
	)
	(arc
		(start 125.825724 155.472171)
		(mid 125.648948 155.545395)
		(end 125.472171 155.472172)
		(width 0.148)
		(layer "In2.Cu")
		(net 89)
	)
	(arc
		(start 128.350103 157.897566)
		(mid 128.423326 157.720789)
		(end 128.350103 157.544012)
		(width 0.148)
		(layer "In2.Cu")
		(net 89)
	)
	(arc
		(start 129.057214 158.604677)
		(mid 129.130437 158.4279)
		(end 129.057214 158.251123)
		(width 0.148)
		(layer "In2.Cu")
		(net 89)
	)
	(arc
		(start 126.22877 155.776233)
		(mid 126.301993 155.599456)
		(end 126.22877 155.422679)
		(width 0.148)
		(layer "In2.Cu")
		(net 89)
	)
	(arc
		(start 126.483347 157.289437)
		(mid 126.410123 157.112661)
		(end 126.483346 156.935884)
		(width 0.148)
		(layer "In2.Cu")
		(net 89)
	)
	(arc
		(start 126.935881 156.129791)
		(mid 126.759105 156.056567)
		(end 126.582328 156.12979)
		(width 0.148)
		(layer "In2.Cu")
		(net 89)
	)
	(arc
		(start 126.836899 157.289436)
		(mid 126.660122 157.362659)
		(end 126.483345 157.289436)
		(width 0.148)
		(layer "In2.Cu")
		(net 89)
	)
	(arc
		(start 130.471436 160.018899)
		(mid 130.544659 159.842122)
		(end 130.471436 159.665345)
		(width 0.148)
		(layer "In2.Cu")
		(net 89)
	)
	(arc
		(start 127.897569 158.703659)
		(mid 127.824345 158.526883)
		(end 127.897568 158.350106)
		(width 0.148)
		(layer "In2.Cu")
		(net 89)
	)
	(arc
		(start 130.018899 160.82499)
		(mid 129.945675 160.648214)
		(end 130.018898 160.471437)
		(width 0.148)
		(layer "In2.Cu")
		(net 89)
	)
	(arc
		(start 128.60468 159.41077)
		(mid 128.531456 159.233994)
		(end 128.604679 159.057217)
		(width 0.148)
		(layer "In2.Cu")
		(net 89)
	)
	(arc
		(start 129.057214 158.251124)
		(mid 128.880438 158.1779)
		(end 128.703661 158.251123)
		(width 0.148)
		(layer "In2.Cu")
		(net 89)
	)
	(arc
		(start 129.665343 160.11788)
		(mid 129.488566 160.191103)
		(end 129.311789 160.11788)
		(width 0.148)
		(layer "In2.Cu")
		(net 89)
	)
	(arc
		(start 126.129788 156.582325)
		(mid 125.953011 156.655548)
		(end 125.776234 156.582325)
		(width 0.148)
		(layer "In2.Cu")
		(net 89)
	)
	(arc
		(start 129.311791 160.117881)
		(mid 129.238567 159.941105)
		(end 129.31179 159.764328)
		(width 0.148)
		(layer "In2.Cu")
		(net 89)
	)
	(arc
		(start 130.7755 160.7755)
		(mid 130.598724 160.702276)
		(end 130.421947 160.775499)
		(width 0.148)
		(layer "In2.Cu")
		(net 89)
	)
	(arc
		(start 127.190458 157.996548)
		(mid 127.117234 157.819772)
		(end 127.190457 157.642995)
		(width 0.148)
		(layer "In2.Cu")
		(net 89)
	)
	(arc
		(start 128.350103 157.544013)
		(mid 128.173327 157.470789)
		(end 127.99655 157.544012)
		(width 0.148)
		(layer "In2.Cu")
		(net 89)
	)
	(arc
		(start 128.958232 159.410769)
		(mid 128.781455 159.483992)
		(end 128.604678 159.410769)
		(width 0.148)
		(layer "In2.Cu")
		(net 89)
	)
	(arc
		(start 126.22877 155.42268)
		(mid 126.051994 155.349456)
		(end 125.875217 155.422679)
		(width 0.148)
		(layer "In2.Cu")
		(net 89)
	)
	(arc
		(start 125.776236 156.582326)
		(mid 125.703012 156.40555)
		(end 125.776235 156.228773)
		(width 0.148)
		(layer "In2.Cu")
		(net 89)
	)
	(arc
		(start 128.251121 158.703658)
		(mid 128.074344 158.776881)
		(end 127.897567 158.703658)
		(width 0.148)
		(layer "In2.Cu")
		(net 89)
	)
	(arc
		(start 130.471436 159.665346)
		(mid 130.29466 159.592122)
		(end 130.117883 159.665345)
		(width 0.148)
		(layer "In2.Cu")
		(net 89)
	)
	(arc
		(start 129.764325 158.958235)
		(mid 129.587549 158.885011)
		(end 129.410772 158.958234)
		(width 0.148)
		(layer "In2.Cu")
		(net 89)
	)
	(arc
		(start 129.764325 159.311788)
		(mid 129.837548 159.135011)
		(end 129.764325 158.958234)
		(width 0.148)
		(layer "In2.Cu")
		(net 89)
	)
	(arc
		(start 126.935881 156.483344)
		(mid 127.009104 156.306567)
		(end 126.935881 156.12979)
		(width 0.148)
		(layer "In2.Cu")
		(net 89)
	)
	(arc
		(start 130.372453 160.82499)
		(mid 130.195677 160.898214)
		(end 130.0189 160.824991)
		(width 0.148)
		(layer "In2.Cu")
		(net 89)
	)
	(segment
		(start 182.140107 169.723107)
		(end 182.140107 168.211)
		(width 0.2)
		(layer "F.Cu")
		(net 90)
	)
	(segment
		(start 182.179107 169.762107)
		(end 182.140107 169.723107)
		(width 0.2)
		(layer "F.Cu")
		(net 90)
	)
	(segment
		(start 200.223001 173.973998)
		(end 199.801001 173.973998)
		(width 0.1)
		(layer "F.Cu")
		(net 90)
	)
	(via
		(at 182.179107 169.762107)
		(size 0.45)
		(drill 0.1)
		(layers "F.Cu" "B.Cu")
		(net 90)
	)
	(via
		(at 199.800001 173.974998)
		(size 0.45)
		(drill 0.1)
		(layers "F.Cu" "B.Cu")
		(net 90)
	)
	(segment
		(start 185.041422 174.4)
		(end 189.158578 174.4)
		(width 0.1)
		(layer "In4.Cu")
		(net 90)
	)
	(segment
		(start 181.987356 169.953858)
		(end 181.987356 171.345934)
		(width 0.1)
		(layer "In4.Cu")
		(net 90)
	)
	(segment
		(start 199.625001 173.799998)
		(end 199.800001 173.974998)
		(width 0.1)
		(layer "In4.Cu")
		(net 90)
	)
	(segment
		(start 181.987356 171.345934)
		(end 185.041422 174.4)
		(width 0.1)
		(layer "In4.Cu")
		(net 90)
	)
	(segment
		(start 199.041422 172.4)
		(end 199.625001 172.983579)
		(width 0.1)
		(layer "In4.Cu")
		(net 90)
	)
	(segment
		(start 191.158578 172.4)
		(end 199.041422 172.4)
		(width 0.1)
		(layer "In4.Cu")
		(net 90)
	)
	(segment
		(start 189.158578 174.4)
		(end 191.158578 172.4)
		(width 0.1)
		(layer "In4.Cu")
		(net 90)
	)
	(segment
		(start 182.179107 169.762107)
		(end 181.987356 169.953858)
		(width 0.1)
		(layer "In4.Cu")
		(net 90)
	)
	(segment
		(start 199.625001 172.983579)
		(end 199.625001 173.799998)
		(width 0.1)
		(layer "In4.Cu")
		(net 90)
	)
	(segment
		(start 135.376501 167.302)
		(end 134.877001 166.8025)
		(width 0.256)
		(layer "F.Cu")
		(net 91)
	)
	(segment
		(start 119.650001 138.8025)
		(end 119.650001 139.8775)
		(width 0.201)
		(layer "F.Cu")
		(net 91)
	)
	(via
		(at 134.877001 166.8025)
		(size 0.45)
		(drill 0.1)
		(layers "F.Cu" "B.Cu")
		(net 91)
	)
	(via
		(at 119.650001 139.8775)
		(size 0.45)
		(drill 0.1)
		(layers "F.Cu" "B.Cu")
		(net 91)
	)
	(segment
		(start 119 151.75)
		(end 121.5 154.25)
		(width 0.148)
		(layer "In2.Cu")
		(net 91)
	)
	(segment
		(start 119.655 141.405)
		(end 119.675706 141.405)
		(width 0.148)
		(layer "In2.Cu")
		(net 91)
	)
	(segment
		(start 134.375001 165.6025)
		(end 134.025001 165.2525)
		(width 0.1)
		(layer "In2.Cu")
		(net 91)
	)
	(segment
		(start 119.650001 140.599999)
		(end 119.405 140.845)
		(width 0.148)
		(layer "In2.Cu")
		(net 91)
	)
	(segment
		(start 133.375001 164.6525)
		(end 133.025001 164.3025)
		(width 0.1)
		(layer "In2.Cu")
		(net 91)
	)
	(segment
		(start 119.405 145.881499)
		(end 119.900501 146.377)
		(width 0.148)
		(layer "In2.Cu")
		(net 91)
	)
	(segment
		(start 121.5 154.25)
		(end 125.5 154.25)
		(width 0.148)
		(layer "In2.Cu")
		(net 91)
	)
	(segment
		(start 119.405 144.655)
		(end 119.405 145.881499)
		(width 0.148)
		(layer "In2.Cu")
		(net 91)
	)
	(segment
		(start 119 148.509137)
		(end 119 151.75)
		(width 0.148)
		(layer "In2.Cu")
		(net 91)
	)
	(segment
		(start 119.655 141.905)
		(end 119.134294 141.905)
		(width 0.148)
		(layer "In2.Cu")
		(net 91)
	)
	(segment
		(start 133.375001 165.080831)
		(end 133.375001 164.6525)
		(width 0.1)
		(layer "In2.Cu")
		(net 91)
	)
	(segment
		(start 119.134294 142.905)
		(end 119.675706 142.905)
		(width 0.148)
		(layer "In2.Cu")
		(net 91)
	)
	(segment
		(start 134.025001 165.2525)
		(end 133.54667 165.2525)
		(width 0.1)
		(layer "In2.Cu")
		(net 91)
	)
	(segment
		(start 119.900501 147.608636)
		(end 119 148.509137)
		(width 0.148)
		(layer "In2.Cu")
		(net 91)
	)
	(segment
		(start 119.134294 144.405)
		(end 119.155 144.405)
		(width 0.148)
		(layer "In2.Cu")
		(net 91)
	)
	(segment
		(start 119.134294 143.405)
		(end 119.675706 143.405)
		(width 0.148)
		(layer "In2.Cu")
		(net 91)
	)
	(segment
		(start 132.375001 161.125001)
		(end 132.375001 164.080832)
		(width 0.148)
		(layer "In2.Cu")
		(net 91)
	)
	(segment
		(start 119.405 140.845)
		(end 119.405 141.155)
		(width 0.148)
		(layer "In2.Cu")
		(net 91)
	)
	(segment
		(start 119.134294 143.905)
		(end 119.675706 143.905)
		(width 0.148)
		(layer "In2.Cu")
		(net 91)
	)
	(segment
		(start 134.877001 166.8025)
		(end 134.375001 166.3005)
		(width 0.1)
		(layer "In2.Cu")
		(net 91)
	)
	(segment
		(start 125.5 154.25)
		(end 132.375001 161.125001)
		(width 0.148)
		(layer "In2.Cu")
		(net 91)
	)
	(segment
		(start 133.025001 164.3025)
		(end 132.596669 164.3025)
		(width 0.1)
		(layer "In2.Cu")
		(net 91)
	)
	(segment
		(start 133.54667 165.2525)
		(end 133.375001 165.080831)
		(width 0.1)
		(layer "In2.Cu")
		(net 91)
	)
	(segment
		(start 119.675706 141.905)
		(end 119.655 141.905)
		(width 0.148)
		(layer "In2.Cu")
		(net 91)
	)
	(segment
		(start 134.375001 166.3005)
		(end 134.375001 165.6025)
		(width 0.1)
		(layer "In2.Cu")
		(net 91)
	)
	(segment
		(start 119.134294 142.405)
		(end 119.675706 142.405)
		(width 0.148)
		(layer "In2.Cu")
		(net 91)
	)
	(segment
		(start 132.596669 164.3025)
		(end 132.375001 164.080832)
		(width 0.1)
		(layer "In2.Cu")
		(net 91)
	)
	(segment
		(start 119.650001 139.8775)
		(end 119.650001 140.599999)
		(width 0.148)
		(layer "In2.Cu")
		(net 91)
	)
	(segment
		(start 119.900501 146.377)
		(end 119.900501 147.608636)
		(width 0.148)
		(layer "In2.Cu")
		(net 91)
	)
	(arc
		(start 119.134294 142.905)
		(mid 118.957517 142.978223)
		(end 118.884294 143.155)
		(width 0.148)
		(layer "In2.Cu")
		(net 91)
	)
	(arc
		(start 119.925706 141.655)
		(mid 119.852483 141.831777)
		(end 119.675706 141.905)
		(width 0.148)
		(layer "In2.Cu")
		(net 91)
	)
	(arc
		(start 118.884294 142.155)
		(mid 118.957517 142.331777)
		(end 119.134294 142.405)
		(width 0.148)
		(layer "In2.Cu")
		(net 91)
	)
	(arc
		(start 119.675706 142.405)
		(mid 119.852483 142.478223)
		(end 119.925706 142.655)
		(width 0.148)
		(layer "In2.Cu")
		(net 91)
	)
	(arc
		(start 118.884294 143.155)
		(mid 118.957517 143.331777)
		(end 119.134294 143.405)
		(width 0.148)
		(layer "In2.Cu")
		(net 91)
	)
	(arc
		(start 118.884294 144.155)
		(mid 118.957517 144.331777)
		(end 119.134294 144.405)
		(width 0.148)
		(layer "In2.Cu")
		(net 91)
	)
	(arc
		(start 119.155 144.405)
		(mid 119.331777 144.478223)
		(end 119.405 144.655)
		(width 0.148)
		(layer "In2.Cu")
		(net 91)
	)
	(arc
		(start 119.134294 143.905)
		(mid 118.957517 143.978223)
		(end 118.884294 144.155)
		(width 0.148)
		(layer "In2.Cu")
		(net 91)
	)
	(arc
		(start 119.675706 141.405)
		(mid 119.852483 141.478223)
		(end 119.925706 141.655)
		(width 0.148)
		(layer "In2.Cu")
		(net 91)
	)
	(arc
		(start 119.925706 142.655)
		(mid 119.852483 142.831777)
		(end 119.675706 142.905)
		(width 0.148)
		(layer "In2.Cu")
		(net 91)
	)
	(arc
		(start 119.405 141.155)
		(mid 119.478223 141.331777)
		(end 119.655 141.405)
		(width 0.148)
		(layer "In2.Cu")
		(net 91)
	)
	(arc
		(start 119.925706 143.655)
		(mid 119.852483 143.831777)
		(end 119.675706 143.905)
		(width 0.148)
		(layer "In2.Cu")
		(net 91)
	)
	(arc
		(start 119.134294 141.905)
		(mid 118.957517 141.978223)
		(end 118.884294 142.155)
		(width 0.148)
		(layer "In2.Cu")
		(net 91)
	)
	(arc
		(start 119.675706 143.405)
		(mid 119.852483 143.478223)
		(end 119.925706 143.655)
		(width 0.148)
		(layer "In2.Cu")
		(net 91)
	)
	(segment
		(start 120.400001 146.2025)
		(end 120.400001 147.2775)
		(width 0.201)
		(layer "F.Cu")
		(net 92)
	)
	(segment
		(start 136.376501 166.302)
		(end 135.877001 165.8025)
		(width 0.256)
		(layer "F.Cu")
		(net 92)
	)
	(via
		(at 135.877001 165.8025)
		(size 0.45)
		(drill 0.1)
		(layers "F.Cu" "B.Cu")
		(net 92)
	)
	(via
		(at 120.400001 147.2775)
		(size 0.45)
		(drill 0.1)
		(layers "F.Cu" "B.Cu")
		(net 92)
	)
	(segment
		(start 134.375001 164.8525)
		(end 134.375001 164.6525)
		(width 0.1)
		(layer "In2.Cu")
		(net 92)
	)
	(segment
		(start 134.375001 164.6525)
		(end 133.975001 164.2525)
		(width 0.1)
		(layer "In2.Cu")
		(net 92)
	)
	(segment
		(start 129.474716 156.578569)
		(end 129.474718 156.57857)
		(width 0.148)
		(layer "In2.Cu")
		(net 92)
	)
	(segment
		(start 127.990414 155.94156)
		(end 128.414059 155.517911)
		(width 0.148)
		(layer "In2.Cu")
		(net 92)
	)
	(segment
		(start 129.474718 156.225018)
		(end 129.474717 156.225016)
		(width 0.148)
		(layer "In2.Cu")
		(net 92)
	)
	(segment
		(start 134.950001 165.4275)
		(end 134.375001 164.8525)
		(width 0.1)
		(layer "In2.Cu")
		(net 92)
	)
	(segment
		(start 129.474718 156.57857)
		(end 129.051069 157.002215)
		(width 0.148)
		(layer "In2.Cu")
		(net 92)
	)
	(segment
		(start 131.207429 158.734929)
		(end 133.375001 160.9025)
		(width 0.148)
		(layer "In2.Cu")
		(net 92)
	)
	(segment
		(start 130.888926 157.639226)
		(end 130.888925 157.639224)
		(width 0.148)
		(layer "In2.Cu")
		(net 92)
	)
	(segment
		(start 128.697518 156.648663)
		(end 128.697518 156.648664)
		(width 0.148)
		(layer "In2.Cu")
		(net 92)
	)
	(segment
		(start 127.353404 154.103703)
		(end 127.353404 154.103704)
		(width 0.148)
		(layer "In2.Cu")
		(net 92)
	)
	(segment
		(start 133.375001 160.9025)
		(end 133.375001 164.0025)
		(width 0.148)
		(layer "In2.Cu")
		(net 92)
	)
	(segment
		(start 128.06051 155.164362)
		(end 127.636861 155.588007)
		(width 0.148)
		(layer "In2.Cu")
		(net 92)
	)
	(segment
		(start 129.404622 157.355767)
		(end 129.404622 157.355768)
		(width 0.148)
		(layer "In2.Cu")
		(net 92)
	)
	(segment
		(start 128.697518 156.648664)
		(end 129.121163 156.225015)
		(width 0.148)
		(layer "In2.Cu")
		(net 92)
	)
	(segment
		(start 127.353403 154.457257)
		(end 127.353403 154.457256)
		(width 0.148)
		(layer "In2.Cu")
		(net 92)
	)
	(segment
		(start 130.888926 157.992778)
		(end 130.465277 158.416423)
		(width 0.148)
		(layer "In2.Cu")
		(net 92)
	)
	(segment
		(start 129.05107 157.355768)
		(end 129.051069 157.355768)
		(width 0.148)
		(layer "In2.Cu")
		(net 92)
	)
	(segment
		(start 130.111726 158.062872)
		(end 130.535371 157.639223)
		(width 0.148)
		(layer "In2.Cu")
		(net 92)
	)
	(segment
		(start 127.353403 154.457256)
		(end 126.929757 154.880903)
		(width 0.148)
		(layer "In2.Cu")
		(net 92)
	)
	(segment
		(start 129.404622 157.355768)
		(end 129.828267 156.932119)
		(width 0.148)
		(layer "In2.Cu")
		(net 92)
	)
	(segment
		(start 130.181822 157.285674)
		(end 129.758173 157.709319)
		(width 0.148)
		(layer "In2.Cu")
		(net 92)
	)
	(segment
		(start 120.400001 147.2775)
		(end 120.400001 147.9765)
		(width 0.148)
		(layer "In2.Cu")
		(net 92)
	)
	(segment
		(start 128.767614 155.871466)
		(end 128.343965 156.295111)
		(width 0.148)
		(layer "In2.Cu")
		(net 92)
	)
	(segment
		(start 133.625001 164.2525)
		(end 133.375001 164.0025)
		(width 0.1)
		(layer "In2.Cu")
		(net 92)
	)
	(segment
		(start 130.111726 158.062871)
		(end 130.111726 158.062872)
		(width 0.148)
		(layer "In2.Cu")
		(net 92)
	)
	(segment
		(start 128.767614 155.517914)
		(end 128.767613 155.517912)
		(width 0.148)
		(layer "In2.Cu")
		(net 92)
	)
	(segment
		(start 135.502001 165.4275)
		(end 134.950001 165.4275)
		(width 0.1)
		(layer "In2.Cu")
		(net 92)
	)
	(segment
		(start 128.06051 154.81081)
		(end 128.060509 154.810808)
		(width 0.148)
		(layer "In2.Cu")
		(net 92)
	)
	(segment
		(start 120.400001 147.9765)
		(end 119.75 148.626501)
		(width 0.148)
		(layer "In2.Cu")
		(net 92)
	)
	(segment
		(start 127.636862 155.94156)
		(end 127.636861 155.94156)
		(width 0.148)
		(layer "In2.Cu")
		(net 92)
	)
	(segment
		(start 133.975001 164.2525)
		(end 133.625001 164.2525)
		(width 0.1)
		(layer "In2.Cu")
		(net 92)
	)
	(segment
		(start 131.20743 158.734929)
		(end 131.207429 158.734929)
		(width 0.148)
		(layer "In2.Cu")
		(net 92)
	)
	(segment
		(start 130.18182 157.285673)
		(end 130.181822 157.285674)
		(width 0.148)
		(layer "In2.Cu")
		(net 92)
	)
	(segment
		(start 128.343966 156.648664)
		(end 128.343965 156.648664)
		(width 0.148)
		(layer "In2.Cu")
		(net 92)
	)
	(segment
		(start 126.929758 155.234456)
		(end 126.929757 155.234456)
		(width 0.148)
		(layer "In2.Cu")
		(net 92)
	)
	(segment
		(start 121.95 153.7)
		(end 126.172501 153.7)
		(width 0.148)
		(layer "In2.Cu")
		(net 92)
	)
	(segment
		(start 130.81883 158.769976)
		(end 130.853876 158.734929)
		(width 0.148)
		(layer "In2.Cu")
		(net 92)
	)
	(segment
		(start 135.877001 165.8025)
		(end 135.502001 165.4275)
		(width 0.1)
		(layer "In2.Cu")
		(net 92)
	)
	(segment
		(start 127.990414 155.941559)
		(end 127.990414 155.94156)
		(width 0.148)
		(layer "In2.Cu")
		(net 92)
	)
	(segment
		(start 126.172501 153.7)
		(end 126.611251 154.13875)
		(width 0.148)
		(layer "In2.Cu")
		(net 92)
	)
	(segment
		(start 126.964804 154.138749)
		(end 126.964805 154.138751)
		(width 0.148)
		(layer "In2.Cu")
		(net 92)
	)
	(segment
		(start 127.28331 155.234456)
		(end 127.706955 154.810807)
		(width 0.148)
		(layer "In2.Cu")
		(net 92)
	)
	(segment
		(start 126.964805 154.138751)
		(end 126.99985 154.103703)
		(width 0.148)
		(layer "In2.Cu")
		(net 92)
	)
	(segment
		(start 130.181822 156.932122)
		(end 130.181821 156.93212)
		(width 0.148)
		(layer "In2.Cu")
		(net 92)
	)
	(segment
		(start 130.888924 157.992777)
		(end 130.888926 157.992778)
		(width 0.148)
		(layer "In2.Cu")
		(net 92)
	)
	(segment
		(start 128.767612 155.871465)
		(end 128.767614 155.871466)
		(width 0.148)
		(layer "In2.Cu")
		(net 92)
	)
	(segment
		(start 119.75 151.5)
		(end 121.95 153.7)
		(width 0.148)
		(layer "In2.Cu")
		(net 92)
	)
	(segment
		(start 127.28331 155.234455)
		(end 127.28331 155.234456)
		(width 0.148)
		(layer "In2.Cu")
		(net 92)
	)
	(segment
		(start 129.758174 158.062872)
		(end 129.758173 158.062872)
		(width 0.148)
		(layer "In2.Cu")
		(net 92)
	)
	(segment
		(start 130.81883 158.769975)
		(end 130.81883 158.769976)
		(width 0.148)
		(layer "In2.Cu")
		(net 92)
	)
	(segment
		(start 130.465278 158.769976)
		(end 130.465277 158.769976)
		(width 0.148)
		(layer "In2.Cu")
		(net 92)
	)
	(segment
		(start 119.75 148.626501)
		(end 119.75 151.5)
		(width 0.148)
		(layer "In2.Cu")
		(net 92)
	)
	(segment
		(start 128.060508 155.164361)
		(end 128.06051 155.164362)
		(width 0.148)
		(layer "In2.Cu")
		(net 92)
	)
	(arc
		(start 127.353404 154.103704)
		(mid 127.426627 154.280481)
		(end 127.353403 154.457257)
		(width 0.148)
		(layer "In2.Cu")
		(net 92)
	)
	(arc
		(start 130.465277 158.769976)
		(mid 130.642054 158.843199)
		(end 130.81883 158.769975)
		(width 0.148)
		(layer "In2.Cu")
		(net 92)
	)
	(arc
		(start 130.535371 157.639223)
		(mid 130.71215 157.566002)
		(end 130.888926 157.639226)
		(width 0.148)
		(layer "In2.Cu")
		(net 92)
	)
	(arc
		(start 129.051069 157.002215)
		(mid 128.977846 157.178992)
		(end 129.05107 157.355768)
		(width 0.148)
		(layer "In2.Cu")
		(net 92)
	)
	(arc
		(start 129.051069 157.355768)
		(mid 129.227846 157.428991)
		(end 129.404622 157.355767)
		(width 0.148)
		(layer "In2.Cu")
		(net 92)
	)
	(arc
		(start 127.636861 155.588007)
		(mid 127.563638 155.764784)
		(end 127.636862 155.94156)
		(width 0.148)
		(layer "In2.Cu")
		(net 92)
	)
	(arc
		(start 128.767613 155.517912)
		(mid 128.840836 155.694689)
		(end 128.767612 155.871465)
		(width 0.148)
		(layer "In2.Cu")
		(net 92)
	)
	(arc
		(start 129.758173 157.709319)
		(mid 129.68495 157.886096)
		(end 129.758174 158.062872)
		(width 0.148)
		(layer "In2.Cu")
		(net 92)
	)
	(arc
		(start 127.706955 154.810807)
		(mid 127.883734 154.737586)
		(end 128.06051 154.81081)
		(width 0.148)
		(layer "In2.Cu")
		(net 92)
	)
	(arc
		(start 129.828267 156.932119)
		(mid 130.005046 156.858898)
		(end 130.181822 156.932122)
		(width 0.148)
		(layer "In2.Cu")
		(net 92)
	)
	(arc
		(start 129.758173 158.062872)
		(mid 129.93495 158.136095)
		(end 130.111726 158.062871)
		(width 0.148)
		(layer "In2.Cu")
		(net 92)
	)
	(arc
		(start 126.99985 154.103703)
		(mid 127.176627 154.03048)
		(end 127.353404 154.103703)
		(width 0.148)
		(layer "In2.Cu")
		(net 92)
	)
	(arc
		(start 129.474717 156.225016)
		(mid 129.54794 156.401793)
		(end 129.474716 156.578569)
		(width 0.148)
		(layer "In2.Cu")
		(net 92)
	)
	(arc
		(start 128.060509 154.810808)
		(mid 128.133732 154.987585)
		(end 128.060508 155.164361)
		(width 0.148)
		(layer "In2.Cu")
		(net 92)
	)
	(arc
		(start 130.888925 157.639224)
		(mid 130.962148 157.816001)
		(end 130.888924 157.992777)
		(width 0.148)
		(layer "In2.Cu")
		(net 92)
	)
	(arc
		(start 126.611251 154.13875)
		(mid 126.788028 154.211973)
		(end 126.964804 154.138749)
		(width 0.148)
		(layer "In2.Cu")
		(net 92)
	)
	(arc
		(start 128.414059 155.517911)
		(mid 128.590838 155.44469)
		(end 128.767614 155.517914)
		(width 0.148)
		(layer "In2.Cu")
		(net 92)
	)
	(arc
		(start 129.121163 156.225015)
		(mid 129.297942 156.151794)
		(end 129.474718 156.225018)
		(width 0.148)
		(layer "In2.Cu")
		(net 92)
	)
	(arc
		(start 130.853876 158.734929)
		(mid 131.030653 158.661706)
		(end 131.20743 158.734929)
		(width 0.148)
		(layer "In2.Cu")
		(net 92)
	)
	(arc
		(start 127.636861 155.94156)
		(mid 127.813638 156.014783)
		(end 127.990414 155.941559)
		(width 0.148)
		(layer "In2.Cu")
		(net 92)
	)
	(arc
		(start 126.929757 155.234456)
		(mid 127.106534 155.307679)
		(end 127.28331 155.234455)
		(width 0.148)
		(layer "In2.Cu")
		(net 92)
	)
	(arc
		(start 128.343965 156.295111)
		(mid 128.270742 156.471888)
		(end 128.343966 156.648664)
		(width 0.148)
		(layer "In2.Cu")
		(net 92)
	)
	(arc
		(start 130.465277 158.416423)
		(mid 130.392054 158.5932)
		(end 130.465278 158.769976)
		(width 0.148)
		(layer "In2.Cu")
		(net 92)
	)
	(arc
		(start 130.181821 156.93212)
		(mid 130.255044 157.108897)
		(end 130.18182 157.285673)
		(width 0.148)
		(layer "In2.Cu")
		(net 92)
	)
	(arc
		(start 126.929757 154.880903)
		(mid 126.856534 155.05768)
		(end 126.929758 155.234456)
		(width 0.148)
		(layer "In2.Cu")
		(net 92)
	)
	(arc
		(start 128.343965 156.648664)
		(mid 128.520742 156.721887)
		(end 128.697518 156.648663)
		(width 0.148)
		(layer "In2.Cu")
		(net 92)
	)
	(segment
		(start 136.376501 165.301999)
		(end 135.877002 164.8025)
		(width 0.256)
		(layer "F.Cu")
		(net 93)
	)
	(segment
		(start 120.650001 138.8025)
		(end 120.650001 139.8775)
		(width 0.201)
		(layer "F.Cu")
		(net 93)
	)
	(via
		(at 120.650001 139.8775)
		(size 0.45)
		(drill 0.1)
		(layers "F.Cu" "B.Cu")
		(net 93)
	)
	(via
		(at 135.877002 164.8025)
		(size 0.45)
		(drill 0.1)
		(layers "F.Cu" "B.Cu")
		(net 93)
	)
	(segment
		(start 134.425001 164.1025)
		(end 134.625001 164.3025)
		(width 0.1)
		(layer "In2.Cu")
		(net 93)
	)
	(segment
		(start 120.5 151.25)
		(end 122.25 153)
		(width 0.148)
		(layer "In2.Cu")
		(net 93)
	)
	(segment
		(start 120.900501 146.277)
		(end 120.900501 148.376)
		(width 0.148)
		(layer "In2.Cu")
		(net 93)
	)
	(segment
		(start 120.696343 142.71)
		(end 121.383657 142.71)
		(width 0.148)
		(layer "In2.Cu")
		(net 93)
	)
	(segment
		(start 120.5 148.776501)
		(end 120.5 151.25)
		(width 0.148)
		(layer "In2.Cu")
		(net 93)
	)
	(segment
		(start 120.419 144.831)
		(end 120.419 145.795499)
		(width 0.148)
		(layer "In2.Cu")
		(net 93)
	)
	(segment
		(start 135.525001 164.8025)
		(end 135.877002 164.8025)
		(width 0.1)
		(layer "In2.Cu")
		(net 93)
	)
	(segment
		(start 121.04 144.21)
		(end 120.419 144.831)
		(width 0.148)
		(layer "In2.Cu")
		(net 93)
	)
	(segment
		(start 134.625001 164.3025)
		(end 135.025001 164.3025)
		(width 0.1)
		(layer "In2.Cu")
		(net 93)
	)
	(segment
		(start 120.419 145.795499)
		(end 120.900501 146.277)
		(width 0.148)
		(layer "In2.Cu")
		(net 93)
	)
	(segment
		(start 135.025001 164.3025)
		(end 135.525001 164.8025)
		(width 0.1)
		(layer "In2.Cu")
		(net 93)
	)
	(segment
		(start 122.25 153)
		(end 127 153)
		(width 0.148)
		(layer "In2.Cu")
		(net 93)
	)
	(segment
		(start 121.04 140.267499)
		(end 121.04 140.96)
		(width 0.148)
		(layer "In2.Cu")
		(net 93)
	)
	(segment
		(start 121.29 141.21)
		(end 121.383657 141.21)
		(width 0.148)
		(layer "In2.Cu")
		(net 93)
	)
	(segment
		(start 121.383657 141.71)
		(end 121.29 141.71)
		(width 0.148)
		(layer "In2.Cu")
		(net 93)
	)
	(segment
		(start 121.04 143.46)
		(end 121.04 144.21)
		(width 0.148)
		(layer "In2.Cu")
		(net 93)
	)
	(segment
		(start 134.425001 160.425001)
		(end 134.425001 164.1025)
		(width 0.148)
		(layer "In2.Cu")
		(net 93)
	)
	(segment
		(start 121.29 141.71)
		(end 120.696343 141.71)
		(width 0.148)
		(layer "In2.Cu")
		(net 93)
	)
	(segment
		(start 120.696343 142.21)
		(end 121.383657 142.21)
		(width 0.148)
		(layer "In2.Cu")
		(net 93)
	)
	(segment
		(start 120.900501 148.376)
		(end 120.5 148.776501)
		(width 0.148)
		(layer "In2.Cu")
		(net 93)
	)
	(segment
		(start 127 153)
		(end 134.425001 160.425001)
		(width 0.148)
		(layer "In2.Cu")
		(net 93)
	)
	(segment
		(start 120.696343 143.21)
		(end 120.79 143.21)
		(width 0.148)
		(layer "In2.Cu")
		(net 93)
	)
	(segment
		(start 120.650001 139.8775)
		(end 121.04 140.267499)
		(width 0.148)
		(layer "In2.Cu")
		(net 93)
	)
	(arc
		(start 121.633657 141.46)
		(mid 121.560434 141.636777)
		(end 121.383657 141.71)
		(width 0.148)
		(layer "In2.Cu")
		(net 93)
	)
	(arc
		(start 120.446343 142.96)
		(mid 120.519566 143.136777)
		(end 120.696343 143.21)
		(width 0.148)
		(layer "In2.Cu")
		(net 93)
	)
	(arc
		(start 121.383657 141.21)
		(mid 121.560434 141.283223)
		(end 121.633657 141.46)
		(width 0.148)
		(layer "In2.Cu")
		(net 93)
	)
	(arc
		(start 121.04 140.96)
		(mid 121.113223 141.136777)
		(end 121.29 141.21)
		(width 0.148)
		(layer "In2.Cu")
		(net 93)
	)
	(arc
		(start 121.383657 142.21)
		(mid 121.560434 142.283223)
		(end 121.633657 142.46)
		(width 0.148)
		(layer "In2.Cu")
		(net 93)
	)
	(arc
		(start 120.696343 141.71)
		(mid 120.519566 141.783223)
		(end 120.446343 141.96)
		(width 0.148)
		(layer "In2.Cu")
		(net 93)
	)
	(arc
		(start 120.79 143.21)
		(mid 120.966777 143.283223)
		(end 121.04 143.46)
		(width 0.148)
		(layer "In2.Cu")
		(net 93)
	)
	(arc
		(start 120.696343 142.71)
		(mid 120.519566 142.783223)
		(end 120.446343 142.96)
		(width 0.148)
		(layer "In2.Cu")
		(net 93)
	)
	(arc
		(start 120.446343 141.96)
		(mid 120.519566 142.136777)
		(end 120.696343 142.21)
		(width 0.148)
		(layer "In2.Cu")
		(net 93)
	)
	(arc
		(start 121.633657 142.46)
		(mid 121.560434 142.636777)
		(end 121.383657 142.71)
		(width 0.148)
		(layer "In2.Cu")
		(net 93)
	)
	(segment
		(start 121.400001 146.2025)
		(end 121.400001 147.2775)
		(width 0.201)
		(layer "F.Cu")
		(net 94)
	)
	(segment
		(start 137.376501 167.302)
		(end 136.877001 166.8025)
		(width 0.256)
		(layer "F.Cu")
		(net 94)
	)
	(via
		(at 121.400001 147.2775)
		(size 0.45)
		(drill 0.1)
		(layers "F.Cu" "B.Cu")
		(net 94)
	)
	(via
		(at 136.877001 166.8025)
		(size 0.45)
		(drill 0.1)
		(layers "F.Cu" "B.Cu")
		(net 94)
	)
	(segment
		(start 131.587309 156.087309)
		(end 131.587311 156.087311)
		(width 0.148)
		(layer "In2.Cu")
		(net 94)
	)
	(segment
		(start 121.400001 148.6765)
		(end 121.25 148.826501)
		(width 0.148)
		(layer "In2.Cu")
		(net 94)
	)
	(segment
		(start 132.565476 156.169807)
		(end 132.565474 156.169806)
		(width 0.148)
		(layer "In2.Cu")
		(net 94)
	)
	(segment
		(start 133.08402 158.126135)
		(end 133.1783 158.031854)
		(width 0.148)
		(layer "In2.Cu")
		(net 94)
	)
	(segment
		(start 131.669806 156.71192)
		(end 131.669806 156.711921)
		(width 0.148)
		(layer "In2.Cu")
		(net 94)
	)
	(segment
		(start 130.962699 156.004814)
		(end 131.504813 155.462698)
		(width 0.148)
		(layer "In2.Cu")
		(net 94)
	)
	(segment
		(start 133.001525 157.501525)
		(end 133.10305 157.4)
		(width 0.148)
		(layer "In2.Cu")
		(net 94)
	)
	(segment
		(start 130.444155 154.048486)
		(end 130.444153 154.048485)
		(width 0.148)
		(layer "In2.Cu")
		(net 94)
	)
	(segment
		(start 134.2 158.7)
		(end 135.025 158.7)
		(width 0.148)
		(layer "In2.Cu")
		(net 94)
	)
	(segment
		(start 130.255592 155.297706)
		(end 130.255592 155.297707)
		(width 0.148)
		(layer "In2.Cu")
		(net 94)
	)
	(segment
		(start 133.531854 158.031854)
		(end 134.2 158.7)
		(width 0.148)
		(layer "In2.Cu")
		(net 94)
	)
	(segment
		(start 133.103049 157.399999)
		(end 133.103051 157.4)
		(width 0.148)
		(layer "In2.Cu")
		(net 94)
	)
	(segment
		(start 136.025001 164.3525)
		(end 135.675001 164.3525)
		(width 0.1)
		(layer "In2.Cu")
		(net 94)
	)
	(segment
		(start 129.737045 153.694931)
		(end 129.737047 153.694932)
		(width 0.148)
		(layer "In2.Cu")
		(net 94)
	)
	(segment
		(start 132.565473 156.523359)
		(end 132.565475 156.52336)
		(width 0.148)
		(layer "In2.Cu")
		(net 94)
	)
	(segment
		(start 133.103052 157.046447)
		(end 133.10305 157.046446)
		(width 0.148)
		(layer "In2.Cu")
		(net 94)
	)
	(segment
		(start 129.029938 152.987824)
		(end 129.02994 152.987825)
		(width 0.148)
		(layer "In2.Cu")
		(net 94)
	)
	(segment
		(start 133.08402 158.126134)
		(end 133.08402 158.126135)
		(width 0.148)
		(layer "In2.Cu")
		(net 94)
	)
	(segment
		(start 132.02336 157.419029)
		(end 132.02336 157.419028)
		(width 0.148)
		(layer "In2.Cu")
		(net 94)
	)
	(segment
		(start 129.029941 152.634272)
		(end 129.029939 152.634271)
		(width 0.148)
		(layer "In2.Cu")
		(net 94)
	)
	(segment
		(start 129.02994 152.987825)
		(end 128.758881 153.258881)
		(width 0.148)
		(layer "In2.Cu")
		(net 94)
	)
	(segment
		(start 122.45 152.2)
		(end 127.7 152.2)
		(width 0.148)
		(layer "In2.Cu")
		(net 94)
	)
	(segment
		(start 131.316253 156.711922)
		(end 131.316253 156.711921)
		(width 0.148)
		(layer "In2.Cu")
		(net 94)
	)
	(segment
		(start 129.548485 154.5906)
		(end 130.090599 154.048484)
		(width 0.148)
		(layer "In2.Cu")
		(net 94)
	)
	(segment
		(start 127.875 152.728553)
		(end 127.780719 152.822833)
		(width 0.148)
		(layer "In2.Cu")
		(net 94)
	)
	(segment
		(start 130.444152 154.402038)
		(end 130.444154 154.402039)
		(width 0.148)
		(layer "In2.Cu")
		(net 94)
	)
	(segment
		(start 132.565475 156.52336)
		(end 132.294416 156.794416)
		(width 0.148)
		(layer "In2.Cu")
		(net 94)
	)
	(segment
		(start 128.134272 153.176386)
		(end 128.134272 153.176387)
		(width 0.148)
		(layer "In2.Cu")
		(net 94)
	)
	(segment
		(start 130.880202 155.380202)
		(end 130.880204 155.380204)
		(width 0.148)
		(layer "In2.Cu")
		(net 94)
	)
	(segment
		(start 121.25 148.826501)
		(end 121.25 151)
		(width 0.148)
		(layer "In2.Cu")
		(net 94)
	)
	(segment
		(start 129.46599 153.96599)
		(end 129.194932 154.237047)
		(width 0.148)
		(layer "In2.Cu")
		(net 94)
	)
	(segment
		(start 121.25 151)
		(end 122.45 152.2)
		(width 0.148)
		(layer "In2.Cu")
		(net 94)
	)
	(segment
		(start 128.758881 153.258881)
		(end 128.758883 153.258883)
		(width 0.148)
		(layer "In2.Cu")
		(net 94)
	)
	(segment
		(start 131.669806 156.711921)
		(end 132.21192 156.169805)
		(width 0.148)
		(layer "In2.Cu")
		(net 94)
	)
	(segment
		(start 128.134272 153.176387)
		(end 128.676385 152.63427)
		(width 0.148)
		(layer "In2.Cu")
		(net 94)
	)
	(segment
		(start 136.425001 166.3505)
		(end 136.425001 164.7525)
		(width 0.1)
		(layer "In2.Cu")
		(net 94)
	)
	(segment
		(start 128.758883 153.258883)
		(end 128.487825 153.52994)
		(width 0.148)
		(layer "In2.Cu")
		(net 94)
	)
	(segment
		(start 129.902039 155.297708)
		(end 129.902039 155.297707)
		(width 0.148)
		(layer "In2.Cu")
		(net 94)
	)
	(segment
		(start 129.194932 154.590601)
		(end 129.194932 154.5906)
		(width 0.148)
		(layer "In2.Cu")
		(net 94)
	)
	(segment
		(start 131.858366 155.816252)
		(end 131.858368 155.816253)
		(width 0.148)
		(layer "In2.Cu")
		(net 94)
	)
	(segment
		(start 131.151262 154.755593)
		(end 131.15126 154.755592)
		(width 0.148)
		(layer "In2.Cu")
		(net 94)
	)
	(segment
		(start 135.025 158.7)
		(end 135.375001 159.050001)
		(width 0.148)
		(layer "In2.Cu")
		(net 94)
	)
	(segment
		(start 127.7 152.2)
		(end 127.875 152.375)
		(width 0.148)
		(layer "In2.Cu")
		(net 94)
	)
	(segment
		(start 132.294418 156.794418)
		(end 132.02336 157.065475)
		(width 0.148)
		(layer "In2.Cu")
		(net 94)
	)
	(segment
		(start 130.609146 156.004815)
		(end 130.609146 156.004814)
		(width 0.148)
		(layer "In2.Cu")
		(net 94)
	)
	(segment
		(start 128.841378 153.883493)
		(end 129.383492 153.341377)
		(width 0.148)
		(layer "In2.Cu")
		(net 94)
	)
	(segment
		(start 130.962699 156.004813)
		(end 130.962699 156.004814)
		(width 0.148)
		(layer "In2.Cu")
		(net 94)
	)
	(segment
		(start 129.548485 154.590599)
		(end 129.548485 154.5906)
		(width 0.148)
		(layer "In2.Cu")
		(net 94)
	)
	(segment
		(start 128.841378 153.883492)
		(end 128.841378 153.883493)
		(width 0.148)
		(layer "In2.Cu")
		(net 94)
	)
	(segment
		(start 130.880204 155.380204)
		(end 130.609146 155.651261)
		(width 0.148)
		(layer "In2.Cu")
		(net 94)
	)
	(segment
		(start 133.001525 157.501525)
		(end 132.730467 157.772582)
		(width 0.148)
		(layer "In2.Cu")
		(net 94)
	)
	(segment
		(start 131.151261 155.109146)
		(end 130.880202 155.380202)
		(width 0.148)
		(layer "In2.Cu")
		(net 94)
	)
	(segment
		(start 130.173097 154.673097)
		(end 129.902039 154.944154)
		(width 0.148)
		(layer "In2.Cu")
		(net 94)
	)
	(segment
		(start 135.375001 159.050001)
		(end 135.375001 164.0525)
		(width 0.148)
		(layer "In2.Cu")
		(net 94)
	)
	(segment
		(start 135.675001 164.3525)
		(end 135.375001 164.0525)
		(width 0.1)
		(layer "In2.Cu")
		(net 94)
	)
	(segment
		(start 131.587311 156.087311)
		(end 131.316253 156.358368)
		(width 0.148)
		(layer "In2.Cu")
		(net 94)
	)
	(segment
		(start 127.874999 152.728553)
		(end 127.875 152.728553)
		(width 0.148)
		(layer "In2.Cu")
		(net 94)
	)
	(segment
		(start 121.400001 147.2775)
		(end 121.400001 148.6765)
		(width 0.148)
		(layer "In2.Cu")
		(net 94)
	)
	(segment
		(start 132.294416 156.794416)
		(end 132.294418 156.794418)
		(width 0.148)
		(layer "In2.Cu")
		(net 94)
	)
	(segment
		(start 131.858368 155.816253)
		(end 131.587309 156.087309)
		(width 0.148)
		(layer "In2.Cu")
		(net 94)
	)
	(segment
		(start 131.151259 155.109145)
		(end 131.151261 155.109146)
		(width 0.148)
		(layer "In2.Cu")
		(net 94)
	)
	(segment
		(start 130.444154 154.402039)
		(end 130.173095 154.673095)
		(width 0.148)
		(layer "In2.Cu")
		(net 94)
	)
	(segment
		(start 130.173095 154.673095)
		(end 130.173097 154.673097)
		(width 0.148)
		(layer "In2.Cu")
		(net 94)
	)
	(segment
		(start 132.749496 157.046445)
		(end 132.376913 157.419027)
		(width 0.148)
		(layer "In2.Cu")
		(net 94)
	)
	(segment
		(start 129.737047 153.694932)
		(end 129.465988 153.965988)
		(width 0.148)
		(layer "In2.Cu")
		(net 94)
	)
	(segment
		(start 128.487825 153.883494)
		(end 128.487825 153.883493)
		(width 0.148)
		(layer "In2.Cu")
		(net 94)
	)
	(segment
		(start 131.858369 155.4627)
		(end 131.858367 155.462699)
		(width 0.148)
		(layer "In2.Cu")
		(net 94)
	)
	(segment
		(start 136.877001 166.8025)
		(end 136.425001 166.3505)
		(width 0.1)
		(layer "In2.Cu")
		(net 94)
	)
	(segment
		(start 136.425001 164.7525)
		(end 136.025001 164.3525)
		(width 0.1)
		(layer "In2.Cu")
		(net 94)
	)
	(segment
		(start 129.465988 153.965988)
		(end 129.46599 153.96599)
		(width 0.148)
		(layer "In2.Cu")
		(net 94)
	)
	(segment
		(start 130.255592 155.297707)
		(end 130.797706 154.755591)
		(width 0.148)
		(layer "In2.Cu")
		(net 94)
	)
	(segment
		(start 132.730467 158.126136)
		(end 132.730467 158.126135)
		(width 0.148)
		(layer "In2.Cu")
		(net 94)
	)
	(segment
		(start 129.737048 153.341379)
		(end 129.737046 153.341378)
		(width 0.148)
		(layer "In2.Cu")
		(net 94)
	)
	(arc
		(start 131.316253 156.358368)
		(mid 131.24303 156.535145)
		(end 131.316253 156.711922)
		(width 0.148)
		(layer "In2.Cu")
		(net 94)
	)
	(arc
		(start 128.487825 153.883493)
		(mid 128.664602 153.956716)
		(end 128.841378 153.883492)
		(width 0.148)
		(layer "In2.Cu")
		(net 94)
	)
	(arc
		(start 132.02336 157.419028)
		(mid 132.200137 157.492251)
		(end 132.376913 157.419027)
		(width 0.148)
		(layer "In2.Cu")
		(net 94)
	)
	(arc
		(start 129.383492 153.341377)
		(mid 129.560271 153.268156)
		(end 129.737048 153.341379)
		(width 0.148)
		(layer "In2.Cu")
		(net 94)
	)
	(arc
		(start 132.730467 157.772582)
		(mid 132.657244 157.949359)
		(end 132.730467 158.126136)
		(width 0.148)
		(layer "In2.Cu")
		(net 94)
	)
	(arc
		(start 130.609146 155.651261)
		(mid 130.535923 155.828038)
		(end 130.609146 156.004815)
		(width 0.148)
		(layer "In2.Cu")
		(net 94)
	)
	(arc
		(start 130.090599 154.048484)
		(mid 130.267378 153.975263)
		(end 130.444155 154.048486)
		(width 0.148)
		(layer "In2.Cu")
		(net 94)
	)
	(arc
		(start 127.875 152.375)
		(mid 127.948223 152.551777)
		(end 127.874999 152.728553)
		(width 0.148)
		(layer "In2.Cu")
		(net 94)
	)
	(arc
		(start 132.02336 157.065475)
		(mid 131.950137 157.242252)
		(end 132.02336 157.419029)
		(width 0.148)
		(layer "In2.Cu")
		(net 94)
	)
	(arc
		(start 132.749496 157.046445)
		(mid 132.926275 156.973224)
		(end 133.103052 157.046447)
		(width 0.148)
		(layer "In2.Cu")
		(net 94)
	)
	(arc
		(start 132.565474 156.169806)
		(mid 132.638697 156.346583)
		(end 132.565473 156.523359)
		(width 0.148)
		(layer "In2.Cu")
		(net 94)
	)
	(arc
		(start 129.194932 154.5906)
		(mid 129.371709 154.663823)
		(end 129.548485 154.590599)
		(width 0.148)
		(layer "In2.Cu")
		(net 94)
	)
	(arc
		(start 127.780719 153.176387)
		(mid 127.957496 153.24961)
		(end 128.134272 153.176386)
		(width 0.148)
		(layer "In2.Cu")
		(net 94)
	)
	(arc
		(start 128.487825 153.52994)
		(mid 128.414602 153.706717)
		(end 128.487825 153.883494)
		(width 0.148)
		(layer "In2.Cu")
		(net 94)
	)
	(arc
		(start 133.1783 158.031854)
		(mid 133.355077 157.958631)
		(end 133.531854 158.031854)
		(width 0.148)
		(layer "In2.Cu")
		(net 94)
	)
	(arc
		(start 132.730467 158.126135)
		(mid 132.907244 158.199358)
		(end 133.08402 158.126134)
		(width 0.148)
		(layer "In2.Cu")
		(net 94)
	)
	(arc
		(start 132.21192 156.169805)
		(mid 132.388699 156.096584)
		(end 132.565476 156.169807)
		(width 0.148)
		(layer "In2.Cu")
		(net 94)
	)
	(arc
		(start 130.444153 154.048485)
		(mid 130.517376 154.225262)
		(end 130.444152 154.402038)
		(width 0.148)
		(layer "In2.Cu")
		(net 94)
	)
	(arc
		(start 131.858367 155.462699)
		(mid 131.93159 155.639476)
		(end 131.858366 155.816252)
		(width 0.148)
		(layer "In2.Cu")
		(net 94)
	)
	(arc
		(start 127.780719 152.822833)
		(mid 127.707496 152.99961)
		(end 127.780719 153.176387)
		(width 0.148)
		(layer "In2.Cu")
		(net 94)
	)
	(arc
		(start 129.902039 155.297707)
		(mid 130.078816 155.37093)
		(end 130.255592 155.297706)
		(width 0.148)
		(layer "In2.Cu")
		(net 94)
	)
	(arc
		(start 128.676385 152.63427)
		(mid 128.853164 152.561049)
		(end 129.029941 152.634272)
		(width 0.148)
		(layer "In2.Cu")
		(net 94)
	)
	(arc
		(start 130.797706 154.755591)
		(mid 130.974485 154.68237)
		(end 131.151262 154.755593)
		(width 0.148)
		(layer "In2.Cu")
		(net 94)
	)
	(arc
		(start 129.902039 154.944154)
		(mid 129.828816 155.120931)
		(end 129.902039 155.297708)
		(width 0.148)
		(layer "In2.Cu")
		(net 94)
	)
	(arc
		(start 130.609146 156.004814)
		(mid 130.785923 156.078037)
		(end 130.962699 156.004813)
		(width 0.148)
		(layer "In2.Cu")
		(net 94)
	)
	(arc
		(start 129.737046 153.341378)
		(mid 129.810269 153.518155)
		(end 129.737045 153.694931)
		(width 0.148)
		(layer "In2.Cu")
		(net 94)
	)
	(arc
		(start 131.15126 154.755592)
		(mid 131.224483 154.932369)
		(end 131.151259 155.109145)
		(width 0.148)
		(layer "In2.Cu")
		(net 94)
	)
	(arc
		(start 129.029939 152.634271)
		(mid 129.103162 152.811048)
		(end 129.029938 152.987824)
		(width 0.148)
		(layer "In2.Cu")
		(net 94)
	)
	(arc
		(start 129.194932 154.237047)
		(mid 129.121709 154.413824)
		(end 129.194932 154.590601)
		(width 0.148)
		(layer "In2.Cu")
		(net 94)
	)
	(arc
		(start 131.504813 155.462698)
		(mid 131.681592 155.389477)
		(end 131.858369 155.4627)
		(width 0.148)
		(layer "In2.Cu")
		(net 94)
	)
	(arc
		(start 131.316253 156.711921)
		(mid 131.49303 156.785144)
		(end 131.669806 156.71192)
		(width 0.148)
		(layer "In2.Cu")
		(net 94)
	)
	(arc
		(start 133.10305 157.046446)
		(mid 133.176273 157.223223)
		(end 133.103049 157.399999)
		(width 0.148)
		(layer "In2.Cu")
		(net 94)
	)
	(segment
		(start 121.670001 139.4225)
		(end 121.67 139.892427)
		(width 0.26)
		(layer "F.Cu")
		(net 95)
	)
	(segment
		(start 121.650001 139.4025)
		(end 121.670001 139.4225)
		(width 0.26)
		(layer "F.Cu")
		(net 95)
	)
	(segment
		(start 121.650001 138.8025)
		(end 121.650001 139.4025)
		(width 0.26)
		(layer "F.Cu")
		(net 95)
	)
	(segment
		(start 121.67 139.892427)
		(end 121.625001 139.937426)
		(width 0.26)
		(layer "F.Cu")
		(net 95)
	)
	(segment
		(start 136.376501 168.302)
		(end 135.877001 167.8025)
		(width 0.256)
		(layer "F.Cu")
		(net 95)
	)
	(via
		(at 135.877001 167.8025)
		(size 0.45)
		(drill 0.1)
		(layers "F.Cu" "B.Cu")
		(net 95)
	)
	(via
		(at 121.625001 139.937426)
		(size 0.45)
		(drill 0.1)
		(layers "F.Cu" "B.Cu")
		(net 95)
	)
	(segment
		(start 134.714472 156.504853)
		(end 134.714472 156.504852)
		(width 0.13)
		(layer "In2.Cu")
		(net 95)
	)
	(segment
		(start 134.798149 158.25965)
		(end 134.798149 158.259651)
		(width 0.13)
		(layer "In2.Cu")
		(net 95)
	)
	(segment
		(start 137.275001 164.593922)
		(end 137.083579 164.4025)
		(width 0.1)
		(layer "In2.Cu")
		(net 95)
	)
	(segment
		(start 136.275001 164.043922)
		(end 136.275001 161.199387)
		(width 0.1)
		(layer "In2.Cu")
		(net 95)
	)
	(segment
		(start 137.275001 167.011078)
		(end 137.275001 164.593922)
		(width 0.1)
		(layer "In2.Cu")
		(net 95)
	)
	(segment
		(start 135.877001 167.8025)
		(end 136.175001 167.8025)
		(width 0.1)
		(layer "In2.Cu")
		(net 95)
	)
	(segment
		(start 135.464003 157.88371)
		(end 135.464003 157.883709)
		(width 0.13)
		(layer "In2.Cu")
		(net 95)
	)
	(segment
		(start 136.260779 158.680485)
		(end 136.260779 159.380779)
		(width 0.13)
		(layer "In2.Cu")
		(net 95)
	)
	(segment
		(start 136.277001 167.426788)
		(end 136.501289 167.2025)
		(width 0.1)
		(layer "In2.Cu")
		(net 95)
	)
	(segment
		(start 122.291591 141.010085)
		(end 122.291591 145.529915)
		(width 0.1)
		(layer "In2.Cu")
		(net 95)
	)
	(segment
		(start 136.085779 159.555779)
		(end 136.074919 159.555779)
		(width 0.13)
		(layer "In2.Cu")
		(net 95)
	)
	(segment
		(start 123.060294 151.52)
		(end 129.100294 151.52)
		(width 0.13)
		(layer "In2.Cu")
		(net 95)
	)
	(segment
		(start 121.794904 146.026602)
		(end 121.794904 149.385096)
		(width 0.1)
		(layer "In2.Cu")
		(net 95)
	)
	(segment
		(start 136.277001 167.7005)
		(end 136.277001 167.426788)
		(width 0.1)
		(layer "In2.Cu")
		(net 95)
	)
	(segment
		(start 121.794904 149.385096)
		(end 121.78 149.4)
		(width 0.1)
		(layer "In2.Cu")
		(net 95)
	)
	(segment
		(start 121.78 149.4)
		(end 121.78 150.239706)
		(width 0.13)
		(layer "In2.Cu")
		(net 95)
	)
	(segment
		(start 135.132839 156.666311)
		(end 134.168824 157.630325)
		(width 0.13)
		(layer "In2.Cu")
		(net 95)
	)
	(segment
		(start 136.175001 167.8025)
		(end 136.277001 167.7005)
		(width 0.1)
		(layer "In2.Cu")
		(net 95)
	)
	(segment
		(start 121.78 150.239706)
		(end 123.060294 151.52)
		(width 0.13)
		(layer "In2.Cu")
		(net 95)
	)
	(segment
		(start 121.795001 140.513495)
		(end 122.291591 141.010085)
		(width 0.1)
		(layer "In2.Cu")
		(net 95)
	)
	(segment
		(start 136.074919 159.905779)
		(end 136.085779 159.905779)
		(width 0.13)
		(layer "In2.Cu")
		(net 95)
	)
	(segment
		(start 134.168823 158.25965)
		(end 134.168824 158.259651)
		(width 0.13)
		(layer "In2.Cu")
		(net 95)
	)
	(segment
		(start 121.795001 140.107426)
		(end 121.795001 140.513495)
		(width 0.1)
		(layer "In2.Cu")
		(net 95)
	)
	(segment
		(start 129.100294 151.52)
		(end 134.085146 156.504851)
		(width 0.13)
		(layer "In2.Cu")
		(net 95)
	)
	(segment
		(start 136.633579 164.4025)
		(end 136.275001 164.043922)
		(width 0.1)
		(layer "In2.Cu")
		(net 95)
	)
	(segment
		(start 136.275001 161.199387)
		(end 136.260779 161.185165)
		(width 0.1)
		(layer "In2.Cu")
		(net 95)
	)
	(segment
		(start 136.501289 167.2025)
		(end 137.083579 167.2025)
		(width 0.1)
		(layer "In2.Cu")
		(net 95)
	)
	(segment
		(start 135.132839 156.666312)
		(end 135.132839 156.666311)
		(width 0.13)
		(layer "In2.Cu")
		(net 95)
	)
	(segment
		(start 135.464003 157.883709)
		(end 136.260779 158.680485)
		(width 0.13)
		(layer "In2.Cu")
		(net 95)
	)
	(segment
		(start 122.291591 145.529915)
		(end 121.794904 146.026602)
		(width 0.1)
		(layer "In2.Cu")
		(net 95)
	)
	(segment
		(start 134.798149 158.259651)
		(end 135.17409 157.883709)
		(width 0.13)
		(layer "In2.Cu")
		(net 95)
	)
	(segment
		(start 121.625001 139.937426)
		(end 121.795001 140.107426)
		(width 0.1)
		(layer "In2.Cu")
		(net 95)
	)
	(segment
		(start 136.260779 160.080779)
		(end 136.260779 161.185165)
		(width 0.13)
		(layer "In2.Cu")
		(net 95)
	)
	(segment
		(start 137.083579 164.4025)
		(end 136.633579 164.4025)
		(width 0.1)
		(layer "In2.Cu")
		(net 95)
	)
	(segment
		(start 137.083579 167.2025)
		(end 137.275001 167.011078)
		(width 0.1)
		(layer "In2.Cu")
		(net 95)
	)
	(segment
		(start 134.714472 156.504852)
		(end 134.842926 156.376399)
		(width 0.13)
		(layer "In2.Cu")
		(net 95)
	)
	(arc
		(start 134.168824 157.630325)
		(mid 134.038486 157.944987)
		(end 134.168823 158.25965)
		(width 0.13)
		(layer "In2.Cu")
		(net 95)
	)
	(arc
		(start 136.260779 159.380779)
		(mid 136.209523 159.504523)
		(end 136.085779 159.555779)
		(width 0.13)
		(layer "In2.Cu")
		(net 95)
	)
	(arc
		(start 136.074919 159.555779)
		(mid 135.951175 159.607035)
		(end 135.899919 159.730779)
		(width 0.13)
		(layer "In2.Cu")
		(net 95)
	)
	(arc
		(start 135.13284 156.376399)
		(mid 135.192881 156.521355)
		(end 135.132839 156.666312)
		(width 0.13)
		(layer "In2.Cu")
		(net 95)
	)
	(arc
		(start 135.17409 157.883709)
		(mid 135.319047 157.823667)
		(end 135.464003 157.88371)
		(width 0.13)
		(layer "In2.Cu")
		(net 95)
	)
	(arc
		(start 134.085146 156.504851)
		(mid 134.399809 156.635189)
		(end 134.714472 156.504853)
		(width 0.13)
		(layer "In2.Cu")
		(net 95)
	)
	(arc
		(start 135.899919 159.730779)
		(mid 135.951175 159.854523)
		(end 136.074919 159.905779)
		(width 0.13)
		(layer "In2.Cu")
		(net 95)
	)
	(arc
		(start 136.085779 159.905779)
		(mid 136.209523 159.957035)
		(end 136.260779 160.080779)
		(width 0.13)
		(layer "In2.Cu")
		(net 95)
	)
	(arc
		(start 134.168824 158.259651)
		(mid 134.483487 158.389988)
		(end 134.798149 158.25965)
		(width 0.13)
		(layer "In2.Cu")
		(net 95)
	)
	(arc
		(start 134.842926 156.376399)
		(mid 134.987883 156.316356)
		(end 135.13284 156.376399)
		(width 0.13)
		(layer "In2.Cu")
		(net 95)
	)
	(segment
		(start 137.376501 168.302)
		(end 136.877001 167.8025)
		(width 0.256)
		(layer "F.Cu")
		(net 96)
	)
	(segment
		(start 122.130001 139.4225)
		(end 122.130002 139.892427)
		(width 0.26)
		(layer "F.Cu")
		(net 96)
	)
	(segment
		(start 122.150001 138.8025)
		(end 122.150001 139.4025)
		(width 0.26)
		(layer "F.Cu")
		(net 96)
	)
	(segment
		(start 122.150001 139.4025)
		(end 122.130001 139.4225)
		(width 0.26)
		(layer "F.Cu")
		(net 96)
	)
	(segment
		(start 122.130002 139.892427)
		(end 122.175001 139.937426)
		(width 0.26)
		(layer "F.Cu")
		(net 96)
	)
	(via
		(at 122.175001 139.937426)
		(size 0.45)
		(drill 0.1)
		(layers "F.Cu" "B.Cu")
		(net 96)
	)
	(via
		(at 136.877001 167.8025)
		(size 0.45)
		(drill 0.1)
		(layers "F.Cu" "B.Cu")
		(net 96)
	)
	(segment
		(start 134.338529 158.089944)
		(end 134.33853 158.089945)
		(width 0.13)
		(layer "In2.Cu")
		(net 96)
	)
	(segment
		(start 136.716423 164.2025)
		(end 136.475001 163.961078)
		(width 0.1)
		(layer "In2.Cu")
		(net 96)
	)
	(segment
		(start 136.500779 158.581073)
		(end 136.500779 161.185165)
		(width 0.13)
		(layer "In2.Cu")
		(net 96)
	)
	(segment
		(start 122.005001 140.426507)
		(end 122.005001 140.107426)
		(width 0.1)
		(layer "In2.Cu")
		(net 96)
	)
	(segment
		(start 129.199706 151.28)
		(end 134.254851 156.335146)
		(width 0.13)
		(layer "In2.Cu")
		(net 96)
	)
	(segment
		(start 137.166423 167.4025)
		(end 137.475001 167.093922)
		(width 0.1)
		(layer "In2.Cu")
		(net 96)
	)
	(segment
		(start 122.02 149.4)
		(end 122.02 150.140294)
		(width 0.13)
		(layer "In2.Cu")
		(net 96)
	)
	(segment
		(start 136.477001 167.509632)
		(end 136.584133 167.4025)
		(width 0.1)
		(layer "In2.Cu")
		(net 96)
	)
	(segment
		(start 122.501591 145.616903)
		(end 122.004904 146.11359)
		(width 0.1)
		(layer "In2.Cu")
		(net 96)
	)
	(segment
		(start 136.584133 167.4025)
		(end 137.166423 167.4025)
		(width 0.1)
		(layer "In2.Cu")
		(net 96)
	)
	(segment
		(start 134.628443 158.089944)
		(end 134.628443 158.089945)
		(width 0.13)
		(layer "In2.Cu")
		(net 96)
	)
	(segment
		(start 122.004904 149.384904)
		(end 122.02 149.4)
		(width 0.1)
		(layer "In2.Cu")
		(net 96)
	)
	(segment
		(start 122.02 150.140294)
		(end 123.159706 151.28)
		(width 0.13)
		(layer "In2.Cu")
		(net 96)
	)
	(segment
		(start 135.302544 156.206692)
		(end 135.302545 156.206694)
		(width 0.13)
		(layer "In2.Cu")
		(net 96)
	)
	(segment
		(start 136.575001 167.8025)
		(end 136.477001 167.7045)
		(width 0.1)
		(layer "In2.Cu")
		(net 96)
	)
	(segment
		(start 135.302544 156.836019)
		(end 135.302544 156.836018)
		(width 0.13)
		(layer "In2.Cu")
		(net 96)
	)
	(segment
		(start 137.166423 164.2025)
		(end 136.716423 164.2025)
		(width 0.1)
		(layer "In2.Cu")
		(net 96)
	)
	(segment
		(start 136.877001 167.8025)
		(end 136.575001 167.8025)
		(width 0.1)
		(layer "In2.Cu")
		(net 96)
	)
	(segment
		(start 122.005001 140.426507)
		(end 122.501591 140.923097)
		(width 0.1)
		(layer "In2.Cu")
		(net 96)
	)
	(segment
		(start 134.944281 157.194282)
		(end 134.94428 157.19428)
		(width 0.13)
		(layer "In2.Cu")
		(net 96)
	)
	(segment
		(start 136.475001 161.210943)
		(end 136.500779 161.185165)
		(width 0.1)
		(layer "In2.Cu")
		(net 96)
	)
	(segment
		(start 137.475001 167.093922)
		(end 137.475001 164.511078)
		(width 0.1)
		(layer "In2.Cu")
		(net 96)
	)
	(segment
		(start 122.005001 140.107426)
		(end 122.175001 139.937426)
		(width 0.1)
		(layer "In2.Cu")
		(net 96)
	)
	(segment
		(start 122.004904 146.11359)
		(end 122.004904 149.384904)
		(width 0.1)
		(layer "In2.Cu")
		(net 96)
	)
	(segment
		(start 136.477001 167.7045)
		(end 136.477001 167.509632)
		(width 0.1)
		(layer "In2.Cu")
		(net 96)
	)
	(segment
		(start 136.475001 163.961078)
		(end 136.475001 161.210943)
		(width 0.1)
		(layer "In2.Cu")
		(net 96)
	)
	(segment
		(start 134.94428 157.19428)
		(end 134.33853 157.800031)
		(width 0.13)
		(layer "In2.Cu")
		(net 96)
	)
	(segment
		(start 134.544767 156.335148)
		(end 134.673219 156.206693)
		(width 0.13)
		(layer "In2.Cu")
		(net 96)
	)
	(segment
		(start 122.501591 140.923097)
		(end 122.501591 145.616903)
		(width 0.1)
		(layer "In2.Cu")
		(net 96)
	)
	(segment
		(start 135.302544 156.836018)
		(end 134.944281 157.194282)
		(width 0.13)
		(layer "In2.Cu")
		(net 96)
	)
	(segment
		(start 135.633709 157.714003)
		(end 136.500779 158.581073)
		(width 0.13)
		(layer "In2.Cu")
		(net 96)
	)
	(segment
		(start 134.628443 158.089945)
		(end 135.004384 157.714003)
		(width 0.13)
		(layer "In2.Cu")
		(net 96)
	)
	(segment
		(start 123.159706 151.28)
		(end 129.199706 151.28)
		(width 0.13)
		(layer "In2.Cu")
		(net 96)
	)
	(segment
		(start 137.475001 164.511078)
		(end 137.166423 164.2025)
		(width 0.1)
		(layer "In2.Cu")
		(net 96)
	)
	(segment
		(start 135.633709 157.714004)
		(end 135.633709 157.714003)
		(width 0.13)
		(layer "In2.Cu")
		(net 96)
	)
	(arc
		(start 134.33853 158.089945)
		(mid 134.483487 158.149987)
		(end 134.628443 158.089944)
		(width 0.13)
		(layer "In2.Cu")
		(net 96)
	)
	(arc
		(start 134.254851 156.335146)
		(mid 134.39981 156.395191)
		(end 134.544767 156.335148)
		(width 0.13)
		(layer "In2.Cu")
		(net 96)
	)
	(arc
		(start 134.33853 157.800031)
		(mid 134.278487 157.944987)
		(end 134.338529 158.089944)
		(width 0.13)
		(layer "In2.Cu")
		(net 96)
	)
	(arc
		(start 134.673219 156.206693)
		(mid 134.987881 156.076355)
		(end 135.302544 156.206692)
		(width 0.13)
		(layer "In2.Cu")
		(net 96)
	)
	(arc
		(start 135.004384 157.714003)
		(mid 135.319047 157.583666)
		(end 135.633709 157.714004)
		(width 0.13)
		(layer "In2.Cu")
		(net 96)
	)
	(arc
		(start 135.302545 156.206694)
		(mid 135.432882 156.521357)
		(end 135.302544 156.836019)
		(width 0.13)
		(layer "In2.Cu")
		(net 96)
	)
	(segment
		(start 122.400001 146.2025)
		(end 122.400001 147.2775)
		(width 0.201)
		(layer "F.Cu")
		(net 97)
	)
	(segment
		(start 138.376501 164.302)
		(end 137.877001 163.8025)
		(width 0.256)
		(layer "F.Cu")
		(net 97)
	)
	(via
		(at 137.877001 163.8025)
		(size 0.45)
		(drill 0.1)
		(layers "F.Cu" "B.Cu")
		(net 97)
	)
	(via
		(at 122.400001 147.2775)
		(size 0.45)
		(drill 0.1)
		(layers "F.Cu" "B.Cu")
		(net 97)
	)
	(segment
		(start 134.404665 155.43417)
		(end 134.404665 155.434171)
		(width 0.148)
		(layer "In2.Cu")
		(net 97)
	)
	(segment
		(start 131.752189 151.36913)
		(end 131.75219 151.369131)
		(width 0.148)
		(layer "In2.Cu")
		(net 97)
	)
	(segment
		(start 133.87351 153.844004)
		(end 133.344005 154.37351)
		(width 0.148)
		(layer "In2.Cu")
		(net 97)
	)
	(segment
		(start 133.344004 154.727063)
		(end 133.344005 154.727064)
		(width 0.148)
		(layer "In2.Cu")
		(net 97)
	)
	(segment
		(start 130.603554 150.750001)
		(end 130.691529 150.662023)
		(width 0.148)
		(layer "In2.Cu")
		(net 97)
	)
	(segment
		(start 132.990451 154.019956)
		(end 132.990451 154.019957)
		(width 0.148)
		(layer "In2.Cu")
		(net 97)
	)
	(segment
		(start 133.166403 153.136898)
		(end 133.166403 153.136897)
		(width 0.148)
		(layer "In2.Cu")
		(net 97)
	)
	(segment
		(start 131.045082 151.015576)
		(end 130.515577 151.545082)
		(width 0.148)
		(layer "In2.Cu")
		(net 97)
	)
	(segment
		(start 132.636897 154.019956)
		(end 132.636898 154.019957)
		(width 0.148)
		(layer "In2.Cu")
		(net 97)
	)
	(segment
		(start 133.87351 153.844005)
		(end 133.87351 153.844004)
		(width 0.148)
		(layer "In2.Cu")
		(net 97)
	)
	(segment
		(start 134.580617 154.197558)
		(end 134.580618 154.197559)
		(width 0.148)
		(layer "In2.Cu")
		(net 97)
	)
	(segment
		(start 134.846194 155.346194)
		(end 137.375001 157.875001)
		(width 0.148)
		(layer "In2.Cu")
		(net 97)
	)
	(segment
		(start 131.752189 151.722684)
		(end 131.752189 151.722683)
		(width 0.148)
		(layer "In2.Cu")
		(net 97)
	)
	(segment
		(start 132.990451 154.019957)
		(end 133.519955 153.49045)
		(width 0.148)
		(layer "In2.Cu")
		(net 97)
	)
	(segment
		(start 134.580617 154.551112)
		(end 134.580617 154.551111)
		(width 0.148)
		(layer "In2.Cu")
		(net 97)
	)
	(segment
		(start 131.752189 151.722683)
		(end 131.222684 152.252189)
		(width 0.148)
		(layer "In2.Cu")
		(net 97)
	)
	(segment
		(start 131.576237 152.605743)
		(end 132.105741 152.076236)
		(width 0.148)
		(layer "In2.Cu")
		(net 97)
	)
	(segment
		(start 122.400001 147.2775)
		(end 122.400001 148.7755)
		(width 0.148)
		(layer "In2.Cu")
		(net 97)
	)
	(segment
		(start 130.100501 150.600501)
		(end 130.25 150.75)
		(width 0.148)
		(layer "In2.Cu")
		(net 97)
	)
	(segment
		(start 132.459296 152.42979)
		(end 131.929791 152.959296)
		(width 0.148)
		(layer "In2.Cu")
		(net 97)
	)
	(segment
		(start 130.86913 151.898636)
		(end 131.398634 151.369129)
		(width 0.148)
		(layer "In2.Cu")
		(net 97)
	)
	(segment
		(start 134.846194 155.346195)
		(end 134.846194 155.346194)
		(width 0.148)
		(layer "In2.Cu")
		(net 97)
	)
	(segment
		(start 132.283344 153.312849)
		(end 132.283344 153.31285)
		(width 0.148)
		(layer "In2.Cu")
		(net 97)
	)
	(segment
		(start 133.697558 154.727063)
		(end 133.697558 154.727064)
		(width 0.148)
		(layer "In2.Cu")
		(net 97)
	)
	(segment
		(start 130.603553 150.749999)
		(end 130.603554 150.750001)
		(width 0.148)
		(layer "In2.Cu")
		(net 97)
	)
	(segment
		(start 132.459296 152.429791)
		(end 132.459296 152.42979)
		(width 0.148)
		(layer "In2.Cu")
		(net 97)
	)
	(segment
		(start 131.222683 152.605742)
		(end 131.222684 152.605743)
		(width 0.148)
		(layer "In2.Cu")
		(net 97)
	)
	(segment
		(start 137.375001 157.875001)
		(end 137.375001 163.3005)
		(width 0.148)
		(layer "In2.Cu")
		(net 97)
	)
	(segment
		(start 137.375001 163.3005)
		(end 137.877001 163.8025)
		(width 0.148)
		(layer "In2.Cu")
		(net 97)
	)
	(segment
		(start 134.051111 155.43417)
		(end 134.051112 155.434171)
		(width 0.148)
		(layer "In2.Cu")
		(net 97)
	)
	(segment
		(start 134.404665 155.434171)
		(end 134.492641 155.346194)
		(width 0.148)
		(layer "In2.Cu")
		(net 97)
	)
	(segment
		(start 133.697558 154.727064)
		(end 134.227062 154.197557)
		(width 0.148)
		(layer "In2.Cu")
		(net 97)
	)
	(segment
		(start 131.045082 150.662024)
		(end 131.045083 150.662024)
		(width 0.148)
		(layer "In2.Cu")
		(net 97)
	)
	(segment
		(start 134.580617 154.551111)
		(end 134.051112 155.080617)
		(width 0.148)
		(layer "In2.Cu")
		(net 97)
	)
	(segment
		(start 130.515576 151.898635)
		(end 130.515577 151.898636)
		(width 0.148)
		(layer "In2.Cu")
		(net 97)
	)
	(segment
		(start 131.576237 152.605742)
		(end 131.576237 152.605743)
		(width 0.148)
		(layer "In2.Cu")
		(net 97)
	)
	(segment
		(start 131.92979 153.312849)
		(end 131.929791 153.31285)
		(width 0.148)
		(layer "In2.Cu")
		(net 97)
	)
	(segment
		(start 133.166403 153.136897)
		(end 132.636898 153.666403)
		(width 0.148)
		(layer "In2.Cu")
		(net 97)
	)
	(segment
		(start 124.225002 150.600501)
		(end 130.100501 150.600501)
		(width 0.148)
		(layer "In2.Cu")
		(net 97)
	)
	(segment
		(start 132.283344 153.31285)
		(end 132.812848 152.783343)
		(width 0.148)
		(layer "In2.Cu")
		(net 97)
	)
	(segment
		(start 132.459296 152.076237)
		(end 132.459297 152.076238)
		(width 0.148)
		(layer "In2.Cu")
		(net 97)
	)
	(segment
		(start 130.86913 151.898635)
		(end 130.86913 151.898636)
		(width 0.148)
		(layer "In2.Cu")
		(net 97)
	)
	(segment
		(start 131.045082 151.015577)
		(end 131.045082 151.015576)
		(width 0.148)
		(layer "In2.Cu")
		(net 97)
	)
	(segment
		(start 122.400001 148.7755)
		(end 124.225002 150.600501)
		(width 0.148)
		(layer "In2.Cu")
		(net 97)
	)
	(segment
		(start 133.87351 153.490451)
		(end 133.873511 153.490452)
		(width 0.148)
		(layer "In2.Cu")
		(net 97)
	)
	(segment
		(start 133.166403 152.783344)
		(end 133.166404 152.783345)
		(width 0.148)
		(layer "In2.Cu")
		(net 97)
	)
	(arc
		(start 134.227062 154.197557)
		(mid 134.40384 154.124335)
		(end 134.580617 154.197558)
		(width 0.148)
		(layer "In2.Cu")
		(net 97)
	)
	(arc
		(start 133.344005 154.37351)
		(mid 133.270781 154.550286)
		(end 133.344004 154.727063)
		(width 0.148)
		(layer "In2.Cu")
		(net 97)
	)
	(arc
		(start 131.75219 151.369131)
		(mid 131.825413 151.545908)
		(end 131.752189 151.722684)
		(width 0.148)
		(layer "In2.Cu")
		(net 97)
	)
	(arc
		(start 133.166404 152.783345)
		(mid 133.239627 152.960122)
		(end 133.166403 153.136898)
		(width 0.148)
		(layer "In2.Cu")
		(net 97)
	)
	(arc
		(start 130.691529 150.662023)
		(mid 130.868306 150.5888)
		(end 131.045082 150.662024)
		(width 0.148)
		(layer "In2.Cu")
		(net 97)
	)
	(arc
		(start 131.929791 152.959296)
		(mid 131.856567 153.136072)
		(end 131.92979 153.312849)
		(width 0.148)
		(layer "In2.Cu")
		(net 97)
	)
	(arc
		(start 134.580618 154.197559)
		(mid 134.653841 154.374336)
		(end 134.580617 154.551112)
		(width 0.148)
		(layer "In2.Cu")
		(net 97)
	)
	(arc
		(start 131.929791 153.31285)
		(mid 132.106568 153.386073)
		(end 132.283344 153.312849)
		(width 0.148)
		(layer "In2.Cu")
		(net 97)
	)
	(arc
		(start 134.492641 155.346194)
		(mid 134.669418 155.272971)
		(end 134.846194 155.346195)
		(width 0.148)
		(layer "In2.Cu")
		(net 97)
	)
	(arc
		(start 132.636898 154.019957)
		(mid 132.813675 154.09318)
		(end 132.990451 154.019956)
		(width 0.148)
		(layer "In2.Cu")
		(net 97)
	)
	(arc
		(start 134.051112 155.434171)
		(mid 134.227889 155.507394)
		(end 134.404665 155.43417)
		(width 0.148)
		(layer "In2.Cu")
		(net 97)
	)
	(arc
		(start 131.222684 152.605743)
		(mid 131.399461 152.678966)
		(end 131.576237 152.605742)
		(width 0.148)
		(layer "In2.Cu")
		(net 97)
	)
	(arc
		(start 133.873511 153.490452)
		(mid 133.946734 153.667229)
		(end 133.87351 153.844005)
		(width 0.148)
		(layer "In2.Cu")
		(net 97)
	)
	(arc
		(start 132.105741 152.076236)
		(mid 132.282519 152.003014)
		(end 132.459296 152.076237)
		(width 0.148)
		(layer "In2.Cu")
		(net 97)
	)
	(arc
		(start 130.515577 151.898636)
		(mid 130.692354 151.971859)
		(end 130.86913 151.898635)
		(width 0.148)
		(layer "In2.Cu")
		(net 97)
	)
	(arc
		(start 131.398634 151.369129)
		(mid 131.575412 151.295907)
		(end 131.752189 151.36913)
		(width 0.148)
		(layer "In2.Cu")
		(net 97)
	)
	(arc
		(start 132.812848 152.783343)
		(mid 132.989626 152.710121)
		(end 133.166403 152.783344)
		(width 0.148)
		(layer "In2.Cu")
		(net 97)
	)
	(arc
		(start 130.515577 151.545082)
		(mid 130.442353 151.721858)
		(end 130.515576 151.898635)
		(width 0.148)
		(layer "In2.Cu")
		(net 97)
	)
	(arc
		(start 133.344005 154.727064)
		(mid 133.520782 154.800287)
		(end 133.697558 154.727063)
		(width 0.148)
		(layer "In2.Cu")
		(net 97)
	)
	(arc
		(start 132.636898 153.666403)
		(mid 132.563674 153.843179)
		(end 132.636897 154.019956)
		(width 0.148)
		(layer "In2.Cu")
		(net 97)
	)
	(arc
		(start 131.045083 150.662024)
		(mid 131.118306 150.838801)
		(end 131.045082 151.015577)
		(width 0.148)
		(layer "In2.Cu")
		(net 97)
	)
	(arc
		(start 134.051112 155.080617)
		(mid 133.977888 155.257393)
		(end 134.051111 155.43417)
		(width 0.148)
		(layer "In2.Cu")
		(net 97)
	)
	(arc
		(start 131.222684 152.252189)
		(mid 131.14946 152.428965)
		(end 131.222683 152.605742)
		(width 0.148)
		(layer "In2.Cu")
		(net 97)
	)
	(arc
		(start 130.25 150.75)
		(mid 130.426777 150.823223)
		(end 130.603553 150.749999)
		(width 0.148)
		(layer "In2.Cu")
		(net 97)
	)
	(arc
		(start 132.459297 152.076238)
		(mid 132.53252 152.253015)
		(end 132.459296 152.429791)
		(width 0.148)
		(layer "In2.Cu")
		(net 97)
	)
	(arc
		(start 133.519955 153.49045)
		(mid 133.696733 153.417228)
		(end 133.87351 153.490451)
		(width 0.148)
		(layer "In2.Cu")
		(net 97)
	)
	(segment
		(start 123.150001 138.8025)
		(end 123.150001 139.8775)
		(width 0.201)
		(layer "F.Cu")
		(net 98)
	)
	(segment
		(start 138.376501 165.302)
		(end 137.877001 164.8025)
		(width 0.256)
		(layer "F.Cu")
		(net 98)
	)
	(via
		(at 137.877001 164.8025)
		(size 0.45)
		(drill 0.1)
		(layers "F.Cu" "B.Cu")
		(net 98)
	)
	(via
		(at 123.150001 139.8775)
		(size 0.45)
		(drill 0.1)
		(layers "F.Cu" "B.Cu")
		(net 98)
	)
	(segment
		(start 138.000501 157.000501)
		(end 138.000501 160.976)
		(width 0.148)
		(layer "In2.Cu")
		(net 98)
	)
	(segment
		(start 123.5 141)
		(end 123.391091 141)
		(width 0.148)
		(layer "In2.Cu")
		(net 98)
	)
	(segment
		(start 138.000501 160.976)
		(end 138.275001 161.2505)
		(width 0.148)
		(layer "In2.Cu")
		(net 98)
	)
	(segment
		(start 123.391091 143.5)
		(end 123.5 143.5)
		(width 0.148)
		(layer "In2.Cu")
		(net 98)
	)
	(segment
		(start 124.625002 149.800501)
		(end 130.800501 149.800501)
		(width 0.148)
		(layer "In2.Cu")
		(net 98)
	)
	(segment
		(start 123.391091 141.5)
		(end 123.5 141.5)
		(width 0.148)
		(layer "In2.Cu")
		(net 98)
	)
	(segment
		(start 123.391091 142)
		(end 124.108909 142)
		(width 0.148)
		(layer "In2.Cu")
		(net 98)
	)
	(segment
		(start 137.877001 164.8025)
		(end 137.877001 164.4505)
		(width 0.1)
		(layer "In2.Cu")
		(net 98)
	)
	(segment
		(start 130.800501 149.800501)
		(end 138.000501 157.000501)
		(width 0.148)
		(layer "In2.Cu")
		(net 98)
	)
	(segment
		(start 123.75 143.75)
		(end 123.75 144.356615)
		(width 0.148)
		(layer "In2.Cu")
		(net 98)
	)
	(segment
		(start 138.275001 164.0525)
		(end 138.275001 161.2505)
		(width 0.1)
		(layer "In2.Cu")
		(net 98)
	)
	(segment
		(start 123.150001 139.8775)
		(end 123.75 140.477499)
		(width 0.148)
		(layer "In2.Cu")
		(net 98)
	)
	(segment
		(start 137.877001 164.4505)
		(end 138.275001 164.0525)
		(width 0.1)
		(layer "In2.Cu")
		(net 98)
	)
	(segment
		(start 123.5 141.5)
		(end 124.108909 141.5)
		(width 0.148)
		(layer "In2.Cu")
		(net 98)
	)
	(segment
		(start 122.875001 148.0505)
		(end 124.625002 149.800501)
		(width 0.148)
		(layer "In2.Cu")
		(net 98)
	)
	(segment
		(start 123.4 146.238751)
		(end 122.875001 146.76375)
		(width 0.148)
		(layer "In2.Cu")
		(net 98)
	)
	(segment
		(start 122.875001 146.76375)
		(end 122.875001 148.0505)
		(width 0.148)
		(layer "In2.Cu")
		(net 98)
	)
	(segment
		(start 123.4 144.706615)
		(end 123.4 146.238751)
		(width 0.148)
		(layer "In2.Cu")
		(net 98)
	)
	(segment
		(start 123.75 140.477499)
		(end 123.75 140.75)
		(width 0.148)
		(layer "In2.Cu")
		(net 98)
	)
	(segment
		(start 123.391091 143)
		(end 124.108909 143)
		(width 0.148)
		(layer "In2.Cu")
		(net 98)
	)
	(segment
		(start 123.391091 142.5)
		(end 124.108909 142.5)
		(width 0.148)
		(layer "In2.Cu")
		(net 98)
	)
	(segment
		(start 123.75 144.356615)
		(end 123.4 144.706615)
		(width 0.148)
		(layer "In2.Cu")
		(net 98)
	)
	(arc
		(start 124.108909 142.5)
		(mid 124.285686 142.573223)
		(end 124.358909 142.75)
		(width 0.148)
		(layer "In2.Cu")
		(net 98)
	)
	(arc
		(start 123.391091 143)
		(mid 123.214314 143.073223)
		(end 123.141091 143.25)
		(width 0.148)
		(layer "In2.Cu")
		(net 98)
	)
	(arc
		(start 123.141091 142.25)
		(mid 123.214314 142.426777)
		(end 123.391091 142.5)
		(width 0.148)
		(layer "In2.Cu")
		(net 98)
	)
	(arc
		(start 123.141091 141.25)
		(mid 123.214314 141.426777)
		(end 123.391091 141.5)
		(width 0.148)
		(layer "In2.Cu")
		(net 98)
	)
	(arc
		(start 123.75 140.75)
		(mid 123.676777 140.926777)
		(end 123.5 141)
		(width 0.148)
		(layer "In2.Cu")
		(net 98)
	)
	(arc
		(start 123.5 143.5)
		(mid 123.676777 143.573223)
		(end 123.75 143.75)
		(width 0.148)
		(layer "In2.Cu")
		(net 98)
	)
	(arc
		(start 124.358909 142.75)
		(mid 124.285686 142.926777)
		(end 124.108909 143)
		(width 0.148)
		(layer "In2.Cu")
		(net 98)
	)
	(arc
		(start 123.141091 143.25)
		(mid 123.214314 143.426777)
		(end 123.391091 143.5)
		(width 0.148)
		(layer "In2.Cu")
		(net 98)
	)
	(arc
		(start 123.391091 141)
		(mid 123.214314 141.073223)
		(end 123.141091 141.25)
		(width 0.148)
		(layer "In2.Cu")
		(net 98)
	)
	(arc
		(start 124.358909 141.75)
		(mid 124.285686 141.926777)
		(end 124.108909 142)
		(width 0.148)
		(layer "In2.Cu")
		(net 98)
	)
	(arc
		(start 124.108909 141.5)
		(mid 124.285686 141.573223)
		(end 124.358909 141.75)
		(width 0.148)
		(layer "In2.Cu")
		(net 98)
	)
	(arc
		(start 123.391091 142)
		(mid 123.214314 142.073223)
		(end 123.141091 142.25)
		(width 0.148)
		(layer "In2.Cu")
		(net 98)
	)
	(segment
		(start 123.400001 146.2025)
		(end 123.400001 147.2775)
		(width 0.201)
		(layer "F.Cu")
		(net 99)
	)
	(segment
		(start 138.376501 166.302)
		(end 137.877001 165.8025)
		(width 0.256)
		(layer "F.Cu")
		(net 99)
	)
	(via
		(at 123.400001 147.2775)
		(size 0.45)
		(drill 0.1)
		(layers "F.Cu" "B.Cu")
		(net 99)
	)
	(via
		(at 137.877001 165.8025)
		(size 0.45)
		(drill 0.1)
		(layers "F.Cu" "B.Cu")
		(net 99)
	)
	(segment
		(start 136.154177 153.249605)
		(end 135.749602 153.654175)
		(width 0.148)
		(layer "In2.Cu")
		(net 99)
	)
	(segment
		(start 133.981828 151.8864)
		(end 134.386398 151.481825)
		(width 0.148)
		(layer "In2.Cu")
		(net 99)
	)
	(segment
		(start 137.517383 155.421955)
		(end 137.921953 155.01738)
		(width 0.148)
		(layer "In2.Cu")
		(net 99)
	)
	(segment
		(start 138.775001 161.1505)
		(end 138.500501 160.876)
		(width 0.148)
		(layer "In2.Cu")
		(net 99)
	)
	(segment
		(start 134.739955 151.835383)
		(end 134.33538 152.239953)
		(width 0.148)
		(layer "In2.Cu")
		(net 99)
	)
	(segment
		(start 125.000501 149.000501)
		(end 123.400001 147.400001)
		(width 0.148)
		(layer "In2.Cu")
		(net 99)
	)
	(segment
		(start 135.396049 153.654174)
		(end 135.39605 153.654176)
		(width 0.148)
		(layer "In2.Cu")
		(net 99)
	)
	(segment
		(start 136.103161 154.007733)
		(end 136.507731 153.603158)
		(width 0.148)
		(layer "In2.Cu")
		(net 99)
	)
	(segment
		(start 137.214841 153.956716)
		(end 137.214842 153.956716)
		(width 0.148)
		(layer "In2.Cu")
		(net 99)
	)
	(segment
		(start 135.447067 152.542493)
		(end 135.447066 152.542494)
		(width 0.148)
		(layer "In2.Cu")
		(net 99)
	)
	(segment
		(start 134.688938 152.593512)
		(end 134.688939 152.593511)
		(width 0.148)
		(layer "In2.Cu")
		(net 99)
	)
	(segment
		(start 135.396049 153.300623)
		(end 135.39605 153.300622)
		(width 0.148)
		(layer "In2.Cu")
		(net 99)
	)
	(segment
		(start 136.154178 153.249604)
		(end 136.154177 153.249605)
		(width 0.148)
		(layer "In2.Cu")
		(net 99)
	)
	(segment
		(start 138.525001 164.82382)
		(end 138.525001 164.4525)
		(width 0.1)
		(layer "In2.Cu")
		(net 99)
	)
	(segment
		(start 138.525001 164.4525)
		(end 138.775001 164.2025)
		(width 0.1)
		(layer "In2.Cu")
		(net 99)
	)
	(segment
		(start 137.896447 155.749999)
		(end 137.896446 155.75)
		(width 0.148)
		(layer "In2.Cu")
		(net 99)
	)
	(segment
		(start 135.447066 152.542494)
		(end 135.042491 152.947064)
		(width 0.148)
		(layer "In2.Cu")
		(net 99)
	)
	(segment
		(start 135.39605 153.300622)
		(end 135.80062 152.896047)
		(width 0.148)
		(layer "In2.Cu")
		(net 99)
	)
	(segment
		(start 134.688939 152.593511)
		(end 135.093509 152.188936)
		(width 0.148)
		(layer "In2.Cu")
		(net 99)
	)
	(segment
		(start 132.567605 150.472179)
		(end 132.567606 150.472178)
		(width 0.148)
		(layer "In2.Cu")
		(net 99)
	)
	(segment
		(start 138.775001 164.2025)
		(end 138.775001 161.1505)
		(width 0.1)
		(layer "In2.Cu")
		(net 99)
	)
	(segment
		(start 133.679286 150.421161)
		(end 133.679287 150.421161)
		(width 0.148)
		(layer "In2.Cu")
		(net 99)
	)
	(segment
		(start 137.568399 154.663827)
		(end 137.163824 155.068397)
		(width 0.148)
		(layer "In2.Cu")
		(net 99)
	)
	(segment
		(start 135.800619 152.542494)
		(end 135.80062 152.542494)
		(width 0.148)
		(layer "In2.Cu")
		(net 99)
	)
	(segment
		(start 133.981827 152.239952)
		(end 133.981828 152.239954)
		(width 0.148)
		(layer "In2.Cu")
		(net 99)
	)
	(segment
		(start 137.5684 154.663826)
		(end 137.568399 154.663827)
		(width 0.148)
		(layer "In2.Cu")
		(net 99)
	)
	(segment
		(start 137.921952 154.663827)
		(end 137.921953 154.663827)
		(width 0.148)
		(layer "In2.Cu")
		(net 99)
	)
	(segment
		(start 134.386397 151.128272)
		(end 134.386398 151.128272)
		(width 0.148)
		(layer "In2.Cu")
		(net 99)
	)
	(segment
		(start 133.274717 151.179289)
		(end 133.679287 150.774714)
		(width 0.148)
		(layer "In2.Cu")
		(net 99)
	)
	(segment
		(start 136.861288 153.956716)
		(end 136.456713 154.361286)
		(width 0.148)
		(layer "In2.Cu")
		(net 99)
	)
	(segment
		(start 135.093508 151.835383)
		(end 135.093509 151.835383)
		(width 0.148)
		(layer "In2.Cu")
		(net 99)
	)
	(segment
		(start 136.810272 154.714844)
		(end 137.214842 154.310269)
		(width 0.148)
		(layer "In2.Cu")
		(net 99)
	)
	(segment
		(start 136.861289 153.956715)
		(end 136.861288 153.956716)
		(width 0.148)
		(layer "In2.Cu")
		(net 99)
	)
	(segment
		(start 132.567605 150.82573)
		(end 132.567606 150.825732)
		(width 0.148)
		(layer "In2.Cu")
		(net 99)
	)
	(segment
		(start 132.567606 150.472178)
		(end 132.593114 150.446667)
		(width 0.148)
		(layer "In2.Cu")
		(net 99)
	)
	(segment
		(start 133.274716 151.17929)
		(end 133.274717 151.179289)
		(width 0.148)
		(layer "In2.Cu")
		(net 99)
	)
	(segment
		(start 138.500501 156.000501)
		(end 138.25 155.75)
		(width 0.148)
		(layer "In2.Cu")
		(net 99)
	)
	(segment
		(start 136.810271 154.714845)
		(end 136.810272 154.714844)
		(width 0.148)
		(layer "In2.Cu")
		(net 99)
	)
	(segment
		(start 137.517382 155.421956)
		(end 137.517383 155.421955)
		(width 0.148)
		(layer "In2.Cu")
		(net 99)
	)
	(segment
		(start 131.500501 149.000501)
		(end 125.000501 149.000501)
		(width 0.148)
		(layer "In2.Cu")
		(net 99)
	)
	(segment
		(start 136.810271 155.068396)
		(end 136.810272 155.068398)
		(width 0.148)
		(layer "In2.Cu")
		(net 99)
	)
	(segment
		(start 136.10316 154.007734)
		(end 136.103161 154.007733)
		(width 0.148)
		(layer "In2.Cu")
		(net 99)
	)
	(segment
		(start 136.10316 154.361285)
		(end 136.103161 154.361287)
		(width 0.148)
		(layer "In2.Cu")
		(net 99)
	)
	(segment
		(start 137.517381 155.775508)
		(end 137.517383 155.775509)
		(width 0.148)
		(layer "In2.Cu")
		(net 99)
	)
	(segment
		(start 133.325733 150.421161)
		(end 132.921158 150.825731)
		(width 0.148)
		(layer "In2.Cu")
		(net 99)
	)
	(segment
		(start 134.032844 151.128272)
		(end 133.628269 151.532842)
		(width 0.148)
		(layer "In2.Cu")
		(net 99)
	)
	(segment
		(start 134.032845 151.128271)
		(end 134.032844 151.128272)
		(width 0.148)
		(layer "In2.Cu")
		(net 99)
	)
	(segment
		(start 123.400001 147.400001)
		(end 123.400001 147.2775)
		(width 0.148)
		(layer "In2.Cu")
		(net 99)
	)
	(segment
		(start 133.325734 150.42116)
		(end 133.325733 150.421161)
		(width 0.148)
		(layer "In2.Cu")
		(net 99)
	)
	(segment
		(start 134.688938 152.947063)
		(end 134.688939 152.947065)
		(width 0.148)
		(layer "In2.Cu")
		(net 99)
	)
	(segment
		(start 137.896446 155.75)
		(end 137.870935 155.775508)
		(width 0.148)
		(layer "In2.Cu")
		(net 99)
	)
	(segment
		(start 137.877001 165.47182)
		(end 138.525001 164.82382)
		(width 0.1)
		(layer "In2.Cu")
		(net 99)
	)
	(segment
		(start 137.877001 165.8025)
		(end 137.877001 165.47182)
		(width 0.1)
		(layer "In2.Cu")
		(net 99)
	)
	(segment
		(start 136.50773 153.249605)
		(end 136.507731 153.249605)
		(width 0.148)
		(layer "In2.Cu")
		(net 99)
	)
	(segment
		(start 132.593114 150.093113)
		(end 132.593115 150.093115)
		(width 0.148)
		(layer "In2.Cu")
		(net 99)
	)
	(segment
		(start 132.593115 150.093115)
		(end 131.500501 149.000501)
		(width 0.148)
		(layer "In2.Cu")
		(net 99)
	)
	(segment
		(start 133.274716 151.532841)
		(end 133.274717 151.532843)
		(width 0.148)
		(layer "In2.Cu")
		(net 99)
	)
	(segment
		(start 134.739956 151.835382)
		(end 134.739955 151.835383)
		(width 0.148)
		(layer "In2.Cu")
		(net 99)
	)
	(segment
		(start 138.500501 160.876)
		(end 138.500501 156.000501)
		(width 0.148)
		(layer "In2.Cu")
		(net 99)
	)
	(segment
		(start 133.981827 151.886401)
		(end 133.981828 151.8864)
		(width 0.148)
		(layer "In2.Cu")
		(net 99)
	)
	(arc
		(start 137.163824 155.068397)
		(mid 136.987047 155.14162)
		(end 136.810271 155.068396)
		(width 0.148)
		(layer "In2.Cu")
		(net 99)
	)
	(arc
		(start 135.80062 152.896047)
		(mid 135.873843 152.71927)
		(end 135.800619 152.542494)
		(width 0.148)
		(layer "In2.Cu")
		(net 99)
	)
	(arc
		(start 137.921953 155.01738)
		(mid 137.995176 154.840603)
		(end 137.921952 154.663827)
		(width 0.148)
		(layer "In2.Cu")
		(net 99)
	)
	(arc
		(start 137.517383 155.775509)
		(mid 137.444159 155.598733)
		(end 137.517382 155.421956)
		(width 0.148)
		(layer "In2.Cu")
		(net 99)
	)
	(arc
		(start 134.688939 152.947065)
		(mid 134.615715 152.770289)
		(end 134.688938 152.593512)
		(width 0.148)
		(layer "In2.Cu")
		(net 99)
	)
	(arc
		(start 134.386398 151.128272)
		(mid 134.209622 151.055048)
		(end 134.032845 151.128271)
		(width 0.148)
		(layer "In2.Cu")
		(net 99)
	)
	(arc
		(start 135.39605 153.654176)
		(mid 135.322826 153.4774)
		(end 135.396049 153.300623)
		(width 0.148)
		(layer "In2.Cu")
		(net 99)
	)
	(arc
		(start 133.679287 150.421161)
		(mid 133.502511 150.347937)
		(end 133.325734 150.42116)
		(width 0.148)
		(layer "In2.Cu")
		(net 99)
	)
	(arc
		(start 135.093509 152.188936)
		(mid 135.166732 152.012159)
		(end 135.093508 151.835383)
		(width 0.148)
		(layer "In2.Cu")
		(net 99)
	)
	(arc
		(start 135.042491 152.947064)
		(mid 134.865714 153.020287)
		(end 134.688938 152.947063)
		(width 0.148)
		(layer "In2.Cu")
		(net 99)
	)
	(arc
		(start 132.921158 150.825731)
		(mid 132.744381 150.898954)
		(end 132.567605 150.82573)
		(width 0.148)
		(layer "In2.Cu")
		(net 99)
	)
	(arc
		(start 135.80062 152.542494)
		(mid 135.623844 152.46927)
		(end 135.447067 152.542493)
		(width 0.148)
		(layer "In2.Cu")
		(net 99)
	)
	(arc
		(start 137.870935 155.775508)
		(mid 137.694158 155.848731)
		(end 137.517381 155.775508)
		(width 0.148)
		(layer "In2.Cu")
		(net 99)
	)
	(arc
		(start 133.274717 151.532843)
		(mid 133.201493 151.356067)
		(end 133.274716 151.17929)
		(width 0.148)
		(layer "In2.Cu")
		(net 99)
	)
	(arc
		(start 138.25 155.75)
		(mid 138.073224 155.676776)
		(end 137.896447 155.749999)
		(width 0.148)
		(layer "In2.Cu")
		(net 99)
	)
	(arc
		(start 132.593114 150.446667)
		(mid 132.666337 150.26989)
		(end 132.593114 150.093113)
		(width 0.148)
		(layer "In2.Cu")
		(net 99)
	)
	(arc
		(start 136.456713 154.361286)
		(mid 136.279936 154.434509)
		(end 136.10316 154.361285)
		(width 0.148)
		(layer "In2.Cu")
		(net 99)
	)
	(arc
		(start 137.921953 154.663827)
		(mid 137.745177 154.590603)
		(end 137.5684 154.663826)
		(width 0.148)
		(layer "In2.Cu")
		(net 99)
	)
	(arc
		(start 135.749602 153.654175)
		(mid 135.572825 153.727398)
		(end 135.396049 153.654174)
		(width 0.148)
		(layer "In2.Cu")
		(net 99)
	)
	(arc
		(start 133.628269 151.532842)
		(mid 133.451492 151.606065)
		(end 133.274716 151.532841)
		(width 0.148)
		(layer "In2.Cu")
		(net 99)
	)
	(arc
		(start 133.679287 150.774714)
		(mid 133.75251 150.597937)
		(end 133.679286 150.421161)
		(width 0.148)
		(layer "In2.Cu")
		(net 99)
	)
	(arc
		(start 134.33538 152.239953)
		(mid 134.158603 152.313176)
		(end 133.981827 152.239952)
		(width 0.148)
		(layer "In2.Cu")
		(net 99)
	)
	(arc
		(start 135.093509 151.835383)
		(mid 134.916733 151.762159)
		(end 134.739956 151.835382)
		(width 0.148)
		(layer "In2.Cu")
		(net 99)
	)
	(arc
		(start 137.214842 153.956716)
		(mid 137.038066 153.883492)
		(end 136.861289 153.956715)
		(width 0.148)
		(layer "In2.Cu")
		(net 99)
	)
	(arc
		(start 136.507731 153.249605)
		(mid 136.330955 153.176381)
		(end 136.154178 153.249604)
		(width 0.148)
		(layer "In2.Cu")
		(net 99)
	)
	(arc
		(start 137.214842 154.310269)
		(mid 137.288065 154.133492)
		(end 137.214841 153.956716)
		(width 0.148)
		(layer "In2.Cu")
		(net 99)
	)
	(arc
		(start 132.567606 150.825732)
		(mid 132.494382 150.648956)
		(end 132.567605 150.472179)
		(width 0.148)
		(layer "In2.Cu")
		(net 99)
	)
	(arc
		(start 136.103161 154.361287)
		(mid 136.029937 154.184511)
		(end 136.10316 154.007734)
		(width 0.148)
		(layer "In2.Cu")
		(net 99)
	)
	(arc
		(start 134.386398 151.481825)
		(mid 134.459621 151.305048)
		(end 134.386397 151.128272)
		(width 0.148)
		(layer "In2.Cu")
		(net 99)
	)
	(arc
		(start 133.981828 152.239954)
		(mid 133.908604 152.063178)
		(end 133.981827 151.886401)
		(width 0.148)
		(layer "In2.Cu")
		(net 99)
	)
	(arc
		(start 136.810272 155.068398)
		(mid 136.737048 154.891622)
		(end 136.810271 154.714845)
		(width 0.148)
		(layer "In2.Cu")
		(net 99)
	)
	(arc
		(start 136.507731 153.603158)
		(mid 136.580954 153.426381)
		(end 136.50773 153.249605)
		(width 0.148)
		(layer "In2.Cu")
		(net 99)
	)
	(segment
		(start 137.376501 166.302)
		(end 137.876001 166.8015)
		(width 0.256)
		(layer "F.Cu")
		(net 100)
	)
	(segment
		(start 124.150001 138.8025)
		(end 124.150001 139.8775)
		(width 0.201)
		(layer "F.Cu")
		(net 100)
	)
	(via
		(at 124.150001 139.8775)
		(size 0.45)
		(drill 0.1)
		(layers "F.Cu" "B.Cu")
		(net 100)
	)
	(via
		(at 137.876001 166.8015)
		(size 0.45)
		(drill 0.1)
		(layers "F.Cu" "B.Cu")
		(net 100)
	)
	(segment
		(start 125.300501 148.276)
		(end 124.900501 147.876)
		(width 0.148)
		(layer "In2.Cu")
		(net 100)
	)
	(segment
		(start 137.876001 166.8015)
		(end 138.325001 166.3525)
		(width 0.1)
		(layer "In2.Cu")
		(net 100)
	)
	(segment
		(start 125.37 141.097499)
		(end 124.150001 139.8775)
		(width 0.148)
		(layer "In2.Cu")
		(net 100)
	)
	(segment
		(start 139.175001 160.9505)
		(end 139.000501 160.776)
		(width 0.148)
		(layer "In2.Cu")
		(net 100)
	)
	(segment
		(start 139.000501 160.776)
		(end 139.000501 155.250501)
		(width 0.148)
		(layer "In2.Cu")
		(net 100)
	)
	(segment
		(start 125.62 142.32)
		(end 125.08419 142.32)
		(width 0.148)
		(layer "In2.Cu")
		(net 100)
	)
	(segment
		(start 132.026 148.276)
		(end 125.300501 148.276)
		(width 0.148)
		(layer "In2.Cu")
		(net 100)
	)
	(segment
		(start 125.37 145.606501)
		(end 125.37 143.07)
		(width 0.148)
		(layer "In2.Cu")
		(net 100)
	)
	(segment
		(start 125.65581 142.32)
		(end 125.62 142.32)
		(width 0.148)
		(layer "In2.Cu")
		(net 100)
	)
	(segment
		(start 139.175001 164.8525)
		(end 139.175001 160.9505)
		(width 0.1)
		(layer "In2.Cu")
		(net 100)
	)
	(segment
		(start 124.900501 146.076)
		(end 125.37 145.606501)
		(width 0.148)
		(layer "In2.Cu")
		(net 100)
	)
	(segment
		(start 125.62 142.82)
		(end 125.65581 142.82)
		(width 0.148)
		(layer "In2.Cu")
		(net 100)
	)
	(segment
		(start 124.900501 147.876)
		(end 124.900501 146.076)
		(width 0.148)
		(layer "In2.Cu")
		(net 100)
	)
	(segment
		(start 138.325001 166.3525)
		(end 138.325001 165.7025)
		(width 0.1)
		(layer "In2.Cu")
		(net 100)
	)
	(segment
		(start 125.08419 141.82)
		(end 125.12 141.82)
		(width 0.148)
		(layer "In2.Cu")
		(net 100)
	)
	(segment
		(start 138.325001 165.7025)
		(end 139.175001 164.8525)
		(width 0.1)
		(layer "In2.Cu")
		(net 100)
	)
	(segment
		(start 139.000501 155.250501)
		(end 132.026 148.276)
		(width 0.148)
		(layer "In2.Cu")
		(net 100)
	)
	(segment
		(start 125.37 141.57)
		(end 125.37 141.097499)
		(width 0.148)
		(layer "In2.Cu")
		(net 100)
	)
	(arc
		(start 125.65581 142.82)
		(mid 125.832587 142.746777)
		(end 125.90581 142.57)
		(width 0.148)
		(layer "In2.Cu")
		(net 100)
	)
	(arc
		(start 125.37 143.07)
		(mid 125.443223 142.893223)
		(end 125.62 142.82)
		(width 0.148)
		(layer "In2.Cu")
		(net 100)
	)
	(arc
		(start 125.08419 142.32)
		(mid 124.907413 142.246777)
		(end 124.83419 142.07)
		(width 0.148)
		(layer "In2.Cu")
		(net 100)
	)
	(arc
		(start 125.12 141.82)
		(mid 125.296777 141.746777)
		(end 125.37 141.57)
		(width 0.148)
		(layer "In2.Cu")
		(net 100)
	)
	(arc
		(start 125.90581 142.57)
		(mid 125.832587 142.393223)
		(end 125.65581 142.32)
		(width 0.148)
		(layer "In2.Cu")
		(net 100)
	)
	(arc
		(start 124.83419 142.07)
		(mid 124.907413 141.893223)
		(end 125.08419 141.82)
		(width 0.148)
		(layer "In2.Cu")
		(net 100)
	)
	(segment
		(start 130.376501 165.302)
		(end 129.877001 164.8025)
		(width 0.256)
		(layer "F.Cu")
		(net 101)
	)
	(via
		(at 139.8 142.3)
		(size 0.45)
		(drill 0.1)
		(layers "F.Cu" "B.Cu")
		(net 101)
	)
	(via
		(at 129.877001 164.8025)
		(size 0.45)
		(drill 0.1)
		(layers "F.Cu" "B.Cu")
		(net 101)
	)
	(segment
		(start 140.1 142.3)
		(end 139.8 142.3)
		(width 0.15)
		(layer "B.Cu")
		(net 101)
	)
	(segment
		(start 140.67 142.885)
		(end 140.67 142.87)
		(width 0.15)
		(layer "B.Cu")
		(net 101)
	)
	(segment
		(start 140.67 142.87)
		(end 140.1 142.3)
		(width 0.15)
		(layer "B.Cu")
		(net 101)
	)
	(segment
		(start 139.825 142.325)
		(end 140.825 142.325)
		(width 0.1)
		(layer "In9.Cu")
		(net 101)
	)
	(segment
		(start 126.65 145.325)
		(end 125.925 146.05)
		(width 0.1)
		(layer "In9.Cu")
		(net 101)
	)
	(segment
		(start 125.925 146.05)
		(end 125.925 157.85)
		(width 0.1)
		(layer "In9.Cu")
		(net 101)
	)
	(segment
		(start 129.877001 164.368186)
		(end 129.877001 164.8025)
		(width 0.1)
		(layer "In9.Cu")
		(net 101)
	)
	(segment
		(start 129.277001 161.202001)
		(end 129.277001 163.768186)
		(width 0.1)
		(layer "In9.Cu")
		(net 101)
	)
	(segment
		(start 141.425 142.925)
		(end 142.975 142.925)
		(width 0.1)
		(layer "In9.Cu")
		(net 101)
	)
	(segment
		(start 143.65 142.25)
		(end 143.65 139.2)
		(width 0.1)
		(layer "In9.Cu")
		(net 101)
	)
	(segment
		(start 127.525 138.525)
		(end 126.65 139.4)
		(width 0.1)
		(layer "In9.Cu")
		(net 101)
	)
	(segment
		(start 129.277001 163.768186)
		(end 129.877001 164.368186)
		(width 0.1)
		(layer "In9.Cu")
		(net 101)
	)
	(segment
		(start 142.975 142.925)
		(end 143.65 142.25)
		(width 0.1)
		(layer "In9.Cu")
		(net 101)
	)
	(segment
		(start 125.925 157.85)
		(end 129.277001 161.202001)
		(width 0.1)
		(layer "In9.Cu")
		(net 101)
	)
	(segment
		(start 142.975 138.525)
		(end 127.525 138.525)
		(width 0.1)
		(layer "In9.Cu")
		(net 101)
	)
	(segment
		(start 139.8 142.3)
		(end 139.825 142.325)
		(width 0.1)
		(layer "In9.Cu")
		(net 101)
	)
	(segment
		(start 140.825 142.325)
		(end 141.425 142.925)
		(width 0.1)
		(layer "In9.Cu")
		(net 101)
	)
	(segment
		(start 126.65 139.4)
		(end 126.65 145.325)
		(width 0.1)
		(layer "In9.Cu")
		(net 101)
	)
	(segment
		(start 143.65 139.2)
		(end 142.975 138.525)
		(width 0.1)
		(layer "In9.Cu")
		(net 101)
	)
	(segment
		(start 132.376501 162.302)
		(end 131.877 161.802501)
		(width 0.256)
		(layer "F.Cu")
		(net 102)
	)
	(segment
		(start 124.400001 146.2025)
		(end 124.400001 147.2775)
		(width 0.201)
		(layer "F.Cu")
		(net 102)
	)
	(via
		(at 131.877 161.802501)
		(size 0.45)
		(drill 0.1)
		(layers "F.Cu" "B.Cu")
		(net 102)
	)
	(via
		(at 124.400001 147.2775)
		(size 0.45)
		(drill 0.1)
		(layers "F.Cu" "B.Cu")
		(net 102)
	)
	(segment
		(start 123 148)
		(end 122.5 148.5)
		(width 0.148)
		(layer "In6.Cu")
		(net 102)
	)
	(segment
		(start 124.400001 147.2775)
		(end 124.400001 147.43875)
		(width 0.148)
		(layer "In6.Cu")
		(net 102)
	)
	(segment
		(start 129.5 160.75)
		(end 130.824499 160.75)
		(width 0.148)
		(layer "In6.Cu")
		(net 102)
	)
	(segment
		(start 123.155177 153)
		(end 122.75 153)
		(width 0.148)
		(layer "In6.Cu")
		(net 102)
	)
	(segment
		(start 122.25 149)
		(end 121.844823 149)
		(width 0.148)
		(layer "In6.Cu")
		(net 102)
	)
	(segment
		(start 124.400001 147.43875)
		(end 123.838751 148)
		(width 0.148)
		(layer "In6.Cu")
		(net 102)
	)
	(segment
		(start 121.844823 151.5)
		(end 123.155177 151.5)
		(width 0.148)
		(layer "In6.Cu")
		(net 102)
	)
	(segment
		(start 121.844823 150)
		(end 123.155177 150)
		(width 0.148)
		(layer "In6.Cu")
		(net 102)
	)
	(segment
		(start 122.5 153.75)
		(end 129.5 160.75)
		(width 0.148)
		(layer "In6.Cu")
		(net 102)
	)
	(segment
		(start 123.838751 148)
		(end 123 148)
		(width 0.148)
		(layer "In6.Cu")
		(net 102)
	)
	(segment
		(start 121.844823 151)
		(end 123.155177 151)
		(width 0.148)
		(layer "In6.Cu")
		(net 102)
	)
	(segment
		(start 121.844823 152)
		(end 123.155177 152)
		(width 0.148)
		(layer "In6.Cu")
		(net 102)
	)
	(segment
		(start 130.824499 160.75)
		(end 131.877 161.802501)
		(width 0.148)
		(layer "In6.Cu")
		(net 102)
	)
	(segment
		(start 121.844823 150.5)
		(end 123.155177 150.5)
		(width 0.148)
		(layer "In6.Cu")
		(net 102)
	)
	(segment
		(start 122.5 153.25)
		(end 122.5 153.75)
		(width 0.148)
		(layer "In6.Cu")
		(net 102)
	)
	(segment
		(start 122.5 148.5)
		(end 122.5 148.75)
		(width 0.148)
		(layer "In6.Cu")
		(net 102)
	)
	(segment
		(start 121.844823 149.5)
		(end 123.155177 149.5)
		(width 0.148)
		(layer "In6.Cu")
		(net 102)
	)
	(segment
		(start 121.844823 152.5)
		(end 123.155177 152.5)
		(width 0.148)
		(layer "In6.Cu")
		(net 102)
	)
	(arc
		(start 123.405177 152.75)
		(mid 123.331954 152.926777)
		(end 123.155177 153)
		(width 0.148)
		(layer "In6.Cu")
		(net 102)
	)
	(arc
		(start 122.5 148.75)
		(mid 122.426777 148.926777)
		(end 122.25 149)
		(width 0.148)
		(layer "In6.Cu")
		(net 102)
	)
	(arc
		(start 123.405177 151.75)
		(mid 123.331954 151.926777)
		(end 123.155177 152)
		(width 0.148)
		(layer "In6.Cu")
		(net 102)
	)
	(arc
		(start 123.155177 149.5)
		(mid 123.331954 149.573223)
		(end 123.405177 149.75)
		(width 0.148)
		(layer "In6.Cu")
		(net 102)
	)
	(arc
		(start 121.844823 149)
		(mid 121.668046 149.073223)
		(end 121.594823 149.25)
		(width 0.148)
		(layer "In6.Cu")
		(net 102)
	)
	(arc
		(start 123.405177 150.75)
		(mid 123.331954 150.926777)
		(end 123.155177 151)
		(width 0.148)
		(layer "In6.Cu")
		(net 102)
	)
	(arc
		(start 121.844823 152)
		(mid 121.668046 152.073223)
		(end 121.594823 152.25)
		(width 0.148)
		(layer "In6.Cu")
		(net 102)
	)
	(arc
		(start 121.594823 149.25)
		(mid 121.668046 149.426777)
		(end 121.844823 149.5)
		(width 0.148)
		(layer "In6.Cu")
		(net 102)
	)
	(arc
		(start 123.155177 151.5)
		(mid 123.331954 151.573223)
		(end 123.405177 151.75)
		(width 0.148)
		(layer "In6.Cu")
		(net 102)
	)
	(arc
		(start 123.155177 152.5)
		(mid 123.331954 152.573223)
		(end 123.405177 152.75)
		(width 0.148)
		(layer "In6.Cu")
		(net 102)
	)
	(arc
		(start 123.155177 150.5)
		(mid 123.331954 150.573223)
		(end 123.405177 150.75)
		(width 0.148)
		(layer "In6.Cu")
		(net 102)
	)
	(arc
		(start 121.844823 150)
		(mid 121.668046 150.073223)
		(end 121.594823 150.25)
		(width 0.148)
		(layer "In6.Cu")
		(net 102)
	)
	(arc
		(start 121.594823 151.25)
		(mid 121.668046 151.426777)
		(end 121.844823 151.5)
		(width 0.148)
		(layer "In6.Cu")
		(net 102)
	)
	(arc
		(start 121.594823 150.25)
		(mid 121.668046 150.426777)
		(end 121.844823 150.5)
		(width 0.148)
		(layer "In6.Cu")
		(net 102)
	)
	(arc
		(start 123.405177 149.75)
		(mid 123.331954 149.926777)
		(end 123.155177 150)
		(width 0.148)
		(layer "In6.Cu")
		(net 102)
	)
	(arc
		(start 121.844823 151)
		(mid 121.668046 151.073223)
		(end 121.594823 151.25)
		(width 0.148)
		(layer "In6.Cu")
		(net 102)
	)
	(arc
		(start 121.594823 152.25)
		(mid 121.668046 152.426777)
		(end 121.844823 152.5)
		(width 0.148)
		(layer "In6.Cu")
		(net 102)
	)
	(arc
		(start 122.75 153)
		(mid 122.573223 153.073223)
		(end 122.5 153.25)
		(width 0.148)
		(layer "In6.Cu")
		(net 102)
	)
	(segment
		(start 136.376501 164.302001)
		(end 135.877001 163.8025)
		(width 0.256)
		(layer "F.Cu")
		(net 103)
	)
	(segment
		(start 125.150001 138.8025)
		(end 125.150001 139.8775)
		(width 0.201)
		(layer "F.Cu")
		(net 103)
	)
	(via
		(at 125.150001 139.8775)
		(size 0.45)
		(drill 0.1)
		(layers "F.Cu" "B.Cu")
		(net 103)
	)
	(via
		(at 135.877001 163.8025)
		(size 0.45)
		(drill 0.1)
		(layers "F.Cu" "B.Cu")
		(net 103)
	)
	(segment
		(start 130.4 161.9)
		(end 130.8 162.3)
		(width 0.148)
		(layer "In6.Cu")
		(net 103)
	)
	(segment
		(start 130.15 161.25)
		(end 130.4 161.5)
		(width 0.148)
		(layer "In6.Cu")
		(net 103)
	)
	(segment
		(start 132.75 164.25)
		(end 135.429501 164.25)
		(width 0.148)
		(layer "In6.Cu")
		(net 103)
	)
	(segment
		(start 120.9 148.8)
		(end 120.9 153.15)
		(width 0.148)
		(layer "In6.Cu")
		(net 103)
	)
	(segment
		(start 130.4 161.5)
		(end 130.4 161.9)
		(width 0.148)
		(layer "In6.Cu")
		(net 103)
	)
	(segment
		(start 131.4 162.580613)
		(end 131.4 163)
		(width 0.148)
		(layer "In6.Cu")
		(net 103)
	)
	(segment
		(start 135.429501 164.25)
		(end 135.877001 163.8025)
		(width 0.148)
		(layer "In6.Cu")
		(net 103)
	)
	(segment
		(start 132.4 163.9)
		(end 132.75 164.25)
		(width 0.148)
		(layer "In6.Cu")
		(net 103)
	)
	(segment
		(start 132.4 163.6)
		(end 132.4 163.9)
		(width 0.148)
		(layer "In6.Cu")
		(net 103)
	)
	(segment
		(start 125.150001 139.8775)
		(end 122.4 142.627501)
		(width 0.148)
		(layer "In6.Cu")
		(net 103)
	)
	(segment
		(start 131.65 163.25)
		(end 132.05 163.25)
		(width 0.148)
		(layer "In6.Cu")
		(net 103)
	)
	(segment
		(start 132.05 163.25)
		(end 132.4 163.6)
		(width 0.148)
		(layer "In6.Cu")
		(net 103)
	)
	(segment
		(start 120.9 153.15)
		(end 129 161.25)
		(width 0.148)
		(layer "In6.Cu")
		(net 103)
	)
	(segment
		(start 120.65 148.05)
		(end 120.647925 148.05)
		(width 0.148)
		(layer "In6.Cu")
		(net 103)
	)
	(segment
		(start 129 161.25)
		(end 130.15 161.25)
		(width 0.148)
		(layer "In6.Cu")
		(net 103)
	)
	(segment
		(start 131.119387 162.3)
		(end 131.4 162.580613)
		(width 0.148)
		(layer "In6.Cu")
		(net 103)
	)
	(segment
		(start 120.647925 148.55)
		(end 120.65 148.55)
		(width 0.148)
		(layer "In6.Cu")
		(net 103)
	)
	(segment
		(start 130.8 162.3)
		(end 131.119387 162.3)
		(width 0.148)
		(layer "In6.Cu")
		(net 103)
	)
	(segment
		(start 120.9 147)
		(end 120.9 147.8)
		(width 0.148)
		(layer "In6.Cu")
		(net 103)
	)
	(segment
		(start 122.4 142.627501)
		(end 122.4 145.5)
		(width 0.148)
		(layer "In6.Cu")
		(net 103)
	)
	(segment
		(start 122.4 145.5)
		(end 120.9 147)
		(width 0.148)
		(layer "In6.Cu")
		(net 103)
	)
	(segment
		(start 131.4 163)
		(end 131.65 163.25)
		(width 0.148)
		(layer "In6.Cu")
		(net 103)
	)
	(arc
		(start 120.9 147.8)
		(mid 120.826777 147.976777)
		(end 120.65 148.05)
		(width 0.148)
		(layer "In6.Cu")
		(net 103)
	)
	(arc
		(start 120.397925 148.3)
		(mid 120.471148 148.476777)
		(end 120.647925 148.55)
		(width 0.148)
		(layer "In6.Cu")
		(net 103)
	)
	(arc
		(start 120.647925 148.05)
		(mid 120.471148 148.123223)
		(end 120.397925 148.3)
		(width 0.148)
		(layer "In6.Cu")
		(net 103)
	)
	(arc
		(start 120.65 148.55)
		(mid 120.826777 148.623223)
		(end 120.9 148.8)
		(width 0.148)
		(layer "In6.Cu")
		(net 103)
	)
	(segment
		(start 125.400001 146.2025)
		(end 125.400001 147.2775)
		(width 0.201)
		(layer "F.Cu")
		(net 104)
	)
	(segment
		(start 133.376501 162.302)
		(end 132.877 161.802501)
		(width 0.256)
		(layer "F.Cu")
		(net 104)
	)
	(via
		(at 125.400001 147.2775)
		(size 0.45)
		(drill 0.1)
		(layers "F.Cu" "B.Cu")
		(net 104)
	)
	(via
		(at 132.877 161.802501)
		(size 0.45)
		(drill 0.1)
		(layers "F.Cu" "B.Cu")
		(net 104)
	)
	(segment
		(start 124.8 154.63)
		(end 124.8 155.05)
		(width 0.148)
		(layer "In6.Cu")
		(net 104)
	)
	(segment
		(start 132.602501 161.802501)
		(end 132.877 161.802501)
		(width 0.148)
		(layer "In6.Cu")
		(net 104)
	)
	(segment
		(start 125.400001 147.2775)
		(end 125.400001 147.299999)
		(width 0.148)
		(layer "In6.Cu")
		(net 104)
	)
	(segment
		(start 124.360186 151.88)
		(end 125.239814 151.88)
		(width 0.148)
		(layer "In6.Cu")
		(net 104)
	)
	(segment
		(start 124.360186 153.88)
		(end 125.239814 153.88)
		(width 0.148)
		(layer "In6.Cu")
		(net 104)
	)
	(segment
		(start 124.8 147.9)
		(end 124.8 148.13)
		(width 0.148)
		(layer "In6.Cu")
		(net 104)
	)
	(segment
		(start 124.360186 154.38)
		(end 124.55 154.38)
		(width 0.148)
		(layer "In6.Cu")
		(net 104)
	)
	(segment
		(start 124.360186 149.38)
		(end 125.239814 149.38)
		(width 0.148)
		(layer "In6.Cu")
		(net 104)
	)
	(segment
		(start 124.360186 150.88)
		(end 125.239814 150.88)
		(width 0.148)
		(layer "In6.Cu")
		(net 104)
	)
	(segment
		(start 124.360186 152.88)
		(end 125.239814 152.88)
		(width 0.148)
		(layer "In6.Cu")
		(net 104)
	)
	(segment
		(start 124.360186 151.38)
		(end 125.239814 151.38)
		(width 0.148)
		(layer "In6.Cu")
		(net 104)
	)
	(segment
		(start 124.8 155.05)
		(end 130.05 160.3)
		(width 0.148)
		(layer "In6.Cu")
		(net 104)
	)
	(segment
		(start 125.400001 147.299999)
		(end 124.8 147.9)
		(width 0.148)
		(layer "In6.Cu")
		(net 104)
	)
	(segment
		(start 124.360186 149.88)
		(end 125.239814 149.88)
		(width 0.148)
		(layer "In6.Cu")
		(net 104)
	)
	(segment
		(start 124.360186 150.38)
		(end 125.239814 150.38)
		(width 0.148)
		(layer "In6.Cu")
		(net 104)
	)
	(segment
		(start 124.360186 148.88)
		(end 125.239814 148.88)
		(width 0.148)
		(layer "In6.Cu")
		(net 104)
	)
	(segment
		(start 124.360186 152.38)
		(end 125.239814 152.38)
		(width 0.148)
		(layer "In6.Cu")
		(net 104)
	)
	(segment
		(start 131.1 160.3)
		(end 132.602501 161.802501)
		(width 0.148)
		(layer "In6.Cu")
		(net 104)
	)
	(segment
		(start 124.360186 153.38)
		(end 125.239814 153.38)
		(width 0.148)
		(layer "In6.Cu")
		(net 104)
	)
	(segment
		(start 125.05 148.38)
		(end 125.239814 148.38)
		(width 0.148)
		(layer "In6.Cu")
		(net 104)
	)
	(segment
		(start 130.05 160.3)
		(end 131.1 160.3)
		(width 0.148)
		(layer "In6.Cu")
		(net 104)
	)
	(arc
		(start 124.110186 150.13)
		(mid 124.183409 150.306777)
		(end 124.360186 150.38)
		(width 0.148)
		(layer "In6.Cu")
		(net 104)
	)
	(arc
		(start 124.110186 153.13)
		(mid 124.183409 153.306777)
		(end 124.360186 153.38)
		(width 0.148)
		(layer "In6.Cu")
		(net 104)
	)
	(arc
		(start 124.360186 151.88)
		(mid 124.183409 151.953223)
		(end 124.110186 152.13)
		(width 0.148)
		(layer "In6.Cu")
		(net 104)
	)
	(arc
		(start 125.239814 151.38)
		(mid 125.416591 151.453223)
		(end 125.489814 151.63)
		(width 0.148)
		(layer "In6.Cu")
		(net 104)
	)
	(arc
		(start 125.489814 149.63)
		(mid 125.416591 149.806777)
		(end 125.239814 149.88)
		(width 0.148)
		(layer "In6.Cu")
		(net 104)
	)
	(arc
		(start 125.489814 153.63)
		(mid 125.416591 153.806777)
		(end 125.239814 153.88)
		(width 0.148)
		(layer "In6.Cu")
		(net 104)
	)
	(arc
		(start 125.239814 149.38)
		(mid 125.416591 149.453223)
		(end 125.489814 149.63)
		(width 0.148)
		(layer "In6.Cu")
		(net 104)
	)
	(arc
		(start 124.110186 154.13)
		(mid 124.183409 154.306777)
		(end 124.360186 154.38)
		(width 0.148)
		(layer "In6.Cu")
		(net 104)
	)
	(arc
		(start 124.360186 149.88)
		(mid 124.183409 149.953223)
		(end 124.110186 150.13)
		(width 0.148)
		(layer "In6.Cu")
		(net 104)
	)
	(arc
		(start 124.360186 153.88)
		(mid 124.183409 153.953223)
		(end 124.110186 154.13)
		(width 0.148)
		(layer "In6.Cu")
		(net 104)
	)
	(arc
		(start 124.8 148.13)
		(mid 124.873223 148.306777)
		(end 125.05 148.38)
		(width 0.148)
		(layer "In6.Cu")
		(net 104)
	)
	(arc
		(start 125.489814 148.63)
		(mid 125.416591 148.806777)
		(end 125.239814 148.88)
		(width 0.148)
		(layer "In6.Cu")
		(net 104)
	)
	(arc
		(start 125.239814 153.38)
		(mid 125.416591 153.453223)
		(end 125.489814 153.63)
		(width 0.148)
		(layer "In6.Cu")
		(net 104)
	)
	(arc
		(start 125.239814 148.38)
		(mid 125.416591 148.453223)
		(end 125.489814 148.63)
		(width 0.148)
		(layer "In6.Cu")
		(net 104)
	)
	(arc
		(start 124.110186 152.13)
		(mid 124.183409 152.306777)
		(end 124.360186 152.38)
		(width 0.148)
		(layer "In6.Cu")
		(net 104)
	)
	(arc
		(start 125.489814 150.63)
		(mid 125.416591 150.806777)
		(end 125.239814 150.88)
		(width 0.148)
		(layer "In6.Cu")
		(net 104)
	)
	(arc
		(start 124.110186 149.13)
		(mid 124.183409 149.306777)
		(end 124.360186 149.38)
		(width 0.148)
		(layer "In6.Cu")
		(net 104)
	)
	(arc
		(start 124.110186 151.13)
		(mid 124.183409 151.306777)
		(end 124.360186 151.38)
		(width 0.148)
		(layer "In6.Cu")
		(net 104)
	)
	(arc
		(start 125.489814 152.63)
		(mid 125.416591 152.806777)
		(end 125.239814 152.88)
		(width 0.148)
		(layer "In6.Cu")
		(net 104)
	)
	(arc
		(start 124.55 154.38)
		(mid 124.726777 154.453223)
		(end 124.8 154.63)
		(width 0.148)
		(layer "In6.Cu")
		(net 104)
	)
	(arc
		(start 125.239814 150.38)
		(mid 125.416591 150.453223)
		(end 125.489814 150.63)
		(width 0.148)
		(layer "In6.Cu")
		(net 104)
	)
	(arc
		(start 124.360186 152.88)
		(mid 124.183409 152.953223)
		(end 124.110186 153.13)
		(width 0.148)
		(layer "In6.Cu")
		(net 104)
	)
	(arc
		(start 125.489814 151.63)
		(mid 125.416591 151.806777)
		(end 125.239814 151.88)
		(width 0.148)
		(layer "In6.Cu")
		(net 104)
	)
	(arc
		(start 124.360186 148.88)
		(mid 124.183409 148.953223)
		(end 124.110186 149.13)
		(width 0.148)
		(layer "In6.Cu")
		(net 104)
	)
	(arc
		(start 124.360186 150.88)
		(mid 124.183409 150.953223)
		(end 124.110186 151.13)
		(width 0.148)
		(layer "In6.Cu")
		(net 104)
	)
	(arc
		(start 125.239814 152.38)
		(mid 125.416591 152.453223)
		(end 125.489814 152.63)
		(width 0.148)
		(layer "In6.Cu")
		(net 104)
	)
	(segment
		(start 135.376501 163.302)
		(end 134.877001 162.8025)
		(width 0.256)
		(layer "F.Cu")
		(net 105)
	)
	(segment
		(start 126.150001 138.8025)
		(end 126.150001 139.8775)
		(width 0.201)
		(layer "F.Cu")
		(net 105)
	)
	(via
		(at 134.877001 162.8025)
		(size 0.45)
		(drill 0.1)
		(layers "F.Cu" "B.Cu")
		(net 105)
	)
	(via
		(at 126.150001 139.8775)
		(size 0.45)
		(drill 0.1)
		(layers "F.Cu" "B.Cu")
		(net 105)
	)
	(segment
		(start 125.9 146.9)
		(end 124.48 145.48)
		(width 0.148)
		(layer "In6.Cu")
		(net 105)
	)
	(segment
		(start 125.9 154.6)
		(end 125.9 146.9)
		(width 0.148)
		(layer "In6.Cu")
		(net 105)
	)
	(segment
		(start 134.877001 162.8025)
		(end 134.389501 163.29)
		(width 0.148)
		(layer "In6.Cu")
		(net 105)
	)
	(segment
		(start 134.389501 163.29)
		(end 133.66 163.29)
		(width 0.148)
		(layer "In6.Cu")
		(net 105)
	)
	(segment
		(start 124.48 141.547501)
		(end 126.150001 139.8775)
		(width 0.148)
		(layer "In6.Cu")
		(net 105)
	)
	(segment
		(start 124.48 145.48)
		(end 124.48 141.547501)
		(width 0.148)
		(layer "In6.Cu")
		(net 105)
	)
	(segment
		(start 132.59 161.29)
		(end 125.9 154.6)
		(width 0.148)
		(layer "In6.Cu")
		(net 105)
	)
	(segment
		(start 133.4 161.6125)
		(end 133.0775 161.29)
		(width 0.148)
		(layer "In6.Cu")
		(net 105)
	)
	(segment
		(start 133.66 163.29)
		(end 133.4 163.03)
		(width 0.148)
		(layer "In6.Cu")
		(net 105)
	)
	(segment
		(start 133.4 163.03)
		(end 133.4 161.6125)
		(width 0.148)
		(layer "In6.Cu")
		(net 105)
	)
	(segment
		(start 133.0775 161.29)
		(end 132.59 161.29)
		(width 0.148)
		(layer "In6.Cu")
		(net 105)
	)
	(segment
		(start 180.202001 125.8)
		(end 180.202001 124.948)
		(width 0.4)
		(layer "F.Cu")
		(net 106)
	)
	(segment
		(start 184.3 125.8)
		(end 184.3 124.948)
		(width 0.4)
		(layer "F.Cu")
		(net 106)
	)
	(segment
		(start 181.9 126)
		(end 180.402001 126)
		(width 0.256)
		(layer "F.Cu")
		(net 106)
	)
	(segment
		(start 182 126)
		(end 181.9 126)
		(width 0.256)
		(layer "F.Cu")
		(net 106)
	)
	(segment
		(start 184.1 126)
		(end 184.3 125.8)
		(width 0.256)
		(layer "F.Cu")
		(net 106)
	)
	(segment
		(start 182 128.2)
		(end 181.400001 128.2)
		(width 0.256)
		(layer "F.Cu")
		(net 106)
	)
	(segment
		(start 131.376501 185.301)
		(end 130.877001 185.8005)
		(width 0.256)
		(layer "F.Cu")
		(net 106)
	)
	(segment
		(start 180.402001 126)
		(end 180.202001 125.8)
		(width 0.256)
		(layer "F.Cu")
		(net 106)
	)
	(segment
		(start 181.9 126)
		(end 184.1 126)
		(width 0.256)
		(layer "F.Cu")
		(net 106)
	)
	(segment
		(start 182 128.2)
		(end 182 126)
		(width 0.256)
		(layer "F.Cu")
		(net 106)
	)
	(segment
		(start 182.631001 128.2)
		(end 182 128.2)
		(width 0.256)
		(layer "F.Cu")
		(net 106)
	)
	(via
		(at 180.202001 125.8)
		(size 0.45)
		(drill 0.1)
		(layers "F.Cu" "B.Cu")
		(net 106)
	)
	(via
		(at 176.6 188)
		(size 0.45)
		(drill 0.1)
		(layers "F.Cu" "B.Cu")
		(net 106)
	)
	(via
		(at 184.3 125.8)
		(size 0.45)
		(drill 0.1)
		(layers "F.Cu" "B.Cu")
		(net 106)
	)
	(via
		(at 130.877001 185.8005)
		(size 0.45)
		(drill 0.1)
		(layers "F.Cu" "B.Cu")
		(net 106)
	)
	(segment
		(start 191.1 173.4)
		(end 191.1 161.7)
		(width 0.1)
		(layer "In2.Cu")
		(net 106)
	)
	(segment
		(start 192.1 160.7)
		(end 192.1 133.6)
		(width 0.1)
		(layer "In2.Cu")
		(net 106)
	)
	(segment
		(start 178.2 187.2)
		(end 181.1 187.2)
		(width 0.1)
		(layer "In2.Cu")
		(net 106)
	)
	(segment
		(start 181.220606 187.079394)
		(end 181.220606 187.045776)
		(width 0.1)
		(layer "In2.Cu")
		(net 106)
	)
	(segment
		(start 181.220606 187.045776)
		(end 185.6 182.666382)
		(width 0.1)
		(layer "In2.Cu")
		(net 106)
	)
	(segment
		(start 192.1 133.6)
		(end 184.3 125.8)
		(width 0.1)
		(layer "In2.Cu")
		(net 106)
	)
	(segment
		(start 191.1 161.7)
		(end 192.1 160.7)
		(width 0.1)
		(layer "In2.Cu")
		(net 106)
	)
	(segment
		(start 185.6 182.666382)
		(end 185.6 178.9)
		(width 0.1)
		(layer "In2.Cu")
		(net 106)
	)
	(segment
		(start 177.4 188)
		(end 178.2 187.2)
		(width 0.1)
		(layer "In2.Cu")
		(net 106)
	)
	(segment
		(start 185.6 178.9)
		(end 191.1 173.4)
		(width 0.1)
		(layer "In2.Cu")
		(net 106)
	)
	(segment
		(start 181.1 187.2)
		(end 181.220606 187.079394)
		(width 0.1)
		(layer "In2.Cu")
		(net 106)
	)
	(segment
		(start 176.6 188)
		(end 177.4 188)
		(width 0.1)
		(layer "In2.Cu")
		(net 106)
	)
	(segment
		(start 147.2 187.3)
		(end 138.65 187.3)
		(width 0.1)
		(layer "In4.Cu")
		(net 106)
	)
	(segment
		(start 148.2 188.3)
		(end 147.2 187.3)
		(width 0.1)
		(layer "In4.Cu")
		(net 106)
	)
	(segment
		(start 138.05 186.3)
		(end 132.59617 186.3)
		(width 0.1)
		(layer "In4.Cu")
		(net 106)
	)
	(segment
		(start 162.8 187.2)
		(end 161.7 188.3)
		(width 0.1)
		(layer "In4.Cu")
		(net 106)
	)
	(segment
		(start 138.35 186.6)
		(end 138.05 186.3)
		(width 0.1)
		(layer "In4.Cu")
		(net 106)
	)
	(segment
		(start 132.59617 186.3)
		(end 132.252001 185.955831)
		(width 0.1)
		(layer "In4.Cu")
		(net 106)
	)
	(segment
		(start 175.8 187.2)
		(end 162.8 187.2)
		(width 0.1)
		(layer "In4.Cu")
		(net 106)
	)
	(segment
		(start 131.252001 185.4255)
		(end 130.877001 185.8005)
		(width 0.1)
		(layer "In4.Cu")
		(net 106)
	)
	(segment
		(start 132.252001 185.645169)
		(end 132.032332 185.4255)
		(width 0.1)
		(layer "In4.Cu")
		(net 106)
	)
	(segment
		(start 132.252001 185.955831)
		(end 132.252001 185.645169)
		(width 0.1)
		(layer "In4.Cu")
		(net 106)
	)
	(segment
		(start 132.032332 185.4255)
		(end 131.252001 185.4255)
		(width 0.1)
		(layer "In4.Cu")
		(net 106)
	)
	(segment
		(start 138.65 187.3)
		(end 138.35 187)
		(width 0.1)
		(layer "In4.Cu")
		(net 106)
	)
	(segment
		(start 138.35 187)
		(end 138.35 186.6)
		(width 0.1)
		(layer "In4.Cu")
		(net 106)
	)
	(segment
		(start 161.7 188.3)
		(end 148.2 188.3)
		(width 0.1)
		(layer "In4.Cu")
		(net 106)
	)
	(segment
		(start 176.6 188)
		(end 175.8 187.2)
		(width 0.1)
		(layer "In4.Cu")
		(net 106)
	)
	(segment
		(start 126.400001 146.8025)
		(end 126.420001 146.8225)
		(width 0.26)
		(layer "F.Cu")
		(net 107)
	)
	(segment
		(start 126.400001 146.2025)
		(end 126.400001 146.8025)
		(width 0.26)
		(layer "F.Cu")
		(net 107)
	)
	(segment
		(start 126.42 147.292427)
		(end 126.375001 147.337426)
		(width 0.26)
		(layer "F.Cu")
		(net 107)
	)
	(segment
		(start 134.376501 162.302)
		(end 133.877001 161.802501)
		(width 0.256)
		(layer "F.Cu")
		(net 107)
	)
	(segment
		(start 126.420001 146.8225)
		(end 126.42 147.292427)
		(width 0.26)
		(layer "F.Cu")
		(net 107)
	)
	(via
		(at 126.375001 147.337426)
		(size 0.45)
		(drill 0.1)
		(layers "F.Cu" "B.Cu")
		(net 107)
	)
	(via
		(at 133.877001 161.802501)
		(size 0.45)
		(drill 0.1)
		(layers "F.Cu" "B.Cu")
		(net 107)
	)
	(segment
		(start 133.156947 160.644852)
		(end 133.156948 160.644852)
		(width 0.13)
		(layer "In6.Cu")
		(net 107)
	)
	(segment
		(start 132.27828 158.508084)
		(end 132.352801 158.582605)
		(width 0.13)
		(layer "In6.Cu")
		(net 107)
	)
	(segment
		(start 131.490408 159.080567)
		(end 131.893182 158.67779)
		(width 0.13)
		(layer "In6.Cu")
		(net 107)
	)
	(segment
		(start 129.027778 156.027778)
		(end 129.305182 155.750377)
		(width 0.13)
		(layer "In6.Cu")
		(net 107)
	)
	(segment
		(start 132.838749 160.326653)
		(end 132.768734 160.396667)
		(width 0.13)
		(layer "In6.Cu")
		(net 107)
	)
	(segment
		(start 129.595094 156.040288)
		(end 129.595093 156.040289)
		(width 0.13)
		(layer "In6.Cu")
		(net 107)
	)
	(segment
		(start 131.359045 157.58885)
		(end 131.359044 157.588848)
		(width 0.13)
		(layer "In6.Cu")
		(net 107)
	)
	(segment
		(start 132.768734 160.396667)
		(end 132.768734 160.396668)
		(width 0.13)
		(layer "In6.Cu")
		(net 107)
	)
	(segment
		(start 127.754718 154.199911)
		(end 127.754717 154.199912)
		(width 0.13)
		(layer "In6.Cu")
		(net 107)
	)
	(segment
		(start 132.278281 158.508086)
		(end 132.27828 158.508084)
		(width 0.13)
		(layer "In6.Cu")
		(net 107)
	)
	(segment
		(start 129.651935 157.242095)
		(end 129.651936 157.242095)
		(width 0.13)
		(layer "In6.Cu")
		(net 107)
	)
	(segment
		(start 127.813463 155.403623)
		(end 127.813464 155.403623)
		(width 0.13)
		(layer "In6.Cu")
		(net 107)
	)
	(segment
		(start 134.162866 162.2025)
		(end 134.288693 162.076673)
		(width 0.1)
		(layer "In6.Cu")
		(net 107)
	)
	(segment
		(start 129.520572 155.750376)
		(end 129.595093 155.824897)
		(width 0.13)
		(layer "In6.Cu")
		(net 107)
	)
	(segment
		(start 132.352801 158.797997)
		(end 132.267948 158.882851)
		(width 0.13)
		(layer "In6.Cu")
		(net 107)
	)
	(segment
		(start 130.51433 156.959524)
		(end 130.514329 156.959525)
		(width 0.13)
		(layer "In6.Cu")
		(net 107)
	)
	(segment
		(start 127.37995 153.994853)
		(end 127.37995 153.994852)
		(width 0.13)
		(layer "In6.Cu")
		(net 107)
	)
	(segment
		(start 128.675857 155.121053)
		(end 128.103375 155.693535)
		(width 0.13)
		(layer "In6.Cu")
		(net 107)
	)
	(segment
		(start 129.022611 157.202929)
		(end 129.061777 157.242095)
		(width 0.13)
		(layer "In6.Cu")
		(net 107)
	)
	(segment
		(start 126.530001 153.699707)
		(end 126.825146 153.994851)
		(width 0.13)
		(layer "In6.Cu")
		(net 107)
	)
	(segment
		(start 134.288693 162.076673)
		(end 134.288693 161.458399)
		(width 0.1)
		(layer "In6.Cu")
		(net 107)
	)
	(segment
		(start 133.877001 162.104501)
		(end 133.975 162.2025)
		(width 0.1)
		(layer "In6.Cu")
		(net 107)
	)
	(segment
		(start 131.490407 159.080567)
		(end 131.490408 159.080567)
		(width 0.13)
		(layer "In6.Cu")
		(net 107)
	)
	(segment
		(start 127.479219 154.479219)
		(end 127.184139 154.774299)
		(width 0.13)
		(layer "In6.Cu")
		(net 107)
	)
	(segment
		(start 127.680196 153.909999)
		(end 127.754717 153.98452)
		(width 0.13)
		(layer "In6.Cu")
		(net 107)
	)
	(segment
		(start 132.267948 159.437655)
		(end 132.267947 159.437653)
		(width 0.13)
		(layer "In6.Cu")
		(net 107)
	)
	(segment
		(start 130.439808 156.669612)
		(end 130.514329 156.744133)
		(width 0.13)
		(layer "In6.Cu")
		(net 107)
	)
	(segment
		(start 128.601336 154.83114)
		(end 128.675857 154.905661)
		(width 0.13)
		(layer "In6.Cu")
		(net 107)
	)
	(segment
		(start 127.37995 153.994852)
		(end 127.464804 153.909999)
		(width 0.13)
		(layer "In6.Cu")
		(net 107)
	)
	(segment
		(start 131.893182 158.67779)
		(end 132.06289 158.508085)
		(width 0.13)
		(layer "In6.Cu")
		(net 107)
	)
	(segment
		(start 129.941847 158.122165)
		(end 129.981013 158.161331)
		(width 0.13)
		(layer "In6.Cu")
		(net 107)
	)
	(segment
		(start 129.520573 155.750378)
		(end 129.520572 155.750376)
		(width 0.13)
		(layer "In6.Cu")
		(net 107)
	)
	(segment
		(start 127.184139 155.364457)
		(end 127.223305 155.403623)
		(width 0.13)
		(layer "In6.Cu")
		(net 107)
	)
	(segment
		(start 128.108542 155.108542)
		(end 128.385946 154.831141)
		(width 0.13)
		(layer "In6.Cu")
		(net 107)
	)
	(segment
		(start 128.601337 154.831142)
		(end 128.601336 154.83114)
		(width 0.13)
		(layer "In6.Cu")
		(net 107)
	)
	(segment
		(start 130.571171 158.161331)
		(end 130.571172 158.161331)
		(width 0.13)
		(layer "In6.Cu")
		(net 107)
	)
	(segment
		(start 131.359044 157.588848)
		(end 131.433565 157.663369)
		(width 0.13)
		(layer "In6.Cu")
		(net 107)
	)
	(segment
		(start 128.675858 155.121052)
		(end 128.675857 155.121053)
		(width 0.13)
		(layer "In6.Cu")
		(net 107)
	)
	(segment
		(start 133.975 162.2025)
		(end 134.162866 162.2025)
		(width 0.1)
		(layer "In6.Cu")
		(net 107)
	)
	(segment
		(start 130.439809 156.669614)
		(end 130.439808 156.669612)
		(width 0.13)
		(layer "In6.Cu")
		(net 107)
	)
	(segment
		(start 133.086933 160.714867)
		(end 133.156947 160.644852)
		(width 0.13)
		(layer "In6.Cu")
		(net 107)
	)
	(segment
		(start 133.877001 161.802501)
		(end 133.877001 162.104501)
		(width 0.1)
		(layer "In6.Cu")
		(net 107)
	)
	(segment
		(start 132.267947 159.437653)
		(end 132.838749 160.008455)
		(width 0.13)
		(layer "In6.Cu")
		(net 107)
	)
	(segment
		(start 132.352802 158.797996)
		(end 132.352801 158.797997)
		(width 0.13)
		(layer "In6.Cu")
		(net 107)
	)
	(segment
		(start 126.530001 147.711628)
		(end 126.530001 153.699707)
		(width 0.13)
		(layer "In6.Cu")
		(net 107)
	)
	(segment
		(start 130.571172 158.161331)
		(end 130.86625 157.86625)
		(width 0.13)
		(layer "In6.Cu")
		(net 107)
	)
	(segment
		(start 128.103375 156.283693)
		(end 128.142541 156.322859)
		(width 0.13)
		(layer "In6.Cu")
		(net 107)
	)
	(segment
		(start 127.754717 154.199912)
		(end 127.477313 154.477313)
		(width 0.13)
		(layer "In6.Cu")
		(net 107)
	)
	(segment
		(start 129.595093 156.040289)
		(end 129.022611 156.612771)
		(width 0.13)
		(layer "In6.Cu")
		(net 107)
	)
	(segment
		(start 129.947014 156.947014)
		(end 130.224418 156.669613)
		(width 0.13)
		(layer "In6.Cu")
		(net 107)
	)
	(segment
		(start 128.7327 156.322859)
		(end 129.027778 156.027778)
		(width 0.13)
		(layer "In6.Cu")
		(net 107)
	)
	(segment
		(start 131.433565 157.878761)
		(end 130.861083 158.451243)
		(width 0.13)
		(layer "In6.Cu")
		(net 107)
	)
	(segment
		(start 133.475147 160.644853)
		(end 133.715147 160.884853)
		(width 0.13)
		(layer "In6.Cu")
		(net 107)
	)
	(segment
		(start 127.477313 154.477313)
		(end 127.479219 154.479219)
		(width 0.13)
		(layer "In6.Cu")
		(net 107)
	)
	(segment
		(start 131.433566 157.87876)
		(end 131.433565 157.878761)
		(width 0.13)
		(layer "In6.Cu")
		(net 107)
	)
	(segment
		(start 130.86625 157.86625)
		(end 131.143654 157.588849)
		(width 0.13)
		(layer "In6.Cu")
		(net 107)
	)
	(segment
		(start 129.651936 157.242095)
		(end 129.947014 156.947014)
		(width 0.13)
		(layer "In6.Cu")
		(net 107)
	)
	(segment
		(start 134.288693 161.458399)
		(end 133.715147 160.884853)
		(width 0.1)
		(layer "In6.Cu")
		(net 107)
	)
	(segment
		(start 128.732699 156.322859)
		(end 128.7327 156.322859)
		(width 0.13)
		(layer "In6.Cu")
		(net 107)
	)
	(segment
		(start 127.813464 155.403623)
		(end 128.108542 155.108542)
		(width 0.13)
		(layer "In6.Cu")
		(net 107)
	)
	(segment
		(start 130.861083 159.041401)
		(end 130.900249 159.080567)
		(width 0.13)
		(layer "In6.Cu")
		(net 107)
	)
	(segment
		(start 130.514329 156.959525)
		(end 129.941847 157.532007)
		(width 0.13)
		(layer "In6.Cu")
		(net 107)
	)
	(arc
		(start 126.530001 147.711628)
		(mid 126.489718 147.509111)
		(end 126.375001 147.337426)
		(width 0.13)
		(layer "In6.Cu")
		(net 107)
	)
	(arc
		(start 127.464804 153.909999)
		(mid 127.572499 153.865389)
		(end 127.680196 153.909999)
		(width 0.13)
		(layer "In6.Cu")
		(net 107)
	)
	(arc
		(start 129.981013 158.161331)
		(mid 130.276092 158.283557)
		(end 130.571171 158.161331)
		(width 0.13)
		(layer "In6.Cu")
		(net 107)
	)
	(arc
		(start 127.223305 155.403623)
		(mid 127.518384 155.525849)
		(end 127.813463 155.403623)
		(width 0.13)
		(layer "In6.Cu")
		(net 107)
	)
	(arc
		(start 126.825146 153.994851)
		(mid 127.102549 154.109756)
		(end 127.37995 153.994853)
		(width 0.13)
		(layer "In6.Cu")
		(net 107)
	)
	(arc
		(start 128.675857 154.905661)
		(mid 128.720466 155.013356)
		(end 128.675858 155.121052)
		(width 0.13)
		(layer "In6.Cu")
		(net 107)
	)
	(arc
		(start 132.06289 158.508085)
		(mid 132.170586 158.463477)
		(end 132.278281 158.508086)
		(width 0.13)
		(layer "In6.Cu")
		(net 107)
	)
	(arc
		(start 129.941847 157.532007)
		(mid 129.819621 157.827086)
		(end 129.941847 158.122165)
		(width 0.13)
		(layer "In6.Cu")
		(net 107)
	)
	(arc
		(start 129.595093 155.824897)
		(mid 129.639702 155.932592)
		(end 129.595094 156.040288)
		(width 0.13)
		(layer "In6.Cu")
		(net 107)
	)
	(arc
		(start 128.103375 155.693535)
		(mid 127.981149 155.988614)
		(end 128.103375 156.283693)
		(width 0.13)
		(layer "In6.Cu")
		(net 107)
	)
	(arc
		(start 128.142541 156.322859)
		(mid 128.43762 156.445085)
		(end 128.732699 156.322859)
		(width 0.13)
		(layer "In6.Cu")
		(net 107)
	)
	(arc
		(start 131.433565 157.663369)
		(mid 131.478174 157.771064)
		(end 131.433566 157.87876)
		(width 0.13)
		(layer "In6.Cu")
		(net 107)
	)
	(arc
		(start 130.514329 156.744133)
		(mid 130.558938 156.851828)
		(end 130.51433 156.959524)
		(width 0.13)
		(layer "In6.Cu")
		(net 107)
	)
	(arc
		(start 129.061777 157.242095)
		(mid 129.356856 157.364321)
		(end 129.651935 157.242095)
		(width 0.13)
		(layer "In6.Cu")
		(net 107)
	)
	(arc
		(start 132.352801 158.582605)
		(mid 132.39741 158.6903)
		(end 132.352802 158.797996)
		(width 0.13)
		(layer "In6.Cu")
		(net 107)
	)
	(arc
		(start 127.754717 153.98452)
		(mid 127.799326 154.092215)
		(end 127.754718 154.199911)
		(width 0.13)
		(layer "In6.Cu")
		(net 107)
	)
	(arc
		(start 129.305182 155.750377)
		(mid 129.412878 155.705769)
		(end 129.520573 155.750378)
		(width 0.13)
		(layer "In6.Cu")
		(net 107)
	)
	(arc
		(start 133.156948 160.644852)
		(mid 133.316047 160.57895)
		(end 133.475147 160.644853)
		(width 0.13)
		(layer "In6.Cu")
		(net 107)
	)
	(arc
		(start 132.768734 160.396668)
		(mid 132.702832 160.555767)
		(end 132.768735 160.714867)
		(width 0.13)
		(layer "In6.Cu")
		(net 107)
	)
	(arc
		(start 132.768735 160.714867)
		(mid 132.927834 160.780768)
		(end 133.086933 160.714867)
		(width 0.13)
		(layer "In6.Cu")
		(net 107)
	)
	(arc
		(start 131.143654 157.588849)
		(mid 131.25135 157.544241)
		(end 131.359045 157.58885)
		(width 0.13)
		(layer "In6.Cu")
		(net 107)
	)
	(arc
		(start 130.224418 156.669613)
		(mid 130.332114 156.625005)
		(end 130.439809 156.669614)
		(width 0.13)
		(layer "In6.Cu")
		(net 107)
	)
	(arc
		(start 128.385946 154.831141)
		(mid 128.493642 154.786533)
		(end 128.601337 154.831142)
		(width 0.13)
		(layer "In6.Cu")
		(net 107)
	)
	(arc
		(start 130.861083 158.451243)
		(mid 130.738857 158.746322)
		(end 130.861083 159.041401)
		(width 0.13)
		(layer "In6.Cu")
		(net 107)
	)
	(arc
		(start 129.022611 156.612771)
		(mid 128.900385 156.90785)
		(end 129.022611 157.202929)
		(width 0.13)
		(layer "In6.Cu")
		(net 107)
	)
	(arc
		(start 132.838749 160.008455)
		(mid 132.90465 160.167554)
		(end 132.838749 160.326653)
		(width 0.13)
		(layer "In6.Cu")
		(net 107)
	)
	(arc
		(start 130.900249 159.080567)
		(mid 131.195328 159.202793)
		(end 131.490407 159.080567)
		(width 0.13)
		(layer "In6.Cu")
		(net 107)
	)
	(arc
		(start 132.267948 158.882851)
		(mid 132.153044 159.160253)
		(end 132.267948 159.437655)
		(width 0.13)
		(layer "In6.Cu")
		(net 107)
	)
	(arc
		(start 127.184139 154.774299)
		(mid 127.061913 155.069378)
		(end 127.184139 155.364457)
		(width 0.13)
		(layer "In6.Cu")
		(net 107)
	)
	(segment
		(start 126.880001 146.8225)
		(end 126.880002 147.292427)
		(width 0.26)
		(layer "F.Cu")
		(net 108)
	)
	(segment
		(start 126.880002 147.292427)
		(end 126.925001 147.337426)
		(width 0.26)
		(layer "F.Cu")
		(net 108)
	)
	(segment
		(start 134.376501 163.302)
		(end 133.877001 162.802499)
		(width 0.256)
		(layer "F.Cu")
		(net 108)
	)
	(segment
		(start 126.900001 146.8025)
		(end 126.880001 146.8225)
		(width 0.26)
		(layer "F.Cu")
		(net 108)
	)
	(segment
		(start 126.900001 146.2025)
		(end 126.900001 146.8025)
		(width 0.26)
		(layer "F.Cu")
		(net 108)
	)
	(via
		(at 126.925001 147.337426)
		(size 0.45)
		(drill 0.1)
		(layers "F.Cu" "B.Cu")
		(net 108)
	)
	(via
		(at 133.877001 162.802499)
		(size 0.45)
		(drill 0.1)
		(layers "F.Cu" "B.Cu")
		(net 108)
	)
	(segment
		(start 134.498693 162.149517)
		(end 134.498693 161.328987)
		(width 0.1)
		(layer "In6.Cu")
		(net 108)
	)
	(segment
		(start 128.27308 156.113987)
		(end 128.312246 156.153153)
		(width 0.13)
		(layer "In6.Cu")
		(net 108)
	)
	(segment
		(start 128.845563 155.290759)
		(end 128.568161 155.568162)
		(width 0.13)
		(layer "In6.Cu")
		(net 108)
	)
	(segment
		(start 127.849901 153.740294)
		(end 127.924422 153.814815)
		(width 0.13)
		(layer "In6.Cu")
		(net 108)
	)
	(segment
		(start 127.643757 155.233917)
		(end 128.216238 154.661433)
		(width 0.13)
		(layer "In6.Cu")
		(net 108)
	)
	(segment
		(start 131.030788 158.871695)
		(end 131.069954 158.910861)
		(width 0.13)
		(layer "In6.Cu")
		(net 108)
	)
	(segment
		(start 127.353844 155.194751)
		(end 127.39301 155.233917)
		(width 0.13)
		(layer "In6.Cu")
		(net 108)
	)
	(segment
		(start 129.690279 155.580672)
		(end 129.690278 155.58067)
		(width 0.13)
		(layer "In6.Cu")
		(net 108)
	)
	(segment
		(start 131.603271 158.048467)
		(end 131.325869 158.32587)
		(width 0.13)
		(layer "In6.Cu")
		(net 108)
	)
	(segment
		(start 130.406633 157.406634)
		(end 130.406632 157.406632)
		(width 0.13)
		(layer "In6.Cu")
		(net 108)
	)
	(segment
		(start 132.522508 158.967702)
		(end 132.522507 158.967703)
		(width 0.13)
		(layer "In6.Cu")
		(net 108)
	)
	(segment
		(start 127.643757 155.233918)
		(end 127.643757 155.233917)
		(width 0.13)
		(layer "In6.Cu")
		(net 108)
	)
	(segment
		(start 131.030788 158.871696)
		(end 131.030788 158.871695)
		(width 0.13)
		(layer "In6.Cu")
		(net 108)
	)
	(segment
		(start 126.770001 147.711671)
		(end 126.770001 153.600295)
		(width 0.13)
		(layer "In6.Cu")
		(net 108)
	)
	(segment
		(start 128.27308 156.113988)
		(end 128.27308 156.113987)
		(width 0.13)
		(layer "In6.Cu")
		(net 108)
	)
	(segment
		(start 132.437654 159.267949)
		(end 133.884853 160.715147)
		(width 0.13)
		(layer "In6.Cu")
		(net 108)
	)
	(segment
		(start 130.684035 157.129231)
		(end 130.406633 157.406634)
		(width 0.13)
		(layer "In6.Cu")
		(net 108)
	)
	(segment
		(start 128.845564 155.290758)
		(end 128.845563 155.290759)
		(width 0.13)
		(layer "In6.Cu")
		(net 108)
	)
	(segment
		(start 130.684036 157.12923)
		(end 130.684035 157.129231)
		(width 0.13)
		(layer "In6.Cu")
		(net 108)
	)
	(segment
		(start 129.690278 155.58067)
		(end 129.764799 155.655191)
		(width 0.13)
		(layer "In6.Cu")
		(net 108)
	)
	(segment
		(start 130.111552 157.952459)
		(end 130.150718 157.991625)
		(width 0.13)
		(layer "In6.Cu")
		(net 108)
	)
	(segment
		(start 128.56816 155.56816)
		(end 128.27308 155.86324)
		(width 0.13)
		(layer "In6.Cu")
		(net 108)
	)
	(segment
		(start 131.325869 158.32587)
		(end 131.325868 158.325868)
		(width 0.13)
		(layer "In6.Cu")
		(net 108)
	)
	(segment
		(start 127.647018 154.64702)
		(end 127.648924 154.648924)
		(width 0.13)
		(layer "In6.Cu")
		(net 108)
	)
	(segment
		(start 128.771042 154.661434)
		(end 128.845563 154.735955)
		(width 0.13)
		(layer "In6.Cu")
		(net 108)
	)
	(segment
		(start 131.603272 158.048466)
		(end 131.603271 158.048467)
		(width 0.13)
		(layer "In6.Cu")
		(net 108)
	)
	(segment
		(start 127.210245 153.825148)
		(end 127.295097 153.740293)
		(width 0.13)
		(layer "In6.Cu")
		(net 108)
	)
	(segment
		(start 130.406632 157.406632)
		(end 130.111552 157.701712)
		(width 0.13)
		(layer "In6.Cu")
		(net 108)
	)
	(segment
		(start 133.979 162.402498)
		(end 134.245712 162.402498)
		(width 0.1)
		(layer "In6.Cu")
		(net 108)
	)
	(segment
		(start 131.320701 158.910862)
		(end 131.320701 158.910861)
		(width 0.13)
		(layer "In6.Cu")
		(net 108)
	)
	(segment
		(start 128.562993 156.153153)
		(end 129.135474 155.580669)
		(width 0.13)
		(layer "In6.Cu")
		(net 108)
	)
	(segment
		(start 130.609515 156.499908)
		(end 130.609514 156.499906)
		(width 0.13)
		(layer "In6.Cu")
		(net 108)
	)
	(segment
		(start 134.498693 161.328987)
		(end 133.884853 160.715147)
		(width 0.1)
		(layer "In6.Cu")
		(net 108)
	)
	(segment
		(start 126.770001 153.600295)
		(end 126.994851 153.825146)
		(width 0.13)
		(layer "In6.Cu")
		(net 108)
	)
	(segment
		(start 129.482229 157.07239)
		(end 129.482229 157.072389)
		(width 0.13)
		(layer "In6.Cu")
		(net 108)
	)
	(segment
		(start 132.522507 158.967703)
		(end 132.437654 159.052557)
		(width 0.13)
		(layer "In6.Cu")
		(net 108)
	)
	(segment
		(start 130.111552 157.95246)
		(end 130.111552 157.952459)
		(width 0.13)
		(layer "In6.Cu")
		(net 108)
	)
	(segment
		(start 134.245712 162.402498)
		(end 134.498693 162.149517)
		(width 0.1)
		(layer "In6.Cu")
		(net 108)
	)
	(segment
		(start 131.52875 157.419142)
		(end 131.603271 157.493663)
		(width 0.13)
		(layer "In6.Cu")
		(net 108)
	)
	(segment
		(start 133.877001 162.504497)
		(end 133.979 162.402498)
		(width 0.1)
		(layer "In6.Cu")
		(net 108)
	)
	(segment
		(start 127.353844 155.194752)
		(end 127.353844 155.194751)
		(width 0.13)
		(layer "In6.Cu")
		(net 108)
	)
	(segment
		(start 131.528751 157.419144)
		(end 131.52875 157.419142)
		(width 0.13)
		(layer "In6.Cu")
		(net 108)
	)
	(segment
		(start 129.7648 156.209994)
		(end 129.764799 156.209995)
		(width 0.13)
		(layer "In6.Cu")
		(net 108)
	)
	(segment
		(start 130.401465 157.991625)
		(end 130.973946 157.419141)
		(width 0.13)
		(layer "In6.Cu")
		(net 108)
	)
	(segment
		(start 130.609514 156.499906)
		(end 130.684035 156.574427)
		(width 0.13)
		(layer "In6.Cu")
		(net 108)
	)
	(segment
		(start 132.447987 158.33838)
		(end 132.447986 158.338378)
		(width 0.13)
		(layer "In6.Cu")
		(net 108)
	)
	(segment
		(start 129.487397 156.487398)
		(end 129.487396 156.487396)
		(width 0.13)
		(layer "In6.Cu")
		(net 108)
	)
	(segment
		(start 127.648924 154.648924)
		(end 127.353844 154.944004)
		(width 0.13)
		(layer "In6.Cu")
		(net 108)
	)
	(segment
		(start 127.849901 153.740293)
		(end 127.849901 153.740294)
		(width 0.13)
		(layer "In6.Cu")
		(net 108)
	)
	(segment
		(start 129.487396 156.487396)
		(end 129.192316 156.782476)
		(width 0.13)
		(layer "In6.Cu")
		(net 108)
	)
	(segment
		(start 129.192316 157.033223)
		(end 129.231482 157.072389)
		(width 0.13)
		(layer "In6.Cu")
		(net 108)
	)
	(segment
		(start 129.192316 157.033224)
		(end 129.192316 157.033223)
		(width 0.13)
		(layer "In6.Cu")
		(net 108)
	)
	(segment
		(start 127.924423 154.369618)
		(end 127.924422 154.369619)
		(width 0.13)
		(layer "In6.Cu")
		(net 108)
	)
	(segment
		(start 132.447986 158.338378)
		(end 132.522507 158.412899)
		(width 0.13)
		(layer "In6.Cu")
		(net 108)
	)
	(segment
		(start 133.877001 162.802499)
		(end 133.877001 162.504497)
		(width 0.1)
		(layer "In6.Cu")
		(net 108)
	)
	(segment
		(start 129.482229 157.072389)
		(end 130.05471 156.499905)
		(width 0.13)
		(layer "In6.Cu")
		(net 108)
	)
	(segment
		(start 128.771043 154.661436)
		(end 128.771042 154.661434)
		(width 0.13)
		(layer "In6.Cu")
		(net 108)
	)
	(segment
		(start 127.924422 154.369619)
		(end 127.647018 154.64702)
		(width 0.13)
		(layer "In6.Cu")
		(net 108)
	)
	(segment
		(start 129.764799 156.209995)
		(end 129.487397 156.487398)
		(width 0.13)
		(layer "In6.Cu")
		(net 108)
	)
	(segment
		(start 128.568161 155.568162)
		(end 128.56816 155.56816)
		(width 0.13)
		(layer "In6.Cu")
		(net 108)
	)
	(segment
		(start 131.320701 158.910861)
		(end 131.893182 158.338377)
		(width 0.13)
		(layer "In6.Cu")
		(net 108)
	)
	(segment
		(start 131.325868 158.325868)
		(end 131.030788 158.620948)
		(width 0.13)
		(layer "In6.Cu")
		(net 108)
	)
	(segment
		(start 128.562993 156.153154)
		(end 128.562993 156.153153)
		(width 0.13)
		(layer "In6.Cu")
		(net 108)
	)
	(segment
		(start 130.401465 157.991626)
		(end 130.401465 157.991625)
		(width 0.13)
		(layer "In6.Cu")
		(net 108)
	)
	(arc
		(start 126.770001 147.711671)
		(mid 126.810292 147.509114)
		(end 126.925001 147.337426)
		(width 0.13)
		(layer "In6.Cu")
		(net 108)
	)
	(arc
		(start 130.05471 156.499905)
		(mid 130.332113 156.385003)
		(end 130.609515 156.499908)
		(width 0.13)
		(layer "In6.Cu")
		(net 108)
	)
	(arc
		(start 129.192316 156.782476)
		(mid 129.140384 156.90785)
		(end 129.192316 157.033224)
		(width 0.13)
		(layer "In6.Cu")
		(net 108)
	)
	(arc
		(start 128.216238 154.661433)
		(mid 128.493641 154.546531)
		(end 128.771043 154.661436)
		(width 0.13)
		(layer "In6.Cu")
		(net 108)
	)
	(arc
		(start 130.150718 157.991625)
		(mid 130.276091 158.043557)
		(end 130.401465 157.991626)
		(width 0.13)
		(layer "In6.Cu")
		(net 108)
	)
	(arc
		(start 129.764799 155.655191)
		(mid 129.879704 155.932593)
		(end 129.7648 156.209994)
		(width 0.13)
		(layer "In6.Cu")
		(net 108)
	)
	(arc
		(start 131.893182 158.338377)
		(mid 132.170585 158.223475)
		(end 132.447987 158.33838)
		(width 0.13)
		(layer "In6.Cu")
		(net 108)
	)
	(arc
		(start 127.353844 154.944004)
		(mid 127.301912 155.069378)
		(end 127.353844 155.194752)
		(width 0.13)
		(layer "In6.Cu")
		(net 108)
	)
	(arc
		(start 130.684035 156.574427)
		(mid 130.79894 156.851829)
		(end 130.684036 157.12923)
		(width 0.13)
		(layer "In6.Cu")
		(net 108)
	)
	(arc
		(start 128.312246 156.153153)
		(mid 128.437619 156.205085)
		(end 128.562993 156.153154)
		(width 0.13)
		(layer "In6.Cu")
		(net 108)
	)
	(arc
		(start 127.924422 153.814815)
		(mid 128.039325 154.092215)
		(end 127.924423 154.369618)
		(width 0.13)
		(layer "In6.Cu")
		(net 108)
	)
	(arc
		(start 128.845563 154.735955)
		(mid 128.960468 155.013357)
		(end 128.845564 155.290758)
		(width 0.13)
		(layer "In6.Cu")
		(net 108)
	)
	(arc
		(start 129.135474 155.580669)
		(mid 129.412877 155.465767)
		(end 129.690279 155.580672)
		(width 0.13)
		(layer "In6.Cu")
		(net 108)
	)
	(arc
		(start 131.069954 158.910861)
		(mid 131.195327 158.962793)
		(end 131.320701 158.910862)
		(width 0.13)
		(layer "In6.Cu")
		(net 108)
	)
	(arc
		(start 131.030788 158.620948)
		(mid 130.978856 158.746322)
		(end 131.030788 158.871696)
		(width 0.13)
		(layer "In6.Cu")
		(net 108)
	)
	(arc
		(start 130.111552 157.701712)
		(mid 130.05962 157.827086)
		(end 130.111552 157.95246)
		(width 0.13)
		(layer "In6.Cu")
		(net 108)
	)
	(arc
		(start 127.295097 153.740293)
		(mid 127.572499 153.625389)
		(end 127.849901 153.740293)
		(width 0.13)
		(layer "In6.Cu")
		(net 108)
	)
	(arc
		(start 132.522507 158.412899)
		(mid 132.637412 158.690301)
		(end 132.522508 158.967702)
		(width 0.13)
		(layer "In6.Cu")
		(net 108)
	)
	(arc
		(start 129.231482 157.072389)
		(mid 129.356855 157.124321)
		(end 129.482229 157.07239)
		(width 0.13)
		(layer "In6.Cu")
		(net 108)
	)
	(arc
		(start 131.603271 157.493663)
		(mid 131.718176 157.771065)
		(end 131.603272 158.048466)
		(width 0.13)
		(layer "In6.Cu")
		(net 108)
	)
	(arc
		(start 128.27308 155.86324)
		(mid 128.221148 155.988614)
		(end 128.27308 156.113988)
		(width 0.13)
		(layer "In6.Cu")
		(net 108)
	)
	(arc
		(start 126.994851 153.825146)
		(mid 127.102548 153.869756)
		(end 127.210245 153.825148)
		(width 0.13)
		(layer "In6.Cu")
		(net 108)
	)
	(arc
		(start 130.973946 157.419141)
		(mid 131.251349 157.304239)
		(end 131.528751 157.419144)
		(width 0.13)
		(layer "In6.Cu")
		(net 108)
	)
	(arc
		(start 127.39301 155.233917)
		(mid 127.518383 155.285849)
		(end 127.643757 155.233918)
		(width 0.13)
		(layer "In6.Cu")
		(net 108)
	)
	(arc
		(start 132.437654 159.052557)
		(mid 132.393044 159.160252)
		(end 132.437654 159.267949)
		(width 0.13)
		(layer "In6.Cu")
		(net 108)
	)
	(segment
		(start 135.376501 162.302)
		(end 134.877001 161.802501)
		(width 0.256)
		(layer "F.Cu")
		(net 109)
	)
	(segment
		(start 127.150001 138.8025)
		(end 127.150001 139.8775)
		(width 0.201)
		(layer "F.Cu")
		(net 109)
	)
	(via
		(at 134.877001 161.802501)
		(size 0.45)
		(drill 0.1)
		(layers "F.Cu" "B.Cu")
		(net 109)
	)
	(via
		(at 127.150001 139.8775)
		(size 0.45)
		(drill 0.1)
		(layers "F.Cu" "B.Cu")
		(net 109)
	)
	(segment
		(start 126.062295 142.62)
		(end 126.637705 142.62)
		(width 0.148)
		(layer "In6.Cu")
		(net 109)
	)
	(segment
		(start 126.062295 143.12)
		(end 126.637705 143.12)
		(width 0.148)
		(layer "In6.Cu")
		(net 109)
	)
	(segment
		(start 126.637705 143.62)
		(end 126.6 143.62)
		(width 0.148)
		(layer "In6.Cu")
		(net 109)
	)
	(segment
		(start 126.35 143.87)
		(end 126.35 146.141771)
		(width 0.148)
		(layer "In6.Cu")
		(net 109)
	)
	(segment
		(start 126.6 141.62)
		(end 126.062295 141.62)
		(width 0.148)
		(layer "In6.Cu")
		(net 109)
	)
	(segment
		(start 126.6 141.12)
		(end 126.637705 141.12)
		(width 0.148)
		(layer "In6.Cu")
		(net 109)
	)
	(segment
		(start 126.062295 142.12)
		(end 126.637705 142.12)
		(width 0.148)
		(layer "In6.Cu")
		(net 109)
	)
	(segment
		(start 134.877001 160.377001)
		(end 134.877001 161.802501)
		(width 0.148)
		(layer "In6.Cu")
		(net 109)
	)
	(segment
		(start 127.150001 139.8775)
		(end 126.35 140.677501)
		(width 0.148)
		(layer "In6.Cu")
		(net 109)
	)
	(segment
		(start 127.400501 147.192272)
		(end 127.400501 152.900501)
		(width 0.148)
		(layer "In6.Cu")
		(net 109)
	)
	(segment
		(start 126.35 146.141771)
		(end 127.400501 147.192272)
		(width 0.148)
		(layer "In6.Cu")
		(net 109)
	)
	(segment
		(start 126.637705 141.62)
		(end 126.6 141.62)
		(width 0.148)
		(layer "In6.Cu")
		(net 109)
	)
	(segment
		(start 127.400501 152.900501)
		(end 134.877001 160.377001)
		(width 0.148)
		(layer "In6.Cu")
		(net 109)
	)
	(segment
		(start 126.35 140.677501)
		(end 126.35 140.87)
		(width 0.148)
		(layer "In6.Cu")
		(net 109)
	)
	(arc
		(start 125.812295 141.87)
		(mid 125.885518 142.046777)
		(end 126.062295 142.12)
		(width 0.148)
		(layer "In6.Cu")
		(net 109)
	)
	(arc
		(start 126.6 143.62)
		(mid 126.423223 143.693223)
		(end 126.35 143.87)
		(width 0.148)
		(layer "In6.Cu")
		(net 109)
	)
	(arc
		(start 126.637705 141.12)
		(mid 126.814482 141.193223)
		(end 126.887705 141.37)
		(width 0.148)
		(layer "In6.Cu")
		(net 109)
	)
	(arc
		(start 126.637705 143.12)
		(mid 126.814482 143.193223)
		(end 126.887705 143.37)
		(width 0.148)
		(layer "In6.Cu")
		(net 109)
	)
	(arc
		(start 126.887705 141.37)
		(mid 126.814482 141.546777)
		(end 126.637705 141.62)
		(width 0.148)
		(layer "In6.Cu")
		(net 109)
	)
	(arc
		(start 126.35 140.87)
		(mid 126.423223 141.046777)
		(end 126.6 141.12)
		(width 0.148)
		(layer "In6.Cu")
		(net 109)
	)
	(arc
		(start 126.887705 142.37)
		(mid 126.814482 142.546777)
		(end 126.637705 142.62)
		(width 0.148)
		(layer "In6.Cu")
		(net 109)
	)
	(arc
		(start 126.062295 141.62)
		(mid 125.885518 141.693223)
		(end 125.812295 141.87)
		(width 0.148)
		(layer "In6.Cu")
		(net 109)
	)
	(arc
		(start 126.887705 143.37)
		(mid 126.814482 143.546777)
		(end 126.637705 143.62)
		(width 0.148)
		(layer "In6.Cu")
		(net 109)
	)
	(arc
		(start 126.062295 142.62)
		(mid 125.885518 142.693223)
		(end 125.812295 142.87)
		(width 0.148)
		(layer "In6.Cu")
		(net 109)
	)
	(arc
		(start 126.637705 142.12)
		(mid 126.814482 142.193223)
		(end 126.887705 142.37)
		(width 0.148)
		(layer "In6.Cu")
		(net 109)
	)
	(arc
		(start 125.812295 142.87)
		(mid 125.885518 143.046777)
		(end 126.062295 143.12)
		(width 0.148)
		(layer "In6.Cu")
		(net 109)
	)
	(segment
		(start 127.900001 146.1525)
		(end 127.900001 147.2275)
		(width 0.201)
		(layer "F.Cu")
		(net 110)
	)
	(segment
		(start 137.376501 164.302)
		(end 136.877001 163.8025)
		(width 0.256)
		(layer "F.Cu")
		(net 110)
	)
	(via
		(at 136.877001 163.8025)
		(size 0.45)
		(drill 0.1)
		(layers "F.Cu" "B.Cu")
		(net 110)
	)
	(via
		(at 127.900001 147.2275)
		(size 0.45)
		(drill 0.1)
		(layers "F.Cu" "B.Cu")
		(net 110)
	)
	(segment
		(start 134.459664 158.646663)
		(end 134.459662 158.646662)
		(width 0.148)
		(layer "In6.Cu")
		(net 110)
	)
	(segment
		(start 134.610309 159.20312)
		(end 134.610309 159.203121)
		(width 0.148)
		(layer "In6.Cu")
		(net 110)
	)
	(segment
		(start 131.631248 155.818247)
		(end 131.631246 155.818246)
		(width 0.148)
		(layer "In6.Cu")
		(net 110)
	)
	(segment
		(start 135.375501 163.111)
		(end 135.565501 163.301)
		(width 0.148)
		(layer "In6.Cu")
		(net 110)
	)
	(segment
		(start 130.419945 153.84758)
		(end 130.419946 153.847581)
		(width 0.148)
		(layer "In6.Cu")
		(net 110)
	)
	(segment
		(start 128.626053 152.459499)
		(end 128.626054 152.459501)
		(width 0.148)
		(layer "In6.Cu")
		(net 110)
	)
	(segment
		(start 132.488997 157.081808)
		(end 132.488997 157.081809)
		(width 0.148)
		(layer "In6.Cu")
		(net 110)
	)
	(segment
		(start 131.127049 154.908237)
		(end 130.924144 155.111143)
		(width 0.148)
		(layer "In6.Cu")
		(net 110)
	)
	(segment
		(start 131.428339 156.374704)
		(end 131.42834 156.374705)
		(width 0.148)
		(layer "In6.Cu")
		(net 110)
	)
	(segment
		(start 133.248361 157.02955)
		(end 133.248361 157.029549)
		(width 0.148)
		(layer "In6.Cu")
		(net 110)
	)
	(segment
		(start 131.127049 154.908238)
		(end 131.127049 154.908237)
		(width 0.148)
		(layer "In6.Cu")
		(net 110)
	)
	(segment
		(start 129.509936 153.696935)
		(end 129.509934 153.696934)
		(width 0.148)
		(layer "In6.Cu")
		(net 110)
	)
	(segment
		(start 133.903205 158.496017)
		(end 134.309014 158.090203)
		(width 0.148)
		(layer "In6.Cu")
		(net 110)
	)
	(segment
		(start 133.752558 157.939558)
		(end 133.549652 158.142463)
		(width 0.148)
		(layer "In6.Cu")
		(net 110)
	)
	(segment
		(start 133.549651 158.496016)
		(end 133.549652 158.496017)
		(width 0.148)
		(layer "In6.Cu")
		(net 110)
	)
	(segment
		(start 134.662569 158.443758)
		(end 134.662569 158.443757)
		(width 0.148)
		(layer "In6.Cu")
		(net 110)
	)
	(segment
		(start 129.660581 154.253392)
		(end 129.660581 154.253393)
		(width 0.148)
		(layer "In6.Cu")
		(net 110)
	)
	(segment
		(start 130.419945 154.201134)
		(end 130.419945 154.201133)
		(width 0.148)
		(layer "In6.Cu")
		(net 110)
	)
	(segment
		(start 130.367685 154.960496)
		(end 130.367685 154.960497)
		(width 0.148)
		(layer "In6.Cu")
		(net 110)
	)
	(segment
		(start 133.955465 157.736653)
		(end 133.75256 157.939559)
		(width 0.148)
		(layer "In6.Cu")
		(net 110)
	)
	(segment
		(start 134.256755 159.20312)
		(end 134.256756 159.203121)
		(width 0.148)
		(layer "In6.Cu")
		(net 110)
	)
	(segment
		(start 132.541257 155.968892)
		(end 132.541258 155.968893)
		(width 0.148)
		(layer "In6.Cu")
		(net 110)
	)
	(segment
		(start 132.135443 157.081808)
		(end 132.135444 157.081809)
		(width 0.148)
		(layer "In6.Cu")
		(net 110)
	)
	(segment
		(start 131.781893 156.374704)
		(end 131.781893 156.374705)
		(width 0.148)
		(layer "In6.Cu")
		(net 110)
	)
	(segment
		(start 133.75256 157.939559)
		(end 133.752558 157.939558)
		(width 0.148)
		(layer "In6.Cu")
		(net 110)
	)
	(segment
		(start 128.599923 153.546288)
		(end 128.599924 153.546289)
		(width 0.148)
		(layer "In6.Cu")
		(net 110)
	)
	(segment
		(start 133.903205 158.496016)
		(end 133.903205 158.496017)
		(width 0.148)
		(layer "In6.Cu")
		(net 110)
	)
	(segment
		(start 131.834153 155.615342)
		(end 131.834153 155.615341)
		(width 0.148)
		(layer "In6.Cu")
		(net 110)
	)
	(segment
		(start 129.712841 153.140476)
		(end 129.712842 153.140477)
		(width 0.148)
		(layer "In6.Cu")
		(net 110)
	)
	(segment
		(start 130.924144 155.111143)
		(end 130.924142 155.111142)
		(width 0.148)
		(layer "In6.Cu")
		(net 110)
	)
	(segment
		(start 135.375501 159.562501)
		(end 135.375501 163.111)
		(width 0.148)
		(layer "In6.Cu")
		(net 110)
	)
	(segment
		(start 131.781893 156.374705)
		(end 132.187702 155.968891)
		(width 0.148)
		(layer "In6.Cu")
		(net 110)
	)
	(segment
		(start 134.989991 159.176991)
		(end 135.375501 159.562501)
		(width 0.148)
		(layer "In6.Cu")
		(net 110)
	)
	(segment
		(start 132.541257 156.322445)
		(end 132.338352 156.525351)
		(width 0.148)
		(layer "In6.Cu")
		(net 110)
	)
	(segment
		(start 129.509934 153.696934)
		(end 129.307028 153.899839)
		(width 0.148)
		(layer "In6.Cu")
		(net 110)
	)
	(segment
		(start 127.900001 147.2275)
		(end 127.900501 147.228)
		(width 0.148)
		(layer "In6.Cu")
		(net 110)
	)
	(segment
		(start 134.610309 159.203121)
		(end 134.636438 159.176991)
		(width 0.148)
		(layer "In6.Cu")
		(net 110)
	)
	(segment
		(start 129.005735 152.786923)
		(end 128.599924 153.192735)
		(width 0.148)
		(layer "In6.Cu")
		(net 110)
	)
	(segment
		(start 133.196101 157.788912)
		(end 133.196101 157.788913)
		(width 0.148)
		(layer "In6.Cu")
		(net 110)
	)
	(segment
		(start 133.248361 157.029549)
		(end 133.045456 157.232455)
		(width 0.148)
		(layer "In6.Cu")
		(net 110)
	)
	(segment
		(start 133.045454 157.232454)
		(end 132.842548 157.435359)
		(width 0.148)
		(layer "In6.Cu")
		(net 110)
	)
	(segment
		(start 130.21704 154.404039)
		(end 130.217038 154.404038)
		(width 0.148)
		(layer "In6.Cu")
		(net 110)
	)
	(segment
		(start 135.565501 163.301)
		(end 136.375501 163.301)
		(width 0.148)
		(layer "In6.Cu")
		(net 110)
	)
	(segment
		(start 129.712841 153.49403)
		(end 129.712841 153.494029)
		(width 0.148)
		(layer "In6.Cu")
		(net 110)
	)
	(segment
		(start 129.307027 154.253392)
		(end 129.307028 154.253393)
		(width 0.148)
		(layer "In6.Cu")
		(net 110)
	)
	(segment
		(start 133.955465 157.3831)
		(end 133.955466 157.383101)
		(width 0.148)
		(layer "In6.Cu")
		(net 110)
	)
	(segment
		(start 130.924142 155.111142)
		(end 130.721236 155.314047)
		(width 0.148)
		(layer "In6.Cu")
		(net 110)
	)
	(segment
		(start 132.338352 156.525351)
		(end 132.33835 156.52535)
		(width 0.148)
		(layer "In6.Cu")
		(net 110)
	)
	(segment
		(start 132.842547 157.788912)
		(end 132.842548 157.788913)
		(width 0.148)
		(layer "In6.Cu")
		(net 110)
	)
	(segment
		(start 130.217038 154.404038)
		(end 130.014132 154.606943)
		(width 0.148)
		(layer "In6.Cu")
		(net 110)
	)
	(segment
		(start 134.662569 158.443757)
		(end 134.459664 158.646663)
		(width 0.148)
		(layer "In6.Cu")
		(net 110)
	)
	(segment
		(start 136.375501 163.301)
		(end 136.877001 163.8025)
		(width 0.148)
		(layer "In6.Cu")
		(net 110)
	)
	(segment
		(start 134.459662 158.646662)
		(end 134.256756 158.849567)
		(width 0.148)
		(layer "In6.Cu")
		(net 110)
	)
	(segment
		(start 129.005735 152.786924)
		(end 129.005735 152.786923)
		(width 0.148)
		(layer "In6.Cu")
		(net 110)
	)
	(segment
		(start 133.955465 157.736654)
		(end 133.955465 157.736653)
		(width 0.148)
		(layer "In6.Cu")
		(net 110)
	)
	(segment
		(start 132.541257 156.322446)
		(end 132.541257 156.322445)
		(width 0.148)
		(layer "In6.Cu")
		(net 110)
	)
	(segment
		(start 132.33835 156.52535)
		(end 132.135444 156.728255)
		(width 0.148)
		(layer "In6.Cu")
		(net 110)
	)
	(segment
		(start 127.900501 152.087501)
		(end 128.2725 152.4595)
		(width 0.148)
		(layer "In6.Cu")
		(net 110)
	)
	(segment
		(start 133.248361 156.675996)
		(end 133.248362 156.675997)
		(width 0.148)
		(layer "In6.Cu")
		(net 110)
	)
	(segment
		(start 132.488997 157.081809)
		(end 132.894806 156.675995)
		(width 0.148)
		(layer "In6.Cu")
		(net 110)
	)
	(segment
		(start 133.045456 157.232455)
		(end 133.045454 157.232454)
		(width 0.148)
		(layer "In6.Cu")
		(net 110)
	)
	(segment
		(start 131.074789 155.6676)
		(end 131.074789 155.667601)
		(width 0.148)
		(layer "In6.Cu")
		(net 110)
	)
	(segment
		(start 127.900501 147.228)
		(end 127.900501 152.087501)
		(width 0.148)
		(layer "In6.Cu")
		(net 110)
	)
	(segment
		(start 131.834153 155.261788)
		(end 131.834154 155.261789)
		(width 0.148)
		(layer "In6.Cu")
		(net 110)
	)
	(segment
		(start 130.014131 154.960496)
		(end 130.014132 154.960497)
		(width 0.148)
		(layer "In6.Cu")
		(net 110)
	)
	(segment
		(start 130.419945 154.201133)
		(end 130.21704 154.404039)
		(width 0.148)
		(layer "In6.Cu")
		(net 110)
	)
	(segment
		(start 128.953477 153.546289)
		(end 129.359286 153.140475)
		(width 0.148)
		(layer "In6.Cu")
		(net 110)
	)
	(segment
		(start 130.721235 155.6676)
		(end 130.721236 155.667601)
		(width 0.148)
		(layer "In6.Cu")
		(net 110)
	)
	(segment
		(start 131.631246 155.818246)
		(end 131.42834 156.021151)
		(width 0.148)
		(layer "In6.Cu")
		(net 110)
	)
	(segment
		(start 129.660581 154.253393)
		(end 130.06639 153.847579)
		(width 0.148)
		(layer "In6.Cu")
		(net 110)
	)
	(segment
		(start 129.005735 152.433371)
		(end 129.005736 152.433371)
		(width 0.148)
		(layer "In6.Cu")
		(net 110)
	)
	(segment
		(start 134.662569 158.090204)
		(end 134.66257 158.090205)
		(width 0.148)
		(layer "In6.Cu")
		(net 110)
	)
	(segment
		(start 129.712841 153.494029)
		(end 129.509936 153.696935)
		(width 0.148)
		(layer "In6.Cu")
		(net 110)
	)
	(segment
		(start 133.196101 157.788913)
		(end 133.60191 157.383099)
		(width 0.148)
		(layer "In6.Cu")
		(net 110)
	)
	(segment
		(start 131.127049 154.554684)
		(end 131.12705 154.554685)
		(width 0.148)
		(layer "In6.Cu")
		(net 110)
	)
	(segment
		(start 130.367685 154.960497)
		(end 130.773494 154.554683)
		(width 0.148)
		(layer "In6.Cu")
		(net 110)
	)
	(segment
		(start 128.953477 153.546288)
		(end 128.953477 153.546289)
		(width 0.148)
		(layer "In6.Cu")
		(net 110)
	)
	(segment
		(start 131.074789 155.667601)
		(end 131.480598 155.261787)
		(width 0.148)
		(layer "In6.Cu")
		(net 110)
	)
	(segment
		(start 128.626054 152.459501)
		(end 128.652182 152.43337)
		(width 0.148)
		(layer "In6.Cu")
		(net 110)
	)
	(segment
		(start 134.989991 159.176992)
		(end 134.989991 159.176991)
		(width 0.148)
		(layer "In6.Cu")
		(net 110)
	)
	(segment
		(start 131.834153 155.615341)
		(end 131.631248 155.818247)
		(width 0.148)
		(layer "In6.Cu")
		(net 110)
	)
	(arc
		(start 128.599924 153.546289)
		(mid 128.776701 153.619512)
		(end 128.953477 153.546288)
		(width 0.148)
		(layer "In6.Cu")
		(net 110)
	)
	(arc
		(start 128.599924 153.192735)
		(mid 128.5267 153.369511)
		(end 128.599923 153.546288)
		(width 0.148)
		(layer "In6.Cu")
		(net 110)
	)
	(arc
		(start 128.2725 152.4595)
		(mid 128.449277 152.532723)
		(end 128.626053 152.459499)
		(width 0.148)
		(layer "In6.Cu")
		(net 110)
	)
	(arc
		(start 130.06639 153.847579)
		(mid 130.243168 153.774357)
		(end 130.419945 153.84758)
		(width 0.148)
		(layer "In6.Cu")
		(net 110)
	)
	(arc
		(start 132.541258 155.968893)
		(mid 132.614481 156.14567)
		(end 132.541257 156.322446)
		(width 0.148)
		(layer "In6.Cu")
		(net 110)
	)
	(arc
		(start 129.712842 153.140477)
		(mid 129.786065 153.317254)
		(end 129.712841 153.49403)
		(width 0.148)
		(layer "In6.Cu")
		(net 110)
	)
	(arc
		(start 132.135444 156.728255)
		(mid 132.06222 156.905031)
		(end 132.135443 157.081808)
		(width 0.148)
		(layer "In6.Cu")
		(net 110)
	)
	(arc
		(start 131.42834 156.021151)
		(mid 131.355116 156.197927)
		(end 131.428339 156.374704)
		(width 0.148)
		(layer "In6.Cu")
		(net 110)
	)
	(arc
		(start 134.309014 158.090203)
		(mid 134.485792 158.016981)
		(end 134.662569 158.090204)
		(width 0.148)
		(layer "In6.Cu")
		(net 110)
	)
	(arc
		(start 133.549652 158.142463)
		(mid 133.476428 158.319239)
		(end 133.549651 158.496016)
		(width 0.148)
		(layer "In6.Cu")
		(net 110)
	)
	(arc
		(start 133.60191 157.383099)
		(mid 133.778688 157.309877)
		(end 133.955465 157.3831)
		(width 0.148)
		(layer "In6.Cu")
		(net 110)
	)
	(arc
		(start 130.721236 155.314047)
		(mid 130.648012 155.490823)
		(end 130.721235 155.6676)
		(width 0.148)
		(layer "In6.Cu")
		(net 110)
	)
	(arc
		(start 131.42834 156.374705)
		(mid 131.605117 156.447928)
		(end 131.781893 156.374704)
		(width 0.148)
		(layer "In6.Cu")
		(net 110)
	)
	(arc
		(start 129.359286 153.140475)
		(mid 129.536064 153.067253)
		(end 129.712841 153.140476)
		(width 0.148)
		(layer "In6.Cu")
		(net 110)
	)
	(arc
		(start 131.12705 154.554685)
		(mid 131.200273 154.731462)
		(end 131.127049 154.908238)
		(width 0.148)
		(layer "In6.Cu")
		(net 110)
	)
	(arc
		(start 129.307028 154.253393)
		(mid 129.483805 154.326616)
		(end 129.660581 154.253392)
		(width 0.148)
		(layer "In6.Cu")
		(net 110)
	)
	(arc
		(start 130.721236 155.667601)
		(mid 130.898013 155.740824)
		(end 131.074789 155.6676)
		(width 0.148)
		(layer "In6.Cu")
		(net 110)
	)
	(arc
		(start 134.636438 159.176991)
		(mid 134.813215 159.103768)
		(end 134.989991 159.176992)
		(width 0.148)
		(layer "In6.Cu")
		(net 110)
	)
	(arc
		(start 130.419946 153.847581)
		(mid 130.493169 154.024358)
		(end 130.419945 154.201134)
		(width 0.148)
		(layer "In6.Cu")
		(net 110)
	)
	(arc
		(start 128.652182 152.43337)
		(mid 128.828959 152.360147)
		(end 129.005735 152.433371)
		(width 0.148)
		(layer "In6.Cu")
		(net 110)
	)
	(arc
		(start 132.187702 155.968891)
		(mid 132.36448 155.895669)
		(end 132.541257 155.968892)
		(width 0.148)
		(layer "In6.Cu")
		(net 110)
	)
	(arc
		(start 133.955466 157.383101)
		(mid 134.028689 157.559878)
		(end 133.955465 157.736654)
		(width 0.148)
		(layer "In6.Cu")
		(net 110)
	)
	(arc
		(start 133.549652 158.496017)
		(mid 133.726429 158.56924)
		(end 133.903205 158.496016)
		(width 0.148)
		(layer "In6.Cu")
		(net 110)
	)
	(arc
		(start 133.248362 156.675997)
		(mid 133.321585 156.852774)
		(end 133.248361 157.02955)
		(width 0.148)
		(layer "In6.Cu")
		(net 110)
	)
	(arc
		(start 130.014132 154.960497)
		(mid 130.190909 155.03372)
		(end 130.367685 154.960496)
		(width 0.148)
		(layer "In6.Cu")
		(net 110)
	)
	(arc
		(start 132.135444 157.081809)
		(mid 132.312221 157.155032)
		(end 132.488997 157.081808)
		(width 0.148)
		(layer "In6.Cu")
		(net 110)
	)
	(arc
		(start 132.842548 157.788913)
		(mid 133.019325 157.862136)
		(end 133.196101 157.788912)
		(width 0.148)
		(layer "In6.Cu")
		(net 110)
	)
	(arc
		(start 134.256756 159.203121)
		(mid 134.433533 159.276344)
		(end 134.610309 159.20312)
		(width 0.148)
		(layer "In6.Cu")
		(net 110)
	)
	(arc
		(start 130.773494 154.554683)
		(mid 130.950272 154.481461)
		(end 131.127049 154.554684)
		(width 0.148)
		(layer "In6.Cu")
		(net 110)
	)
	(arc
		(start 132.842548 157.435359)
		(mid 132.769324 157.612135)
		(end 132.842547 157.788912)
		(width 0.148)
		(layer "In6.Cu")
		(net 110)
	)
	(arc
		(start 129.005736 152.433371)
		(mid 129.078959 152.610148)
		(end 129.005735 152.786924)
		(width 0.148)
		(layer "In6.Cu")
		(net 110)
	)
	(arc
		(start 131.480598 155.261787)
		(mid 131.657376 155.188565)
		(end 131.834153 155.261788)
		(width 0.148)
		(layer "In6.Cu")
		(net 110)
	)
	(arc
		(start 130.014132 154.606943)
		(mid 129.940908 154.783719)
		(end 130.014131 154.960496)
		(width 0.148)
		(layer "In6.Cu")
		(net 110)
	)
	(arc
		(start 134.256756 158.849567)
		(mid 134.183532 159.026343)
		(end 134.256755 159.20312)
		(width 0.148)
		(layer "In6.Cu")
		(net 110)
	)
	(arc
		(start 134.66257 158.090205)
		(mid 134.735793 158.266982)
		(end 134.662569 158.443758)
		(width 0.148)
		(layer "In6.Cu")
		(net 110)
	)
	(arc
		(start 132.894806 156.675995)
		(mid 133.071584 156.602773)
		(end 133.248361 156.675996)
		(width 0.148)
		(layer "In6.Cu")
		(net 110)
	)
	(arc
		(start 129.307028 153.899839)
		(mid 129.233804 154.076615)
		(end 129.307027 154.253392)
		(width 0.148)
		(layer "In6.Cu")
		(net 110)
	)
	(arc
		(start 131.834154 155.261789)
		(mid 131.907377 155.438566)
		(end 131.834153 155.615342)
		(width 0.148)
		(layer "In6.Cu")
		(net 110)
	)
	(segment
		(start 128.150001 138.8025)
		(end 128.150001 139.8775)
		(width 0.201)
		(layer "F.Cu")
		(net 111)
	)
	(segment
		(start 137.376501 163.302)
		(end 136.877001 162.8025)
		(width 0.256)
		(layer "F.Cu")
		(net 111)
	)
	(via
		(at 128.150001 139.8775)
		(size 0.45)
		(drill 0.1)
		(layers "F.Cu" "B.Cu")
		(net 111)
	)
	(via
		(at 136.877001 162.8025)
		(size 0.45)
		(drill 0.1)
		(layers "F.Cu" "B.Cu")
		(net 111)
	)
	(segment
		(start 128.400501 151.150501)
		(end 135.75 158.5)
		(width 0.148)
		(layer "In6.Cu")
		(net 111)
	)
	(segment
		(start 136.385501 161.461)
		(end 136.385501 162.311)
		(width 0.148)
		(layer "In6.Cu")
		(net 111)
	)
	(segment
		(start 128.150001 139.8775)
		(end 127.9 140.127501)
		(width 0.148)
		(layer "In6.Cu")
		(net 111)
	)
	(segment
		(start 127.44353 142.686)
		(end 128.35647 142.686)
		(width 0.148)
		(layer "In6.Cu")
		(net 111)
	)
	(segment
		(start 127.9 144.436)
		(end 127.9 146.005499)
		(width 0.148)
		(layer "In6.Cu")
		(net 111)
	)
	(segment
		(start 127.44353 144.186)
		(end 127.65 144.186)
		(width 0.148)
		(layer "In6.Cu")
		(net 111)
	)
	(segment
		(start 127.44353 141.186)
		(end 128.35647 141.186)
		(width 0.148)
		(layer "In6.Cu")
		(net 111)
	)
	(segment
		(start 127.44353 143.686)
		(end 128.35647 143.686)
		(width 0.148)
		(layer "In6.Cu")
		(net 111)
	)
	(segment
		(start 127.65 140.686)
		(end 127.44353 140.686)
		(width 0.148)
		(layer "In6.Cu")
		(net 111)
	)
	(segment
		(start 135.75 160.825499)
		(end 136.385501 161.461)
		(width 0.148)
		(layer "In6.Cu")
		(net 111)
	)
	(segment
		(start 127.44353 142.186)
		(end 128.35647 142.186)
		(width 0.148)
		(layer "In6.Cu")
		(net 111)
	)
	(segment
		(start 127.9 140.127501)
		(end 127.9 140.436)
		(width 0.148)
		(layer "In6.Cu")
		(net 111)
	)
	(segment
		(start 135.75 158.5)
		(end 135.75 160.825499)
		(width 0.148)
		(layer "In6.Cu")
		(net 111)
	)
	(segment
		(start 127.44353 143.186)
		(end 128.35647 143.186)
		(width 0.148)
		(layer "In6.Cu")
		(net 111)
	)
	(segment
		(start 136.385501 162.311)
		(end 136.877001 162.8025)
		(width 0.148)
		(layer "In6.Cu")
		(net 111)
	)
	(segment
		(start 128.400501 146.506)
		(end 128.400501 151.150501)
		(width 0.148)
		(layer "In6.Cu")
		(net 111)
	)
	(segment
		(start 127.44353 141.686)
		(end 128.35647 141.686)
		(width 0.148)
		(layer "In6.Cu")
		(net 111)
	)
	(segment
		(start 127.9 146.005499)
		(end 128.400501 146.506)
		(width 0.148)
		(layer "In6.Cu")
		(net 111)
	)
	(arc
		(start 127.9 140.436)
		(mid 127.826777 140.612777)
		(end 127.65 140.686)
		(width 0.148)
		(layer "In6.Cu")
		(net 111)
	)
	(arc
		(start 127.65 144.186)
		(mid 127.826777 144.259223)
		(end 127.9 144.436)
		(width 0.148)
		(layer "In6.Cu")
		(net 111)
	)
	(arc
		(start 127.19353 142.936)
		(mid 127.266753 143.112777)
		(end 127.44353 143.186)
		(width 0.148)
		(layer "In6.Cu")
		(net 111)
	)
	(arc
		(start 127.19353 143.936)
		(mid 127.266753 144.112777)
		(end 127.44353 144.186)
		(width 0.148)
		(layer "In6.Cu")
		(net 111)
	)
	(arc
		(start 128.60647 143.436)
		(mid 128.533247 143.612777)
		(end 128.35647 143.686)
		(width 0.148)
		(layer "In6.Cu")
		(net 111)
	)
	(arc
		(start 127.19353 140.936)
		(mid 127.266753 141.112777)
		(end 127.44353 141.186)
		(width 0.148)
		(layer "In6.Cu")
		(net 111)
	)
	(arc
		(start 127.19353 141.936)
		(mid 127.266753 142.112777)
		(end 127.44353 142.186)
		(width 0.148)
		(layer "In6.Cu")
		(net 111)
	)
	(arc
		(start 128.60647 141.436)
		(mid 128.533247 141.612777)
		(end 128.35647 141.686)
		(width 0.148)
		(layer "In6.Cu")
		(net 111)
	)
	(arc
		(start 128.60647 142.436)
		(mid 128.533247 142.612777)
		(end 128.35647 142.686)
		(width 0.148)
		(layer "In6.Cu")
		(net 111)
	)
	(arc
		(start 127.44353 140.686)
		(mid 127.266753 140.759223)
		(end 127.19353 140.936)
		(width 0.148)
		(layer "In6.Cu")
		(net 111)
	)
	(arc
		(start 127.44353 142.686)
		(mid 127.266753 142.759223)
		(end 127.19353 142.936)
		(width 0.148)
		(layer "In6.Cu")
		(net 111)
	)
	(arc
		(start 127.44353 141.686)
		(mid 127.266753 141.759223)
		(end 127.19353 141.936)
		(width 0.148)
		(layer "In6.Cu")
		(net 111)
	)
	(arc
		(start 127.44353 143.686)
		(mid 127.266753 143.759223)
		(end 127.19353 143.936)
		(width 0.148)
		(layer "In6.Cu")
		(net 111)
	)
	(arc
		(start 128.35647 143.186)
		(mid 128.533247 143.259223)
		(end 128.60647 143.436)
		(width 0.148)
		(layer "In6.Cu")
		(net 111)
	)
	(arc
		(start 128.35647 142.186)
		(mid 128.533247 142.259223)
		(end 128.60647 142.436)
		(width 0.148)
		(layer "In6.Cu")
		(net 111)
	)
	(arc
		(start 128.35647 141.186)
		(mid 128.533247 141.259223)
		(end 128.60647 141.436)
		(width 0.148)
		(layer "In6.Cu")
		(net 111)
	)
	(segment
		(start 128.900001 146.2025)
		(end 128.900001 147.2775)
		(width 0.201)
		(layer "F.Cu")
		(net 112)
	)
	(segment
		(start 137.376501 162.302)
		(end 136.877001 161.8025)
		(width 0.256)
		(layer "F.Cu")
		(net 112)
	)
	(via
		(at 136.877001 161.8025)
		(size 0.45)
		(drill 0.1)
		(layers "F.Cu" "B.Cu")
		(net 112)
	)
	(via
		(at 128.900001 147.2775)
		(size 0.45)
		(drill 0.1)
		(layers "F.Cu" "B.Cu")
		(net 112)
	)
	(segment
		(start 135.726904 156.712434)
		(end 135.301577 157.137757)
		(width 0.148)
		(layer "In6.Cu")
		(net 112)
	)
	(segment
		(start 135.019794 156.005322)
		(end 135.019793 156.005323)
		(width 0.148)
		(layer "In6.Cu")
		(net 112)
	)
	(segment
		(start 129.3447 150.720199)
		(end 128.900001 150.2755)
		(width 0.148)
		(layer "In6.Cu")
		(net 112)
	)
	(segment
		(start 130.070017 151.055545)
		(end 130.070016 151.055546)
		(width 0.148)
		(layer "In6.Cu")
		(net 112)
	)
	(segment
		(start 132.11958 154.309312)
		(end 132.119581 154.309314)
		(width 0.148)
		(layer "In6.Cu")
		(net 112)
	)
	(segment
		(start 131.484238 152.469768)
		(end 131.058911 152.895091)
		(width 0.148)
		(layer "In6.Cu")
		(net 112)
	)
	(segment
		(start 132.119581 153.95576)
		(end 132.544903 153.530433)
		(width 0.148)
		(layer "In6.Cu")
		(net 112)
	)
	(segment
		(start 128.900001 150.2755)
		(end 128.900001 147.2775)
		(width 0.148)
		(layer "In6.Cu")
		(net 112)
	)
	(segment
		(start 132.191349 153.176879)
		(end 131.766022 153.602202)
		(width 0.148)
		(layer "In6.Cu")
		(net 112)
	)
	(segment
		(start 136.080459 156.712435)
		(end 136.080458 156.712434)
		(width 0.148)
		(layer "In6.Cu")
		(net 112)
	)
	(segment
		(start 131.484239 152.469767)
		(end 131.484238 152.469768)
		(width 0.148)
		(layer "In6.Cu")
		(net 112)
	)
	(segment
		(start 129.291136 151.127317)
		(end 129.291137 151.127316)
		(width 0.148)
		(layer "In6.Cu")
		(net 112)
	)
	(segment
		(start 133.533802 155.723534)
		(end 133.533803 155.723536)
		(width 0.148)
		(layer "In6.Cu")
		(net 112)
	)
	(segment
		(start 136.261251 157.63675)
		(end 136.062251 157.43775)
		(width 0.148)
		(layer "In6.Cu")
		(net 112)
	)
	(segment
		(start 130.705358 152.541539)
		(end 130.705359 152.541538)
		(width 0.148)
		(layer "In6.Cu")
		(net 112)
	)
	(segment
		(start 129.291137 151.127316)
		(end 129.344699 151.073751)
		(width 0.148)
		(layer "In6.Cu")
		(net 112)
	)
	(segment
		(start 134.948024 156.784205)
		(end 134.948025 156.784204)
		(width 0.148)
		(layer "In6.Cu")
		(net 112)
	)
	(segment
		(start 130.777128 151.762656)
		(end 130.777127 151.762657)
		(width 0.148)
		(layer "In6.Cu")
		(net 112)
	)
	(segment
		(start 136.062251 157.084196)
		(end 136.080458 157.065988)
		(width 0.148)
		(layer "In6.Cu")
		(net 112)
	)
	(segment
		(start 134.312682 155.298212)
		(end 133.887355 155.723535)
		(width 0.148)
		(layer "In6.Cu")
		(net 112)
	)
	(segment
		(start 129.998247 151.834428)
		(end 129.998248 151.834427)
		(width 0.148)
		(layer "In6.Cu")
		(net 112)
	)
	(segment
		(start 133.605572 154.5911)
		(end 133.605571 154.591101)
		(width 0.148)
		(layer "In6.Cu")
		(net 112)
	)
	(segment
		(start 132.11958 153.955761)
		(end 132.119581 153.95576)
		(width 0.148)
		(layer "In6.Cu")
		(net 112)
	)
	(segment
		(start 134.240914 156.077093)
		(end 134.666236 155.651766)
		(width 0.148)
		(layer "In6.Cu")
		(net 112)
	)
	(segment
		(start 135.726905 156.712433)
		(end 135.726904 156.712434)
		(width 0.148)
		(layer "In6.Cu")
		(net 112)
	)
	(segment
		(start 132.826691 155.016423)
		(end 132.826692 155.016425)
		(width 0.148)
		(layer "In6.Cu")
		(net 112)
	)
	(segment
		(start 132.898461 153.883989)
		(end 132.89846 153.88399)
		(width 0.148)
		(layer "In6.Cu")
		(net 112)
	)
	(segment
		(start 130.070016 151.055546)
		(end 129.644689 151.480869)
		(width 0.148)
		(layer "In6.Cu")
		(net 112)
	)
	(segment
		(start 136.877001 161.2525)
		(end 136.261251 160.63675)
		(width 0.148)
		(layer "In6.Cu")
		(net 112)
	)
	(segment
		(start 134.948024 157.137756)
		(end 134.948025 157.137758)
		(width 0.148)
		(layer "In6.Cu")
		(net 112)
	)
	(segment
		(start 130.705358 152.89509)
		(end 130.705359 152.895092)
		(width 0.148)
		(layer "In6.Cu")
		(net 112)
	)
	(segment
		(start 136.06225 157.084197)
		(end 136.062251 157.084196)
		(width 0.148)
		(layer "In6.Cu")
		(net 112)
	)
	(segment
		(start 135.019793 156.005323)
		(end 134.594466 156.430646)
		(width 0.148)
		(layer "In6.Cu")
		(net 112)
	)
	(segment
		(start 130.777127 151.762657)
		(end 130.3518 152.18798)
		(width 0.148)
		(layer "In6.Cu")
		(net 112)
	)
	(segment
		(start 132.19135 153.176878)
		(end 132.191349 153.176879)
		(width 0.148)
		(layer "In6.Cu")
		(net 112)
	)
	(segment
		(start 130.705359 152.541538)
		(end 131.130681 152.116211)
		(width 0.148)
		(layer "In6.Cu")
		(net 112)
	)
	(segment
		(start 129.291136 151.480868)
		(end 129.291137 151.48087)
		(width 0.148)
		(layer "In6.Cu")
		(net 112)
	)
	(segment
		(start 133.533802 155.369983)
		(end 133.533803 155.369982)
		(width 0.148)
		(layer "In6.Cu")
		(net 112)
	)
	(segment
		(start 134.312683 155.298211)
		(end 134.312682 155.298212)
		(width 0.148)
		(layer "In6.Cu")
		(net 112)
	)
	(segment
		(start 131.41247 153.248649)
		(end 131.837792 152.823322)
		(width 0.148)
		(layer "In6.Cu")
		(net 112)
	)
	(segment
		(start 129.998247 152.187979)
		(end 129.998248 152.187981)
		(width 0.148)
		(layer "In6.Cu")
		(net 112)
	)
	(segment
		(start 132.89846 153.88399)
		(end 132.473133 154.309313)
		(width 0.148)
		(layer "In6.Cu")
		(net 112)
	)
	(segment
		(start 132.826692 154.662871)
		(end 133.252014 154.237544)
		(width 0.148)
		(layer "In6.Cu")
		(net 112)
	)
	(segment
		(start 134.240913 156.430645)
		(end 134.240914 156.430647)
		(width 0.148)
		(layer "In6.Cu")
		(net 112)
	)
	(segment
		(start 133.605571 154.591101)
		(end 133.180244 155.016424)
		(width 0.148)
		(layer "In6.Cu")
		(net 112)
	)
	(segment
		(start 136.877001 161.8025)
		(end 136.877001 161.2525)
		(width 0.148)
		(layer "In6.Cu")
		(net 112)
	)
	(segment
		(start 133.533803 155.369982)
		(end 133.959125 154.944655)
		(width 0.148)
		(layer "In6.Cu")
		(net 112)
	)
	(segment
		(start 132.826691 154.662872)
		(end 132.826692 154.662871)
		(width 0.148)
		(layer "In6.Cu")
		(net 112)
	)
	(segment
		(start 134.240913 156.077094)
		(end 134.240914 156.077093)
		(width 0.148)
		(layer "In6.Cu")
		(net 112)
	)
	(segment
		(start 136.261251 160.63675)
		(end 136.261251 157.63675)
		(width 0.148)
		(layer "In6.Cu")
		(net 112)
	)
	(segment
		(start 131.412469 153.602201)
		(end 131.41247 153.602203)
		(width 0.148)
		(layer "In6.Cu")
		(net 112)
	)
	(segment
		(start 129.998248 151.834427)
		(end 130.42357 151.4091)
		(width 0.148)
		(layer "In6.Cu")
		(net 112)
	)
	(segment
		(start 131.412469 153.24865)
		(end 131.41247 153.248649)
		(width 0.148)
		(layer "In6.Cu")
		(net 112)
	)
	(segment
		(start 134.948025 156.784204)
		(end 135.373347 156.358877)
		(width 0.148)
		(layer "In6.Cu")
		(net 112)
	)
	(segment
		(start 129.344699 150.720197)
		(end 129.3447 150.720199)
		(width 0.148)
		(layer "In6.Cu")
		(net 112)
	)
	(arc
		(start 130.42357 151.4091)
		(mid 130.496793 151.232323)
		(end 130.42357 151.055546)
		(width 0.148)
		(layer "In6.Cu")
		(net 112)
	)
	(arc
		(start 129.644689 151.480869)
		(mid 129.467912 151.554092)
		(end 129.291136 151.480868)
		(width 0.148)
		(layer "In6.Cu")
		(net 112)
	)
	(arc
		(start 129.344699 151.073751)
		(mid 129.417922 150.896974)
		(end 129.344699 150.720197)
		(width 0.148)
		(layer "In6.Cu")
		(net 112)
	)
	(arc
		(start 131.837792 152.469768)
		(mid 131.661016 152.396544)
		(end 131.484239 152.469767)
		(width 0.148)
		(layer "In6.Cu")
		(net 112)
	)
	(arc
		(start 136.080458 157.065988)
		(mid 136.153682 156.889212)
		(end 136.080459 156.712435)
		(width 0.148)
		(layer "In6.Cu")
		(net 112)
	)
	(arc
		(start 131.766022 153.602202)
		(mid 131.589245 153.675425)
		(end 131.412469 153.602201)
		(width 0.148)
		(layer "In6.Cu")
		(net 112)
	)
	(arc
		(start 129.998248 152.187981)
		(mid 129.925024 152.011205)
		(end 129.998247 151.834428)
		(width 0.148)
		(layer "In6.Cu")
		(net 112)
	)
	(arc
		(start 134.666236 155.298212)
		(mid 134.48946 155.224988)
		(end 134.312683 155.298211)
		(width 0.148)
		(layer "In6.Cu")
		(net 112)
	)
	(arc
		(start 133.533803 155.723536)
		(mid 133.460579 155.54676)
		(end 133.533802 155.369983)
		(width 0.148)
		(layer "In6.Cu")
		(net 112)
	)
	(arc
		(start 134.948025 157.137758)
		(mid 134.874801 156.960982)
		(end 134.948024 156.784205)
		(width 0.148)
		(layer "In6.Cu")
		(net 112)
	)
	(arc
		(start 133.959125 154.591101)
		(mid 133.782349 154.517877)
		(end 133.605572 154.5911)
		(width 0.148)
		(layer "In6.Cu")
		(net 112)
	)
	(arc
		(start 133.252014 154.237544)
		(mid 133.325237 154.060767)
		(end 133.252014 153.88399)
		(width 0.148)
		(layer "In6.Cu")
		(net 112)
	)
	(arc
		(start 135.373347 156.358877)
		(mid 135.44657 156.1821)
		(end 135.373347 156.005323)
		(width 0.148)
		(layer "In6.Cu")
		(net 112)
	)
	(arc
		(start 135.373347 156.005323)
		(mid 135.196571 155.932099)
		(end 135.019794 156.005322)
		(width 0.148)
		(layer "In6.Cu")
		(net 112)
	)
	(arc
		(start 135.301577 157.137757)
		(mid 135.1248 157.21098)
		(end 134.948024 157.137756)
		(width 0.148)
		(layer "In6.Cu")
		(net 112)
	)
	(arc
		(start 131.837792 152.823322)
		(mid 131.911015 152.646545)
		(end 131.837792 152.469768)
		(width 0.148)
		(layer "In6.Cu")
		(net 112)
	)
	(arc
		(start 134.240914 156.430647)
		(mid 134.16769 156.253871)
		(end 134.240913 156.077094)
		(width 0.148)
		(layer "In6.Cu")
		(net 112)
	)
	(arc
		(start 134.594466 156.430646)
		(mid 134.417689 156.503869)
		(end 134.240913 156.430645)
		(width 0.148)
		(layer "In6.Cu")
		(net 112)
	)
	(arc
		(start 131.130681 152.116211)
		(mid 131.203904 151.939434)
		(end 131.130681 151.762657)
		(width 0.148)
		(layer "In6.Cu")
		(net 112)
	)
	(arc
		(start 136.080458 156.712434)
		(mid 135.903682 156.63921)
		(end 135.726905 156.712433)
		(width 0.148)
		(layer "In6.Cu")
		(net 112)
	)
	(arc
		(start 131.058911 152.895091)
		(mid 130.882134 152.968314)
		(end 130.705358 152.89509)
		(width 0.148)
		(layer "In6.Cu")
		(net 112)
	)
	(arc
		(start 136.062251 157.43775)
		(mid 135.989027 157.260974)
		(end 136.06225 157.084197)
		(width 0.148)
		(layer "In6.Cu")
		(net 112)
	)
	(arc
		(start 132.544903 153.176879)
		(mid 132.368127 153.103655)
		(end 132.19135 153.176878)
		(width 0.148)
		(layer "In6.Cu")
		(net 112)
	)
	(arc
		(start 133.959125 154.944655)
		(mid 134.032348 154.767878)
		(end 133.959125 154.591101)
		(width 0.148)
		(layer "In6.Cu")
		(net 112)
	)
	(arc
		(start 133.887355 155.723535)
		(mid 133.710578 155.796758)
		(end 133.533802 155.723534)
		(width 0.148)
		(layer "In6.Cu")
		(net 112)
	)
	(arc
		(start 134.666236 155.651766)
		(mid 134.739459 155.474989)
		(end 134.666236 155.298212)
		(width 0.148)
		(layer "In6.Cu")
		(net 112)
	)
	(arc
		(start 132.826692 155.016425)
		(mid 132.753468 154.839649)
		(end 132.826691 154.662872)
		(width 0.148)
		(layer "In6.Cu")
		(net 112)
	)
	(arc
		(start 133.180244 155.016424)
		(mid 133.003467 155.089647)
		(end 132.826691 155.016423)
		(width 0.148)
		(layer "In6.Cu")
		(net 112)
	)
	(arc
		(start 131.41247 153.602203)
		(mid 131.339246 153.425427)
		(end 131.412469 153.24865)
		(width 0.148)
		(layer "In6.Cu")
		(net 112)
	)
	(arc
		(start 130.3518 152.18798)
		(mid 130.175023 152.261203)
		(end 129.998247 152.187979)
		(width 0.148)
		(layer "In6.Cu")
		(net 112)
	)
	(arc
		(start 132.544903 153.530433)
		(mid 132.618126 153.353656)
		(end 132.544903 153.176879)
		(width 0.148)
		(layer "In6.Cu")
		(net 112)
	)
	(arc
		(start 131.130681 151.762657)
		(mid 130.953905 151.689433)
		(end 130.777128 151.762656)
		(width 0.148)
		(layer "In6.Cu")
		(net 112)
	)
	(arc
		(start 132.473133 154.309313)
		(mid 132.296356 154.382536)
		(end 132.11958 154.309312)
		(width 0.148)
		(layer "In6.Cu")
		(net 112)
	)
	(arc
		(start 132.119581 154.309314)
		(mid 132.046357 154.132538)
		(end 132.11958 153.955761)
		(width 0.148)
		(layer "In6.Cu")
		(net 112)
	)
	(arc
		(start 133.252014 153.88399)
		(mid 133.075238 153.810766)
		(end 132.898461 153.883989)
		(width 0.148)
		(layer "In6.Cu")
		(net 112)
	)
	(arc
		(start 130.705359 152.895092)
		(mid 130.632135 152.718316)
		(end 130.705358 152.541539)
		(width 0.148)
		(layer "In6.Cu")
		(net 112)
	)
	(arc
		(start 130.42357 151.055546)
		(mid 130.246794 150.982322)
		(end 130.070017 151.055545)
		(width 0.148)
		(layer "In6.Cu")
		(net 112)
	)
	(arc
		(start 129.291137 151.48087)
		(mid 129.217913 151.304094)
		(end 129.291136 151.127317)
		(width 0.148)
		(layer "In6.Cu")
		(net 112)
	)
	(segment
		(start 138.376501 162.302)
		(end 137.877001 161.802499)
		(width 0.256)
		(layer "F.Cu")
		(net 113)
	)
	(segment
		(start 129.150001 138.8025)
		(end 129.150001 139.8775)
		(width 0.201)
		(layer "F.Cu")
		(net 113)
	)
	(via
		(at 137.877001 161.802499)
		(size 0.45)
		(drill 0.1)
		(layers "F.Cu" "B.Cu")
		(net 113)
	)
	(via
		(at 129.150001 139.8775)
		(size 0.45)
		(drill 0.1)
		(layers "F.Cu" "B.Cu")
		(net 113)
	)
	(segment
		(start 129.150001 139.8775)
		(end 129.150001 139.900001)
		(width 0.148)
		(layer "In6.Cu")
		(net 113)
	)
	(segment
		(start 129.150001 139.900001)
		(end 130 140.75)
		(width 0.148)
		(layer "In6.Cu")
		(net 113)
	)
	(segment
		(start 130 140.75)
		(end 130 141)
		(width 0.148)
		(layer "In6.Cu")
		(net 113)
	)
	(segment
		(start 130.837136 149.96)
		(end 130.75 149.96)
		(width 0.148)
		(layer "In6.Cu")
		(net 113)
	)
	(segment
		(start 130.35 142.25)
		(end 129.65 142.25)
		(width 0.148)
		(layer "In6.Cu")
		(net 113)
	)
	(segment
		(start 130.162864 148.96)
		(end 130.837136 148.96)
		(width 0.148)
		(layer "In6.Cu")
		(net 113)
	)
	(segment
		(start 130.25 147.96)
		(end 130.162864 147.96)
		(width 0.148)
		(layer "In6.Cu")
		(net 113)
	)
	(segment
		(start 130 145.520886)
		(end 130.5 146.020886)
		(width 0.148)
		(layer "In6.Cu")
		(net 113)
	)
	(segment
		(start 130.5 150.493874)
		(end 136.723001 156.716875)
		(width 0.148)
		(layer "In6.Cu")
		(net 113)
	)
	(segment
		(start 129.65 142.75)
		(end 130.35 142.75)
		(width 0.148)
		(layer "In6.Cu")
		(net 113)
	)
	(segment
		(start 130.5 146.020886)
		(end 130.5 147.71)
		(width 0.148)
		(layer "In6.Cu")
		(net 113)
	)
	(segment
		(start 130 144.5)
		(end 130 145.520886)
		(width 0.148)
		(layer "In6.Cu")
		(net 113)
	)
	(segment
		(start 136.723001 160.648499)
		(end 137.877001 161.802499)
		(width 0.148)
		(layer "In6.Cu")
		(net 113)
	)
	(segment
		(start 130.35 144.25)
		(end 130.25 144.25)
		(width 0.148)
		(layer "In6.Cu")
		(net 113)
	)
	(segment
		(start 130.162864 148.46)
		(end 130.25 148.46)
		(width 0.148)
		(layer "In6.Cu")
		(net 113)
	)
	(segment
		(start 136.723001 156.716875)
		(end 136.723001 160.648499)
		(width 0.148)
		(layer "In6.Cu")
		(net 113)
	)
	(segment
		(start 129.75 141.25)
		(end 129.65 141.25)
		(width 0.148)
		(layer "In6.Cu")
		(net 113)
	)
	(segment
		(start 129.65 143.75)
		(end 130.35 143.75)
		(width 0.148)
		(layer "In6.Cu")
		(net 113)
	)
	(segment
		(start 130.25 148.46)
		(end 130.837136 148.46)
		(width 0.148)
		(layer "In6.Cu")
		(net 113)
	)
	(segment
		(start 129.65 141.75)
		(end 130.35 141.75)
		(width 0.148)
		(layer "In6.Cu")
		(net 113)
	)
	(segment
		(start 130.35 143.25)
		(end 129.65 143.25)
		(width 0.148)
		(layer "In6.Cu")
		(net 113)
	)
	(segment
		(start 130.162864 149.46)
		(end 130.837136 149.46)
		(width 0.148)
		(layer "In6.Cu")
		(net 113)
	)
	(segment
		(start 130.5 150.21)
		(end 130.5 150.493874)
		(width 0.148)
		(layer "In6.Cu")
		(net 113)
	)
	(arc
		(start 130.25 144.25)
		(mid 130.073223 144.323223)
		(end 130 144.5)
		(width 0.148)
		(layer "In6.Cu")
		(net 113)
	)
	(arc
		(start 129.912864 149.21)
		(mid 129.986087 149.386777)
		(end 130.162864 149.46)
		(width 0.148)
		(layer "In6.Cu")
		(net 113)
	)
	(arc
		(start 129.912864 148.21)
		(mid 129.986087 148.386777)
		(end 130.162864 148.46)
		(width 0.148)
		(layer "In6.Cu")
		(net 113)
	)
	(arc
		(start 129.65 142.25)
		(mid 129.473223 142.323223)
		(end 129.4 142.5)
		(width 0.148)
		(layer "In6.Cu")
		(net 113)
	)
	(arc
		(start 131.087136 149.71)
		(mid 131.013913 149.886777)
		(end 130.837136 149.96)
		(width 0.148)
		(layer "In6.Cu")
		(net 113)
	)
	(arc
		(start 130.75 149.96)
		(mid 130.573223 150.033223)
		(end 130.5 150.21)
		(width 0.148)
		(layer "In6.Cu")
		(net 113)
	)
	(arc
		(start 129.65 143.25)
		(mid 129.473223 143.323223)
		(end 129.4 143.5)
		(width 0.148)
		(layer "In6.Cu")
		(net 113)
	)
	(arc
		(start 130.162864 147.96)
		(mid 129.986087 148.033223)
		(end 129.912864 148.21)
		(width 0.148)
		(layer "In6.Cu")
		(net 113)
	)
	(arc
		(start 129.4 142.5)
		(mid 129.473223 142.676777)
		(end 129.65 142.75)
		(width 0.148)
		(layer "In6.Cu")
		(net 113)
	)
	(arc
		(start 130.837136 148.46)
		(mid 131.013913 148.533223)
		(end 131.087136 148.71)
		(width 0.148)
		(layer "In6.Cu")
		(net 113)
	)
	(arc
		(start 130.6 144)
		(mid 130.526777 144.176777)
		(end 130.35 144.25)
		(width 0.148)
		(layer "In6.Cu")
		(net 113)
	)
	(arc
		(start 130.35 141.75)
		(mid 130.526777 141.823223)
		(end 130.6 142)
		(width 0.148)
		(layer "In6.Cu")
		(net 113)
	)
	(arc
		(start 130.6 142)
		(mid 130.526777 142.176777)
		(end 130.35 142.25)
		(width 0.148)
		(layer "In6.Cu")
		(net 113)
	)
	(arc
		(start 131.087136 148.71)
		(mid 131.013913 148.886777)
		(end 130.837136 148.96)
		(width 0.148)
		(layer "In6.Cu")
		(net 113)
	)
	(arc
		(start 129.4 143.5)
		(mid 129.473223 143.676777)
		(end 129.65 143.75)
		(width 0.148)
		(layer "In6.Cu")
		(net 113)
	)
	(arc
		(start 130.35 142.75)
		(mid 130.526777 142.823223)
		(end 130.6 143)
		(width 0.148)
		(layer "In6.Cu")
		(net 113)
	)
	(arc
		(start 130.35 143.75)
		(mid 130.526777 143.823223)
		(end 130.6 144)
		(width 0.148)
		(layer "In6.Cu")
		(net 113)
	)
	(arc
		(start 130 141)
		(mid 129.926777 141.176777)
		(end 129.75 141.25)
		(width 0.148)
		(layer "In6.Cu")
		(net 113)
	)
	(arc
		(start 130.6 143)
		(mid 130.526777 143.176777)
		(end 130.35 143.25)
		(width 0.148)
		(layer "In6.Cu")
		(net 113)
	)
	(arc
		(start 130.837136 149.46)
		(mid 131.013913 149.533223)
		(end 131.087136 149.71)
		(width 0.148)
		(layer "In6.Cu")
		(net 113)
	)
	(arc
		(start 129.65 141.25)
		(mid 129.473223 141.323223)
		(end 129.4 141.5)
		(width 0.148)
		(layer "In6.Cu")
		(net 113)
	)
	(arc
		(start 130.162864 148.96)
		(mid 129.986087 149.033223)
		(end 129.912864 149.21)
		(width 0.148)
		(layer "In6.Cu")
		(net 113)
	)
	(arc
		(start 129.4 141.5)
		(mid 129.473223 141.676777)
		(end 129.65 141.75)
		(width 0.148)
		(layer "In6.Cu")
		(net 113)
	)
	(arc
		(start 130.5 147.71)
		(mid 130.426777 147.886777)
		(end 130.25 147.96)
		(width 0.148)
		(layer "In6.Cu")
		(net 113)
	)
	(segment
		(start 138.376501 167.302)
		(end 138.876001 166.8025)
		(width 0.256)
		(layer "F.Cu")
		(net 114)
	)
	(segment
		(start 129.900001 146.2025)
		(end 129.900001 147.2775)
		(width 0.201)
		(layer "F.Cu")
		(net 114)
	)
	(via
		(at 138.876001 166.8025)
		(size 0.45)
		(drill 0.1)
		(layers "F.Cu" "B.Cu")
		(net 114)
	)
	(via
		(at 129.900001 147.2775)
		(size 0.45)
		(drill 0.1)
		(layers "F.Cu" "B.Cu")
		(net 114)
	)
	(segment
		(start 137.8755 158.448447)
		(end 137.875501 158.448446)
		(width 0.148)
		(layer "In9.Cu")
		(net 114)
	)
	(segment
		(start 134.636906 156.030154)
		(end 135.103654 155.563404)
		(width 0.148)
		(layer "In9.Cu")
		(net 114)
	)
	(segment
		(start 136.164322 156.624072)
		(end 135.697571 157.090819)
		(width 0.148)
		(layer "In9.Cu")
		(net 114)
	)
	(segment
		(start 134.750101 155.209849)
		(end 134.7501 155.20985)
		(width 0.148)
		(layer "In9.Cu")
		(net 114)
	)
	(segment
		(start 133.222683 154.615933)
		(end 133.222684 154.615932)
		(width 0.148)
		(layer "In9.Cu")
		(net 114)
	)
	(segment
		(start 136.758238 158.151488)
		(end 136.758239 158.151487)
		(width 0.148)
		(layer "In9.Cu")
		(net 114)
	)
	(segment
		(start 132.982322 153.088518)
		(end 132.982321 153.088517)
		(width 0.148)
		(layer "In9.Cu")
		(net 114)
	)
	(segment
		(start 134.636907 156.383709)
		(end 134.636906 156.383708)
		(width 0.148)
		(layer "In9.Cu")
		(net 114)
	)
	(segment
		(start 134.04299 154.502738)
		(end 134.042989 154.502739)
		(width 0.148)
		(layer "In9.Cu")
		(net 114)
	)
	(segment
		(start 132.628768 153.088516)
		(end 132.628767 153.088517)
		(width 0.148)
		(layer "In9.Cu")
		(net 114)
	)
	(segment
		(start 136.051127 157.444377)
		(end 136.051128 157.444376)
		(width 0.148)
		(layer "In9.Cu")
		(net 114)
	)
	(segment
		(start 138.876001 166.8025)
		(end 138.577001 166.5035)
		(width 0.148)
		(layer "In9.Cu")
		(net 114)
	)
	(segment
		(start 131.157949 152.084448)
		(end 131.157949 152.084447)
		(width 0.148)
		(layer "In9.Cu")
		(net 114)
	)
	(segment
		(start 136.871433 157.331183)
		(end 136.404682 157.79793)
		(width 0.148)
		(layer "In9.Cu")
		(net 114)
	)
	(segment
		(start 133.929795 155.323043)
		(end 134.396543 154.856293)
		(width 0.148)
		(layer "In9.Cu")
		(net 114)
	)
	(segment
		(start 135.457211 155.916961)
		(end 134.99046 156.383708)
		(width 0.148)
		(layer "In9.Cu")
		(net 114)
	)
	(segment
		(start 132.275211 152.381407)
		(end 132.27521 152.381406)
		(width 0.148)
		(layer "In9.Cu")
		(net 114)
	)
	(segment
		(start 137.875501 158.448446)
		(end 137.932099 158.391847)
		(width 0.148)
		(layer "In9.Cu")
		(net 114)
	)
	(segment
		(start 136.051129 157.797931)
		(end 136.051128 157.79793)
		(width 0.148)
		(layer "In9.Cu")
		(net 114)
	)
	(segment
		(start 135.344017 156.737265)
		(end 135.810765 156.270515)
		(width 0.148)
		(layer "In9.Cu")
		(net 114)
	)
	(segment
		(start 134.042989 154.502739)
		(end 133.576238 154.969486)
		(width 0.148)
		(layer "In9.Cu")
		(net 114)
	)
	(segment
		(start 137.932098 158.038294)
		(end 137.932099 158.038294)
		(width 0.148)
		(layer "In9.Cu")
		(net 114)
	)
	(segment
		(start 131.921657 152.381405)
		(end 131.921656 152.381406)
		(width 0.148)
		(layer "In9.Cu")
		(net 114)
	)
	(segment
		(start 137.224988 157.331184)
		(end 137.224987 157.331183)
		(width 0.148)
		(layer "In9.Cu")
		(net 114)
	)
	(segment
		(start 133.222685 154.969487)
		(end 133.222684 154.969486)
		(width 0.148)
		(layer "In9.Cu")
		(net 114)
	)
	(segment
		(start 134.396544 154.50274)
		(end 134.396543 154.502739)
		(width 0.148)
		(layer "In9.Cu")
		(net 114)
	)
	(segment
		(start 131.808462 153.20171)
		(end 132.27521 152.73496)
		(width 0.148)
		(layer "In9.Cu")
		(net 114)
	)
	(segment
		(start 131.808463 153.555265)
		(end 131.808462 153.555264)
		(width 0.148)
		(layer "In9.Cu")
		(net 114)
	)
	(segment
		(start 133.222684 154.615932)
		(end 133.689432 154.149182)
		(width 0.148)
		(layer "In9.Cu")
		(net 114)
	)
	(segment
		(start 133.689433 153.795629)
		(end 133.689432 153.795628)
		(width 0.148)
		(layer "In9.Cu")
		(net 114)
	)
	(segment
		(start 131.10135 152.4946)
		(end 131.101351 152.494599)
		(width 0.148)
		(layer "In9.Cu")
		(net 114)
	)
	(segment
		(start 136.051128 157.444376)
		(end 136.517876 156.977626)
		(width 0.148)
		(layer "In9.Cu")
		(net 114)
	)
	(segment
		(start 129.900001 150.8265)
		(end 129.900001 147.2775)
		(width 0.148)
		(layer "In9.Cu")
		(net 114)
	)
	(segment
		(start 135.344018 157.09082)
		(end 135.344017 157.090819)
		(width 0.148)
		(layer "In9.Cu")
		(net 114)
	)
	(segment
		(start 131.101352 152.848154)
		(end 131.101351 152.848153)
		(width 0.148)
		(layer "In9.Cu")
		(net 114)
	)
	(segment
		(start 131.157949 152.084447)
		(end 129.900001 150.8265)
		(width 0.148)
		(layer "In9.Cu")
		(net 114)
	)
	(segment
		(start 137.578546 158.038293)
		(end 137.578545 158.038294)
		(width 0.148)
		(layer "In9.Cu")
		(net 114)
	)
	(segment
		(start 136.517877 156.624073)
		(end 136.517876 156.624072)
		(width 0.148)
		(layer "In9.Cu")
		(net 114)
	)
	(segment
		(start 133.335879 153.795627)
		(end 133.335878 153.795628)
		(width 0.148)
		(layer "In9.Cu")
		(net 114)
	)
	(segment
		(start 132.515573 153.908821)
		(end 132.982321 153.442071)
		(width 0.148)
		(layer "In9.Cu")
		(net 114)
	)
	(segment
		(start 135.457212 155.91696)
		(end 135.457211 155.916961)
		(width 0.148)
		(layer "In9.Cu")
		(net 114)
	)
	(segment
		(start 136.75824 158.505042)
		(end 136.758239 158.505041)
		(width 0.148)
		(layer "In9.Cu")
		(net 114)
	)
	(segment
		(start 135.344016 156.737266)
		(end 135.344017 156.737265)
		(width 0.148)
		(layer "In9.Cu")
		(net 114)
	)
	(segment
		(start 131.808461 153.201711)
		(end 131.808462 153.20171)
		(width 0.148)
		(layer "In9.Cu")
		(net 114)
	)
	(segment
		(start 134.636905 156.030155)
		(end 134.636906 156.030154)
		(width 0.148)
		(layer "In9.Cu")
		(net 114)
	)
	(segment
		(start 136.164323 156.624071)
		(end 136.164322 156.624072)
		(width 0.148)
		(layer "In9.Cu")
		(net 114)
	)
	(segment
		(start 136.871434 157.331182)
		(end 136.871433 157.331183)
		(width 0.148)
		(layer "In9.Cu")
		(net 114)
	)
	(segment
		(start 136.758239 158.151487)
		(end 137.224987 157.684737)
		(width 0.148)
		(layer "In9.Cu")
		(net 114)
	)
	(segment
		(start 135.103655 155.209851)
		(end 135.103654 155.20985)
		(width 0.148)
		(layer "In9.Cu")
		(net 114)
	)
	(segment
		(start 135.810766 155.916962)
		(end 135.810765 155.916961)
		(width 0.148)
		(layer "In9.Cu")
		(net 114)
	)
	(segment
		(start 132.515574 154.262376)
		(end 132.515573 154.262375)
		(width 0.148)
		(layer "In9.Cu")
		(net 114)
	)
	(segment
		(start 134.7501 155.20985)
		(end 134.283349 155.676597)
		(width 0.148)
		(layer "In9.Cu")
		(net 114)
	)
	(segment
		(start 131.101351 152.494599)
		(end 131.15795 152.438001)
		(width 0.148)
		(layer "In9.Cu")
		(net 114)
	)
	(segment
		(start 133.929794 155.323044)
		(end 133.929795 155.323043)
		(width 0.148)
		(layer "In9.Cu")
		(net 114)
	)
	(segment
		(start 138.577001 166.5035)
		(end 138.577001 159.5035)
		(width 0.148)
		(layer "In9.Cu")
		(net 114)
	)
	(segment
		(start 132.515572 153.908822)
		(end 132.515573 153.908821)
		(width 0.148)
		(layer "In9.Cu")
		(net 114)
	)
	(segment
		(start 131.921656 152.381406)
		(end 131.454905 152.848153)
		(width 0.148)
		(layer "In9.Cu")
		(net 114)
	)
	(segment
		(start 137.578545 158.038294)
		(end 137.111793 158.505041)
		(width 0.148)
		(layer "In9.Cu")
		(net 114)
	)
	(segment
		(start 132.628767 153.088517)
		(end 132.162016 153.555264)
		(width 0.148)
		(layer "In9.Cu")
		(net 114)
	)
	(segment
		(start 133.929796 155.676598)
		(end 133.929795 155.676597)
		(width 0.148)
		(layer "In9.Cu")
		(net 114)
	)
	(segment
		(start 138.577001 159.5035)
		(end 137.875501 158.802)
		(width 0.148)
		(layer "In9.Cu")
		(net 114)
	)
	(segment
		(start 133.335878 153.795628)
		(end 132.869127 154.262375)
		(width 0.148)
		(layer "In9.Cu")
		(net 114)
	)
	(arc
		(start 133.576238 154.969486)
		(mid 133.399462 155.04271)
		(end 133.222685 154.969487)
		(width 0.148)
		(layer "In9.Cu")
		(net 114)
	)
	(arc
		(start 135.103654 155.563404)
		(mid 135.176878 155.386628)
		(end 135.103655 155.209851)
		(width 0.148)
		(layer "In9.Cu")
		(net 114)
	)
	(arc
		(start 132.27521 152.73496)
		(mid 132.348434 152.558184)
		(end 132.275211 152.381407)
		(width 0.148)
		(layer "In9.Cu")
		(net 114)
	)
	(arc
		(start 134.99046 156.383708)
		(mid 134.813684 156.456932)
		(end 134.636907 156.383709)
		(width 0.148)
		(layer "In9.Cu")
		(net 114)
	)
	(arc
		(start 132.982321 153.442071)
		(mid 133.055545 153.265295)
		(end 132.982322 153.088518)
		(width 0.148)
		(layer "In9.Cu")
		(net 114)
	)
	(arc
		(start 137.932099 158.391847)
		(mid 138.005322 158.21507)
		(end 137.932098 158.038294)
		(width 0.148)
		(layer "In9.Cu")
		(net 114)
	)
	(arc
		(start 132.982321 153.088517)
		(mid 132.805545 153.015293)
		(end 132.628768 153.088516)
		(width 0.148)
		(layer "In9.Cu")
		(net 114)
	)
	(arc
		(start 137.224987 157.684737)
		(mid 137.298211 157.507961)
		(end 137.224988 157.331184)
		(width 0.148)
		(layer "In9.Cu")
		(net 114)
	)
	(arc
		(start 131.101351 152.848153)
		(mid 131.028127 152.671377)
		(end 131.10135 152.4946)
		(width 0.148)
		(layer "In9.Cu")
		(net 114)
	)
	(arc
		(start 137.224987 157.331183)
		(mid 137.048211 157.257959)
		(end 136.871434 157.331182)
		(width 0.148)
		(layer "In9.Cu")
		(net 114)
	)
	(arc
		(start 133.929795 155.676597)
		(mid 133.856571 155.499821)
		(end 133.929794 155.323044)
		(width 0.148)
		(layer "In9.Cu")
		(net 114)
	)
	(arc
		(start 132.27521 152.381406)
		(mid 132.098434 152.308182)
		(end 131.921657 152.381405)
		(width 0.148)
		(layer "In9.Cu")
		(net 114)
	)
	(arc
		(start 137.932099 158.038294)
		(mid 137.755323 157.96507)
		(end 137.578546 158.038293)
		(width 0.148)
		(layer "In9.Cu")
		(net 114)
	)
	(arc
		(start 131.454905 152.848153)
		(mid 131.278129 152.921377)
		(end 131.101352 152.848154)
		(width 0.148)
		(layer "In9.Cu")
		(net 114)
	)
	(arc
		(start 136.758239 158.505041)
		(mid 136.685015 158.328265)
		(end 136.758238 158.151488)
		(width 0.148)
		(layer "In9.Cu")
		(net 114)
	)
	(arc
		(start 132.515573 154.262375)
		(mid 132.442349 154.085599)
		(end 132.515572 153.908822)
		(width 0.148)
		(layer "In9.Cu")
		(net 114)
	)
	(arc
		(start 133.689432 154.149182)
		(mid 133.762656 153.972406)
		(end 133.689433 153.795629)
		(width 0.148)
		(layer "In9.Cu")
		(net 114)
	)
	(arc
		(start 132.162016 153.555264)
		(mid 131.98524 153.628488)
		(end 131.808463 153.555265)
		(width 0.148)
		(layer "In9.Cu")
		(net 114)
	)
	(arc
		(start 134.283349 155.676597)
		(mid 134.106573 155.749821)
		(end 133.929796 155.676598)
		(width 0.148)
		(layer "In9.Cu")
		(net 114)
	)
	(arc
		(start 136.517876 156.977626)
		(mid 136.5911 156.80085)
		(end 136.517877 156.624073)
		(width 0.148)
		(layer "In9.Cu")
		(net 114)
	)
	(arc
		(start 136.051128 157.79793)
		(mid 135.977904 157.621154)
		(end 136.051127 157.444377)
		(width 0.148)
		(layer "In9.Cu")
		(net 114)
	)
	(arc
		(start 132.869127 154.262375)
		(mid 132.692351 154.335599)
		(end 132.515574 154.262376)
		(width 0.148)
		(layer "In9.Cu")
		(net 114)
	)
	(arc
		(start 133.222684 154.969486)
		(mid 133.14946 154.79271)
		(end 133.222683 154.615933)
		(width 0.148)
		(layer "In9.Cu")
		(net 114)
	)
	(arc
		(start 137.875501 158.802)
		(mid 137.802277 158.625224)
		(end 137.8755 158.448447)
		(width 0.148)
		(layer "In9.Cu")
		(net 114)
	)
	(arc
		(start 135.697571 157.090819)
		(mid 135.520795 157.164043)
		(end 135.344018 157.09082)
		(width 0.148)
		(layer "In9.Cu")
		(net 114)
	)
	(arc
		(start 131.808462 153.555264)
		(mid 131.735238 153.378488)
		(end 131.808461 153.201711)
		(width 0.148)
		(layer "In9.Cu")
		(net 114)
	)
	(arc
		(start 134.396543 154.856293)
		(mid 134.469767 154.679517)
		(end 134.396544 154.50274)
		(width 0.148)
		(layer "In9.Cu")
		(net 114)
	)
	(arc
		(start 136.404682 157.79793)
		(mid 136.227906 157.871154)
		(end 136.051129 157.797931)
		(width 0.148)
		(layer "In9.Cu")
		(net 114)
	)
	(arc
		(start 135.810765 156.270515)
		(mid 135.883989 156.093739)
		(end 135.810766 155.916962)
		(width 0.148)
		(layer "In9.Cu")
		(net 114)
	)
	(arc
		(start 134.396543 154.502739)
		(mid 134.219767 154.429515)
		(end 134.04299 154.502738)
		(width 0.148)
		(layer "In9.Cu")
		(net 114)
	)
	(arc
		(start 135.344017 157.090819)
		(mid 135.270793 156.914043)
		(end 135.344016 156.737266)
		(width 0.148)
		(layer "In9.Cu")
		(net 114)
	)
	(arc
		(start 131.15795 152.438001)
		(mid 131.231173 152.261224)
		(end 131.157949 152.084448)
		(width 0.148)
		(layer "In9.Cu")
		(net 114)
	)
	(arc
		(start 136.517876 156.624072)
		(mid 136.3411 156.550848)
		(end 136.164323 156.624071)
		(width 0.148)
		(layer "In9.Cu")
		(net 114)
	)
	(arc
		(start 133.689432 153.795628)
		(mid 133.512656 153.722404)
		(end 133.335879 153.795627)
		(width 0.148)
		(layer "In9.Cu")
		(net 114)
	)
	(arc
		(start 135.810765 155.916961)
		(mid 135.633989 155.843737)
		(end 135.457212 155.91696)
		(width 0.148)
		(layer "In9.Cu")
		(net 114)
	)
	(arc
		(start 134.636906 156.383708)
		(mid 134.563682 156.206932)
		(end 134.636905 156.030155)
		(width 0.148)
		(layer "In9.Cu")
		(net 114)
	)
	(arc
		(start 137.111793 158.505041)
		(mid 136.935017 158.578265)
		(end 136.75824 158.505042)
		(width 0.148)
		(layer "In9.Cu")
		(net 114)
	)
	(arc
		(start 135.103654 155.20985)
		(mid 134.926878 155.136626)
		(end 134.750101 155.209849)
		(width 0.148)
		(layer "In9.Cu")
		(net 114)
	)
	(segment
		(start 132.376501 166.302)
		(end 131.877001 165.8025)
		(width 0.256)
		(layer "F.Cu")
		(net 115)
	)
	(segment
		(start 130.150001 138.8025)
		(end 130.150001 139.8775)
		(width 0.201)
		(layer "F.Cu")
		(net 115)
	)
	(via
		(at 131.877001 165.8025)
		(size 0.45)
		(drill 0.1)
		(layers "F.Cu" "B.Cu")
		(net 115)
	)
	(via
		(at 130.150001 139.8775)
		(size 0.45)
		(drill 0.1)
		(layers "F.Cu" "B.Cu")
		(net 115)
	)
	(segment
		(start 130.205277 153.739989)
		(end 129.813488 154.131774)
		(width 0.148)
		(layer "In9.Cu")
		(net 115)
	)
	(segment
		(start 128.4 152.326499)
		(end 129.125501 153.052)
		(width 0.148)
		(layer "In9.Cu")
		(net 115)
	)
	(segment
		(start 129.813488 154.485328)
		(end 129.813488 154.485327)
		(width 0.148)
		(layer "In9.Cu")
		(net 115)
	)
	(segment
		(start 129.459937 153.778222)
		(end 129.459937 153.778223)
		(width 0.148)
		(layer "In9.Cu")
		(net 115)
	)
	(segment
		(start 128.877001 143.2985)
		(end 128.877001 145.9905)
		(width 0.148)
		(layer "In9.Cu")
		(net 115)
	)
	(segment
		(start 129.125501 153.405553)
		(end 129.106384 153.424669)
		(width 0.148)
		(layer "In9.Cu")
		(net 115)
	)
	(segment
		(start 129.1255 153.405553)
		(end 129.125501 153.405553)
		(width 0.148)
		(layer "In9.Cu")
		(net 115)
	)
	(segment
		(start 128.4 146.467501)
		(end 128.4 152.326499)
		(width 0.148)
		(layer "In9.Cu")
		(net 115)
	)
	(segment
		(start 130.150001 139.8775)
		(end 130.150001 142.0255)
		(width 0.148)
		(layer "In9.Cu")
		(net 115)
	)
	(segment
		(start 131.186616 155.113115)
		(end 132.377001 156.3035)
		(width 0.148)
		(layer "In9.Cu")
		(net 115)
	)
	(segment
		(start 128.877001 145.9905)
		(end 128.4 146.467501)
		(width 0.148)
		(layer "In9.Cu")
		(net 115)
	)
	(segment
		(start 130.539711 154.46621)
		(end 131.186616 155.113115)
		(width 0.148)
		(layer "In9.Cu")
		(net 115)
	)
	(segment
		(start 130.205278 153.386436)
		(end 130.205276 153.386435)
		(width 0.148)
		(layer "In9.Cu")
		(net 115)
	)
	(segment
		(start 132.377001 156.3035)
		(end 132.377001 165.3025)
		(width 0.148)
		(layer "In9.Cu")
		(net 115)
	)
	(segment
		(start 130.167041 154.485327)
		(end 130.186157 154.46621)
		(width 0.148)
		(layer "In9.Cu")
		(net 115)
	)
	(segment
		(start 130.205275 153.739988)
		(end 130.205277 153.739989)
		(width 0.148)
		(layer "In9.Cu")
		(net 115)
	)
	(segment
		(start 129.459937 153.778223)
		(end 129.851722 153.386434)
		(width 0.148)
		(layer "In9.Cu")
		(net 115)
	)
	(segment
		(start 132.377001 165.3025)
		(end 131.877001 165.8025)
		(width 0.148)
		(layer "In9.Cu")
		(net 115)
	)
	(segment
		(start 130.167041 154.485326)
		(end 130.167041 154.485327)
		(width 0.148)
		(layer "In9.Cu")
		(net 115)
	)
	(segment
		(start 130.150001 142.0255)
		(end 128.877001 143.2985)
		(width 0.148)
		(layer "In9.Cu")
		(net 115)
	)
	(arc
		(start 129.106384 153.778223)
		(mid 129.283161 153.851446)
		(end 129.459937 153.778222)
		(width 0.148)
		(layer "In9.Cu")
		(net 115)
	)
	(arc
		(start 129.106384 153.424669)
		(mid 129.033161 153.601446)
		(end 129.106384 153.778223)
		(width 0.148)
		(layer "In9.Cu")
		(net 115)
	)
	(arc
		(start 130.186157 154.46621)
		(mid 130.362934 154.392987)
		(end 130.539711 154.46621)
		(width 0.148)
		(layer "In9.Cu")
		(net 115)
	)
	(arc
		(start 129.813488 154.131774)
		(mid 129.740265 154.308551)
		(end 129.813488 154.485328)
		(width 0.148)
		(layer "In9.Cu")
		(net 115)
	)
	(arc
		(start 130.205276 153.386435)
		(mid 130.278499 153.563212)
		(end 130.205275 153.739988)
		(width 0.148)
		(layer "In9.Cu")
		(net 115)
	)
	(arc
		(start 129.851722 153.386434)
		(mid 130.028501 153.313213)
		(end 130.205278 153.386436)
		(width 0.148)
		(layer "In9.Cu")
		(net 115)
	)
	(arc
		(start 129.125501 153.052)
		(mid 129.198724 153.228777)
		(end 129.1255 153.405553)
		(width 0.148)
		(layer "In9.Cu")
		(net 115)
	)
	(arc
		(start 129.813488 154.485327)
		(mid 129.990265 154.55855)
		(end 130.167041 154.485326)
		(width 0.148)
		(layer "In9.Cu")
		(net 115)
	)
	(segment
		(start 139.375502 169.302)
		(end 139.875001 168.8025)
		(width 0.256)
		(layer "F.Cu")
		(net 116)
	)
	(segment
		(start 130.900001 146.2025)
		(end 130.900001 147.2775)
		(width 0.201)
		(layer "F.Cu")
		(net 116)
	)
	(via
		(at 130.900001 147.2775)
		(size 0.45)
		(drill 0.1)
		(layers "F.Cu" "B.Cu")
		(net 116)
	)
	(via
		(at 139.875001 168.8025)
		(size 0.45)
		(drill 0.1)
		(layers "F.Cu" "B.Cu")
		(net 116)
	)
	(segment
		(start 132.261511 150.43801)
		(end 132.261511 150.438009)
		(width 0.148)
		(layer "In9.Cu")
		(net 116)
	)
	(segment
		(start 137.823715 156.543124)
		(end 138.366622 156.000212)
		(width 0.148)
		(layer "In9.Cu")
		(net 116)
	)
	(segment
		(start 136.409494 155.482456)
		(end 136.409493 155.482455)
		(width 0.148)
		(layer "In9.Cu")
		(net 116)
	)
	(segment
		(start 135.184629 152.818217)
		(end 135.184628 152.818218)
		(width 0.148)
		(layer "In9.Cu")
		(net 116)
	)
	(segment
		(start 133.581054 152.654016)
		(end 133.581053 152.654015)
		(width 0.148)
		(layer "In9.Cu")
		(net 116)
	)
	(segment
		(start 133.581053 152.300461)
		(end 134.123962 151.757552)
		(width 0.148)
		(layer "In9.Cu")
		(net 116)
	)
	(segment
		(start 134.288162 153.007572)
		(end 134.288163 153.007571)
		(width 0.148)
		(layer "In9.Cu")
		(net 116)
	)
	(segment
		(start 132.166834 151.239796)
		(end 132.166833 151.239795)
		(width 0.148)
		(layer "In9.Cu")
		(net 116)
	)
	(segment
		(start 132.873942 151.593352)
		(end 132.873943 151.593351)
		(width 0.148)
		(layer "In9.Cu")
		(net 116)
	)
	(segment
		(start 138.013069 155.646657)
		(end 138.013068 155.646658)
		(width 0.148)
		(layer "In9.Cu")
		(net 116)
	)
	(segment
		(start 134.477519 152.111107)
		(end 134.477518 152.111108)
		(width 0.148)
		(layer "In9.Cu")
		(net 116)
	)
	(segment
		(start 134.288164 153.361126)
		(end 134.288163 153.361125)
		(width 0.148)
		(layer "In9.Cu")
		(net 116)
	)
	(segment
		(start 132.873943 151.593351)
		(end 133.416852 151.050442)
		(width 0.148)
		(layer "In9.Cu")
		(net 116)
	)
	(segment
		(start 137.823714 156.543125)
		(end 137.823715 156.543124)
		(width 0.148)
		(layer "In9.Cu")
		(net 116)
	)
	(segment
		(start 135.891739 153.525327)
		(end 135.891738 153.525328)
		(width 0.148)
		(layer "In9.Cu")
		(net 116)
	)
	(segment
		(start 136.245293 153.525329)
		(end 136.245292 153.525328)
		(width 0.148)
		(layer "In9.Cu")
		(net 116)
	)
	(segment
		(start 135.184628 152.818218)
		(end 134.641717 153.361125)
		(width 0.148)
		(layer "In9.Cu")
		(net 116)
	)
	(segment
		(start 130.900001 149.0765)
		(end 130.900001 147.2775)
		(width 0.148)
		(layer "In9.Cu")
		(net 116)
	)
	(segment
		(start 137.116603 155.836011)
		(end 137.659512 155.293102)
		(width 0.148)
		(layer "In9.Cu")
		(net 116)
	)
	(segment
		(start 134.123963 151.403999)
		(end 134.123962 151.403998)
		(width 0.148)
		(layer "In9.Cu")
		(net 116)
	)
	(segment
		(start 136.952403 154.232439)
		(end 136.952402 154.232438)
		(width 0.148)
		(layer "In9.Cu")
		(net 116)
	)
	(segment
		(start 138.271948 156.801999)
		(end 138.271947 156.802)
		(width 0.148)
		(layer "In9.Cu")
		(net 116)
	)
	(segment
		(start 139.875001 168.8025)
		(end 139.377001 168.3045)
		(width 0.148)
		(layer "In9.Cu")
		(net 116)
	)
	(segment
		(start 137.116604 156.189566)
		(end 137.116603 156.189565)
		(width 0.148)
		(layer "In9.Cu")
		(net 116)
	)
	(segment
		(start 134.995274 154.068236)
		(end 134.995273 154.068235)
		(width 0.148)
		(layer "In9.Cu")
		(net 116)
	)
	(segment
		(start 136.598848 154.232438)
		(end 136.055937 154.775345)
		(width 0.148)
		(layer "In9.Cu")
		(net 116)
	)
	(segment
		(start 138.366623 155.646659)
		(end 138.366622 155.646658)
		(width 0.148)
		(layer "In9.Cu")
		(net 116)
	)
	(segment
		(start 135.891738 153.525328)
		(end 135.348827 154.068235)
		(width 0.148)
		(layer "In9.Cu")
		(net 116)
	)
	(segment
		(start 133.063298 150.696888)
		(end 132.520387 151.239795)
		(width 0.148)
		(layer "In9.Cu")
		(net 116)
	)
	(segment
		(start 132.873944 151.946906)
		(end 132.873943 151.946905)
		(width 0.148)
		(layer "In9.Cu")
		(net 116)
	)
	(segment
		(start 134.288163 153.007571)
		(end 134.831072 152.464662)
		(width 0.148)
		(layer "In9.Cu")
		(net 116)
	)
	(segment
		(start 132.261511 150.438009)
		(end 130.900001 149.0765)
		(width 0.148)
		(layer "In9.Cu")
		(net 116)
	)
	(segment
		(start 134.995273 153.714681)
		(end 135.538182 153.171772)
		(width 0.148)
		(layer "In9.Cu")
		(net 116)
	)
	(segment
		(start 135.702382 154.421792)
		(end 135.702383 154.421791)
		(width 0.148)
		(layer "In9.Cu")
		(net 116)
	)
	(segment
		(start 133.581052 152.300462)
		(end 133.581053 152.300461)
		(width 0.148)
		(layer "In9.Cu")
		(net 116)
	)
	(segment
		(start 137.823714 156.896676)
		(end 137.823715 156.896678)
		(width 0.148)
		(layer "In9.Cu")
		(net 116)
	)
	(segment
		(start 139.377001 157.5535)
		(end 138.625501 156.802)
		(width 0.148)
		(layer "In9.Cu")
		(net 116)
	)
	(segment
		(start 136.598849 154.232437)
		(end 136.598848 154.232438)
		(width 0.148)
		(layer "In9.Cu")
		(net 116)
	)
	(segment
		(start 134.831073 152.111109)
		(end 134.831072 152.111108)
		(width 0.148)
		(layer "In9.Cu")
		(net 116)
	)
	(segment
		(start 137.659513 154.939549)
		(end 137.659512 154.939548)
		(width 0.148)
		(layer "In9.Cu")
		(net 116)
	)
	(segment
		(start 134.477518 152.111108)
		(end 133.934607 152.654015)
		(width 0.148)
		(layer "In9.Cu")
		(net 116)
	)
	(segment
		(start 133.770408 151.403998)
		(end 133.227497 151.946905)
		(width 0.148)
		(layer "In9.Cu")
		(net 116)
	)
	(segment
		(start 135.702384 154.775346)
		(end 135.702383 154.775345)
		(width 0.148)
		(layer "In9.Cu")
		(net 116)
	)
	(segment
		(start 133.416853 150.696889)
		(end 133.416852 150.696888)
		(width 0.148)
		(layer "In9.Cu")
		(net 116)
	)
	(segment
		(start 134.995272 153.714682)
		(end 134.995273 153.714681)
		(width 0.148)
		(layer "In9.Cu")
		(net 116)
	)
	(segment
		(start 133.770409 151.403997)
		(end 133.770408 151.403998)
		(width 0.148)
		(layer "In9.Cu")
		(net 116)
	)
	(segment
		(start 132.166832 150.886242)
		(end 132.166833 150.886241)
		(width 0.148)
		(layer "In9.Cu")
		(net 116)
	)
	(segment
		(start 135.538183 152.818219)
		(end 135.538182 152.818218)
		(width 0.148)
		(layer "In9.Cu")
		(net 116)
	)
	(segment
		(start 137.305959 154.939547)
		(end 137.305958 154.939548)
		(width 0.148)
		(layer "In9.Cu")
		(net 116)
	)
	(segment
		(start 135.702383 154.421791)
		(end 136.245292 153.878882)
		(width 0.148)
		(layer "In9.Cu")
		(net 116)
	)
	(segment
		(start 136.409492 155.128902)
		(end 136.409493 155.128901)
		(width 0.148)
		(layer "In9.Cu")
		(net 116)
	)
	(segment
		(start 138.271947 156.802)
		(end 138.177267 156.896677)
		(width 0.148)
		(layer "In9.Cu")
		(net 116)
	)
	(segment
		(start 138.013068 155.646658)
		(end 137.470157 156.189565)
		(width 0.148)
		(layer "In9.Cu")
		(net 116)
	)
	(segment
		(start 132.166833 150.886241)
		(end 132.261512 150.791563)
		(width 0.148)
		(layer "In9.Cu")
		(net 116)
	)
	(segment
		(start 139.377001 168.3045)
		(end 139.377001 157.5535)
		(width 0.148)
		(layer "In9.Cu")
		(net 116)
	)
	(segment
		(start 133.063299 150.696887)
		(end 133.063298 150.696888)
		(width 0.148)
		(layer "In9.Cu")
		(net 116)
	)
	(segment
		(start 137.305958 154.939548)
		(end 136.763047 155.482455)
		(width 0.148)
		(layer "In9.Cu")
		(net 116)
	)
	(segment
		(start 137.116602 155.836012)
		(end 137.116603 155.836011)
		(width 0.148)
		(layer "In9.Cu")
		(net 116)
	)
	(segment
		(start 136.409493 155.128901)
		(end 136.952402 154.585992)
		(width 0.148)
		(layer "In9.Cu")
		(net 116)
	)
	(arc
		(start 136.763047 155.482455)
		(mid 136.586271 155.555679)
		(end 136.409494 155.482456)
		(width 0.148)
		(layer "In9.Cu")
		(net 116)
	)
	(arc
		(start 132.166833 151.239795)
		(mid 132.093609 151.063019)
		(end 132.166832 150.886242)
		(width 0.148)
		(layer "In9.Cu")
		(net 116)
	)
	(arc
		(start 138.177267 156.896677)
		(mid 138.00049 156.9699)
		(end 137.823714 156.896676)
		(width 0.148)
		(layer "In9.Cu")
		(net 116)
	)
	(arc
		(start 138.625501 156.802)
		(mid 138.448725 156.728776)
		(end 138.271948 156.801999)
		(width 0.148)
		(layer "In9.Cu")
		(net 116)
	)
	(arc
		(start 133.416852 151.050442)
		(mid 133.490076 150.873666)
		(end 133.416853 150.696889)
		(width 0.148)
		(layer "In9.Cu")
		(net 116)
	)
	(arc
		(start 133.581053 152.654015)
		(mid 133.507829 152.477239)
		(end 133.581052 152.300462)
		(width 0.148)
		(layer "In9.Cu")
		(net 116)
	)
	(arc
		(start 134.641717 153.361125)
		(mid 134.464941 153.434349)
		(end 134.288164 153.361126)
		(width 0.148)
		(layer "In9.Cu")
		(net 116)
	)
	(arc
		(start 134.123962 151.403998)
		(mid 133.947186 151.330774)
		(end 133.770409 151.403997)
		(width 0.148)
		(layer "In9.Cu")
		(net 116)
	)
	(arc
		(start 132.261512 150.791563)
		(mid 132.334735 150.614786)
		(end 132.261511 150.43801)
		(width 0.148)
		(layer "In9.Cu")
		(net 116)
	)
	(arc
		(start 134.288163 153.361125)
		(mid 134.214939 153.184349)
		(end 134.288162 153.007572)
		(width 0.148)
		(layer "In9.Cu")
		(net 116)
	)
	(arc
		(start 134.995273 154.068235)
		(mid 134.922049 153.891459)
		(end 134.995272 153.714682)
		(width 0.148)
		(layer "In9.Cu")
		(net 116)
	)
	(arc
		(start 135.702383 154.775345)
		(mid 135.629159 154.598569)
		(end 135.702382 154.421792)
		(width 0.148)
		(layer "In9.Cu")
		(net 116)
	)
	(arc
		(start 137.659512 154.939548)
		(mid 137.482736 154.866324)
		(end 137.305959 154.939547)
		(width 0.148)
		(layer "In9.Cu")
		(net 116)
	)
	(arc
		(start 134.831072 152.464662)
		(mid 134.904296 152.287886)
		(end 134.831073 152.111109)
		(width 0.148)
		(layer "In9.Cu")
		(net 116)
	)
	(arc
		(start 137.659512 155.293102)
		(mid 137.732736 155.116326)
		(end 137.659513 154.939549)
		(width 0.148)
		(layer "In9.Cu")
		(net 116)
	)
	(arc
		(start 132.520387 151.239795)
		(mid 132.343611 151.313019)
		(end 132.166834 151.239796)
		(width 0.148)
		(layer "In9.Cu")
		(net 116)
	)
	(arc
		(start 135.538182 153.171772)
		(mid 135.611406 152.994996)
		(end 135.538183 152.818219)
		(width 0.148)
		(layer "In9.Cu")
		(net 116)
	)
	(arc
		(start 132.873943 151.946905)
		(mid 132.800719 151.770129)
		(end 132.873942 151.593352)
		(width 0.148)
		(layer "In9.Cu")
		(net 116)
	)
	(arc
		(start 137.823715 156.896678)
		(mid 137.750491 156.719902)
		(end 137.823714 156.543125)
		(width 0.148)
		(layer "In9.Cu")
		(net 116)
	)
	(arc
		(start 137.470157 156.189565)
		(mid 137.293381 156.262789)
		(end 137.116604 156.189566)
		(width 0.148)
		(layer "In9.Cu")
		(net 116)
	)
	(arc
		(start 138.366622 155.646658)
		(mid 138.189846 155.573434)
		(end 138.013069 155.646657)
		(width 0.148)
		(layer "In9.Cu")
		(net 116)
	)
	(arc
		(start 133.416852 150.696888)
		(mid 133.240076 150.623664)
		(end 133.063299 150.696887)
		(width 0.148)
		(layer "In9.Cu")
		(net 116)
	)
	(arc
		(start 133.934607 152.654015)
		(mid 133.757831 152.727239)
		(end 133.581054 152.654016)
		(width 0.148)
		(layer "In9.Cu")
		(net 116)
	)
	(arc
		(start 137.116603 156.189565)
		(mid 137.043379 156.012789)
		(end 137.116602 155.836012)
		(width 0.148)
		(layer "In9.Cu")
		(net 116)
	)
	(arc
		(start 134.831072 152.111108)
		(mid 134.654296 152.037884)
		(end 134.477519 152.111107)
		(width 0.148)
		(layer "In9.Cu")
		(net 116)
	)
	(arc
		(start 136.245292 153.525328)
		(mid 136.068516 153.452104)
		(end 135.891739 153.525327)
		(width 0.148)
		(layer "In9.Cu")
		(net 116)
	)
	(arc
		(start 136.952402 154.232438)
		(mid 136.775626 154.159214)
		(end 136.598849 154.232437)
		(width 0.148)
		(layer "In9.Cu")
		(net 116)
	)
	(arc
		(start 136.245292 153.878882)
		(mid 136.318516 153.702106)
		(end 136.245293 153.525329)
		(width 0.148)
		(layer "In9.Cu")
		(net 116)
	)
	(arc
		(start 133.227497 151.946905)
		(mid 133.050721 152.020129)
		(end 132.873944 151.946906)
		(width 0.148)
		(layer "In9.Cu")
		(net 116)
	)
	(arc
		(start 135.348827 154.068235)
		(mid 135.172051 154.141459)
		(end 134.995274 154.068236)
		(width 0.148)
		(layer "In9.Cu")
		(net 116)
	)
	(arc
		(start 136.409493 155.482455)
		(mid 136.336269 155.305679)
		(end 136.409492 155.128902)
		(width 0.148)
		(layer "In9.Cu")
		(net 116)
	)
	(arc
		(start 134.123962 151.757552)
		(mid 134.197186 151.580776)
		(end 134.123963 151.403999)
		(width 0.148)
		(layer "In9.Cu")
		(net 116)
	)
	(arc
		(start 136.055937 154.775345)
		(mid 135.879161 154.848569)
		(end 135.702384 154.775346)
		(width 0.148)
		(layer "In9.Cu")
		(net 116)
	)
	(arc
		(start 138.366622 156.000212)
		(mid 138.439846 155.823436)
		(end 138.366623 155.646659)
		(width 0.148)
		(layer "In9.Cu")
		(net 116)
	)
	(arc
		(start 135.538182 152.818218)
		(mid 135.361406 152.744994)
		(end 135.184629 152.818217)
		(width 0.148)
		(layer "In9.Cu")
		(net 116)
	)
	(arc
		(start 136.952402 154.585992)
		(mid 137.025626 154.409216)
		(end 136.952403 154.232439)
		(width 0.148)
		(layer "In9.Cu")
		(net 116)
	)
	(segment
		(start 144.375501 162.302)
		(end 144.875001 161.8025)
		(width 0.256)
		(layer "F.Cu")
		(net 117)
	)
	(segment
		(start 131.150001 139.4025)
		(end 131.170001 139.4225)
		(width 0.26)
		(layer "F.Cu")
		(net 117)
	)
	(segment
		(start 131.17 139.892427)
		(end 131.125001 139.937426)
		(width 0.26)
		(layer "F.Cu")
		(net 117)
	)
	(segment
		(start 131.150001 138.8025)
		(end 131.150001 139.4025)
		(width 0.26)
		(layer "F.Cu")
		(net 117)
	)
	(segment
		(start 131.170001 139.4225)
		(end 131.17 139.892427)
		(width 0.26)
		(layer "F.Cu")
		(net 117)
	)
	(via
		(at 131.125001 139.937426)
		(size 0.45)
		(drill 0.1)
		(layers "F.Cu" "B.Cu")
		(net 117)
	)
	(via
		(at 144.875001 161.8025)
		(size 0.45)
		(drill 0.1)
		(layers "F.Cu" "B.Cu")
		(net 117)
	)
	(segment
		(start 145.254088 159.923413)
		(end 145.254088 157.843223)
		(width 0.13)
		(layer "In9.Cu")
		(net 117)
	)
	(segment
		(start 144.973001 162.202499)
		(end 145.106246 162.202499)
		(width 0.1)
		(layer "In9.Cu")
		(net 117)
	)
	(segment
		(start 145.275001 161.35312)
		(end 145.254088 161.332207)
		(width 0.1)
		(layer "In9.Cu")
		(net 117)
	)
	(segment
		(start 144.875001 162.104499)
		(end 144.973001 162.202499)
		(width 0.1)
		(layer "In9.Cu")
		(net 117)
	)
	(segment
		(start 131.280001 140.092426)
		(end 131.125001 139.937426)
		(width 0.13)
		(layer "In9.Cu")
		(net 117)
	)
	(segment
		(start 131.280001 141.125206)
		(end 131.280001 140.092426)
		(width 0.13)
		(layer "In9.Cu")
		(net 117)
	)
	(segment
		(start 131.821795 141.667)
		(end 131.280001 141.125206)
		(width 0.13)
		(layer "In9.Cu")
		(net 117)
	)
	(segment
		(start 145.02989 160.148413)
		(end 145.079088 160.148413)
		(width 0.13)
		(layer "In9.Cu")
		(net 117)
	)
	(segment
		(start 145.254088 159.973413)
		(end 145.254088 159.923413)
		(width 0.13)
		(layer "In9.Cu")
		(net 117)
	)
	(segment
		(start 137.077865 141.667)
		(end 131.821795 141.667)
		(width 0.13)
		(layer "In9.Cu")
		(net 117)
	)
	(segment
		(start 144.875001 161.8025)
		(end 144.875001 162.104499)
		(width 0.1)
		(layer "In9.Cu")
		(net 117)
	)
	(segment
		(start 138.260501 150.849636)
		(end 138.260501 142.849636)
		(width 0.13)
		(layer "In9.Cu")
		(net 117)
	)
	(segment
		(start 145.254088 161.332207)
		(end 145.254088 160.673413)
		(width 0.13)
		(layer "In9.Cu")
		(net 117)
	)
	(segment
		(start 145.275001 162.033744)
		(end 145.275001 161.35312)
		(width 0.1)
		(layer "In9.Cu")
		(net 117)
	)
	(segment
		(start 145.254088 157.843223)
		(end 138.260501 150.849636)
		(width 0.13)
		(layer "In9.Cu")
		(net 117)
	)
	(segment
		(start 145.106246 162.202499)
		(end 145.275001 162.033744)
		(width 0.1)
		(layer "In9.Cu")
		(net 117)
	)
	(segment
		(start 145.079088 160.498413)
		(end 145.02989 160.498413)
		(width 0.13)
		(layer "In9.Cu")
		(net 117)
	)
	(segment
		(start 138.260501 142.849636)
		(end 137.077865 141.667)
		(width 0.13)
		(layer "In9.Cu")
		(net 117)
	)
	(arc
		(start 145.254088 160.673413)
		(mid 145.202832 160.549669)
		(end 145.079088 160.498413)
		(width 0.13)
		(layer "In9.Cu")
		(net 117)
	)
	(arc
		(start 145.02989 160.498413)
		(mid 144.906146 160.447157)
		(end 144.85489 160.323413)
		(width 0.13)
		(layer "In9.Cu")
		(net 117)
	)
	(arc
		(start 144.85489 160.323413)
		(mid 144.906146 160.199669)
		(end 145.02989 160.148413)
		(width 0.13)
		(layer "In9.Cu")
		(net 117)
	)
	(arc
		(start 145.079088 160.148413)
		(mid 145.202832 160.097157)
		(end 145.254088 159.973413)
		(width 0.13)
		(layer "In9.Cu")
		(net 117)
	)
	(segment
		(start 131.630002 139.892427)
		(end 131.675001 139.937426)
		(width 0.26)
		(layer "F.Cu")
		(net 118)
	)
	(segment
		(start 144.375501 163.302)
		(end 144.875001 162.8025)
		(width 0.256)
		(layer "F.Cu")
		(net 118)
	)
	(segment
		(start 131.650001 138.8025)
		(end 131.650001 139.4025)
		(width 0.26)
		(layer "F.Cu")
		(net 118)
	)
	(segment
		(start 131.650001 139.4025)
		(end 131.630001 139.4225)
		(width 0.26)
		(layer "F.Cu")
		(net 118)
	)
	(segment
		(start 131.630001 139.4225)
		(end 131.630002 139.892427)
		(width 0.26)
		(layer "F.Cu")
		(net 118)
	)
	(via
		(at 144.875001 162.8025)
		(size 0.45)
		(drill 0.1)
		(layers "F.Cu" "B.Cu")
		(net 118)
	)
	(via
		(at 131.675001 139.937426)
		(size 0.45)
		(drill 0.1)
		(layers "F.Cu" "B.Cu")
		(net 118)
	)
	(segment
		(start 145.475001 161.351294)
		(end 145.494088 161.332207)
		(width 0.1)
		(layer "In9.Cu")
		(net 118)
	)
	(segment
		(start 131.931207 141.437)
		(end 131.520001 141.025794)
		(width 0.13)
		(layer "In9.Cu")
		(net 118)
	)
	(segment
		(start 138.490501 150.754364)
		(end 138.490501 142.754364)
		(width 0.13)
		(layer "In9.Cu")
		(net 118)
	)
	(segment
		(start 131.520001 141.025794)
		(end 131.520001 140.092426)
		(width 0.13)
		(layer "In9.Cu")
		(net 118)
	)
	(segment
		(start 138.490501 142.754364)
		(end 137.173137 141.437)
		(width 0.13)
		(layer "In9.Cu")
		(net 118)
	)
	(segment
		(start 145.494088 161.332207)
		(end 145.494088 157.757951)
		(width 0.13)
		(layer "In9.Cu")
		(net 118)
	)
	(segment
		(start 131.520001 140.092426)
		(end 131.675001 139.937426)
		(width 0.13)
		(layer "In9.Cu")
		(net 118)
	)
	(segment
		(start 145.494088 157.757951)
		(end 138.490501 150.754364)
		(width 0.13)
		(layer "In9.Cu")
		(net 118)
	)
	(segment
		(start 144.977001 162.4025)
		(end 145.189089 162.4025)
		(width 0.1)
		(layer "In9.Cu")
		(net 118)
	)
	(segment
		(start 145.475001 162.116588)
		(end 145.475001 161.351294)
		(width 0.1)
		(layer "In9.Cu")
		(net 118)
	)
	(segment
		(start 144.875001 162.8025)
		(end 144.875001 162.5045)
		(width 0.1)
		(layer "In9.Cu")
		(net 118)
	)
	(segment
		(start 145.189089 162.4025)
		(end 145.475001 162.116588)
		(width 0.1)
		(layer "In9.Cu")
		(net 118)
	)
	(segment
		(start 144.875001 162.5045)
		(end 144.977001 162.4025)
		(width 0.1)
		(layer "In9.Cu")
		(net 118)
	)
	(segment
		(start 137.173137 141.437)
		(end 131.931207 141.437)
		(width 0.13)
		(layer "In9.Cu")
		(net 118)
	)
	(segment
		(start 139.375501 170.302)
		(end 139.875001 169.802499)
		(width 0.256)
		(layer "F.Cu")
		(net 119)
	)
	(segment
		(start 131.900001 146.2025)
		(end 131.900001 147.2775)
		(width 0.201)
		(layer "F.Cu")
		(net 119)
	)
	(via
		(at 139.875001 169.802499)
		(size 0.45)
		(drill 0.1)
		(layers "F.Cu" "B.Cu")
		(net 119)
	)
	(via
		(at 131.900001 147.2775)
		(size 0.45)
		(drill 0.1)
		(layers "F.Cu" "B.Cu")
		(net 119)
	)
	(segment
		(start 134.413251 149.346924)
		(end 134.41325 149.346925)
		(width 0.148)
		(layer "In9.Cu")
		(net 119)
	)
	(segment
		(start 133.282949 148.709449)
		(end 131.900001 147.3265)
		(width 0.148)
		(layer "In9.Cu")
		(net 119)
	)
	(segment
		(start 138.302359 152.882479)
		(end 138.302359 152.88248)
		(width 0.148)
		(layer "In9.Cu")
		(net 119)
	)
	(segment
		(start 138.516646 154.789524)
		(end 138.516648 154.789525)
		(width 0.148)
		(layer "In9.Cu")
		(net 119)
	)
	(segment
		(start 136.181026 150.761146)
		(end 136.181026 150.761147)
		(width 0.148)
		(layer "In9.Cu")
		(net 119)
	)
	(segment
		(start 134.981091 151.253969)
		(end 134.981093 151.25397)
		(width 0.148)
		(layer "In9.Cu")
		(net 119)
	)
	(segment
		(start 137.809537 153.72886)
		(end 138.302359 153.236033)
		(width 0.148)
		(layer "In9.Cu")
		(net 119)
	)
	(segment
		(start 139.223757 155.496635)
		(end 139.223756 155.496634)
		(width 0.148)
		(layer "In9.Cu")
		(net 119)
	)
	(segment
		(start 133.70614 148.639813)
		(end 133.706139 148.639814)
		(width 0.148)
		(layer "In9.Cu")
		(net 119)
	)
	(segment
		(start 139.646947 155.427)
		(end 139.57731 155.496634)
		(width 0.148)
		(layer "In9.Cu")
		(net 119)
	)
	(segment
		(start 134.273981 150.193306)
		(end 134.273982 150.193305)
		(width 0.148)
		(layer "In9.Cu")
		(net 119)
	)
	(segment
		(start 137.948805 152.88248)
		(end 137.455978 153.375302)
		(width 0.148)
		(layer "In9.Cu")
		(net 119)
	)
	(segment
		(start 134.27398 150.546858)
		(end 134.273982 150.546859)
		(width 0.148)
		(layer "In9.Cu")
		(net 119)
	)
	(segment
		(start 134.059693 148.639813)
		(end 134.059693 148.639814)
		(width 0.148)
		(layer "In9.Cu")
		(net 119)
	)
	(segment
		(start 136.888137 151.468257)
		(end 136.888137 151.468258)
		(width 0.148)
		(layer "In9.Cu")
		(net 119)
	)
	(segment
		(start 139.875001 169.802499)
		(end 140.377001 169.300499)
		(width 0.148)
		(layer "In9.Cu")
		(net 119)
	)
	(segment
		(start 135.688203 151.607528)
		(end 135.688204 151.607527)
		(width 0.148)
		(layer "In9.Cu")
		(net 119)
	)
	(segment
		(start 138.516647 154.435972)
		(end 138.516648 154.435971)
		(width 0.148)
		(layer "In9.Cu")
		(net 119)
	)
	(segment
		(start 137.809536 153.728861)
		(end 137.809537 153.72886)
		(width 0.148)
		(layer "In9.Cu")
		(net 119)
	)
	(segment
		(start 136.395313 152.668191)
		(end 136.395315 152.668192)
		(width 0.148)
		(layer "In9.Cu")
		(net 119)
	)
	(segment
		(start 140.377001 155.8035)
		(end 140.000501 155.427)
		(width 0.148)
		(layer "In9.Cu")
		(net 119)
	)
	(segment
		(start 133.566871 149.486194)
		(end 134.059693 148.993367)
		(width 0.148)
		(layer "In9.Cu")
		(net 119)
	)
	(segment
		(start 133.706139 148.639814)
		(end 133.636503 148.709449)
		(width 0.148)
		(layer "In9.Cu")
		(net 119)
	)
	(segment
		(start 137.102426 153.021749)
		(end 137.595248 152.528922)
		(width 0.148)
		(layer "In9.Cu")
		(net 119)
	)
	(segment
		(start 134.981093 150.900416)
		(end 135.473915 150.407589)
		(width 0.148)
		(layer "In9.Cu")
		(net 119)
	)
	(segment
		(start 135.473915 150.054035)
		(end 135.473915 150.054036)
		(width 0.148)
		(layer "In9.Cu")
		(net 119)
	)
	(segment
		(start 137.241695 152.175368)
		(end 137.241694 152.175369)
		(width 0.148)
		(layer "In9.Cu")
		(net 119)
	)
	(segment
		(start 138.655916 153.589591)
		(end 138.163089 154.082413)
		(width 0.148)
		(layer "In9.Cu")
		(net 119)
	)
	(segment
		(start 135.688202 151.96108)
		(end 135.688204 151.961081)
		(width 0.148)
		(layer "In9.Cu")
		(net 119)
	)
	(segment
		(start 139.223755 155.143081)
		(end 139.223756 155.14308)
		(width 0.148)
		(layer "In9.Cu")
		(net 119)
	)
	(segment
		(start 139.363027 154.296702)
		(end 138.8702 154.789524)
		(width 0.148)
		(layer "In9.Cu")
		(net 119)
	)
	(segment
		(start 134.981092 150.900417)
		(end 134.981093 150.900416)
		(width 0.148)
		(layer "In9.Cu")
		(net 119)
	)
	(segment
		(start 140.377001 169.300499)
		(end 140.377001 155.8035)
		(width 0.148)
		(layer "In9.Cu")
		(net 119)
	)
	(segment
		(start 133.56687 149.486195)
		(end 133.566871 149.486194)
		(width 0.148)
		(layer "In9.Cu")
		(net 119)
	)
	(segment
		(start 135.827473 150.761146)
		(end 135.827472 150.761147)
		(width 0.148)
		(layer "In9.Cu")
		(net 119)
	)
	(segment
		(start 134.273982 150.193305)
		(end 134.766804 149.700478)
		(width 0.148)
		(layer "In9.Cu")
		(net 119)
	)
	(segment
		(start 137.595248 152.175368)
		(end 137.595248 152.175369)
		(width 0.148)
		(layer "In9.Cu")
		(net 119)
	)
	(segment
		(start 135.120362 150.054035)
		(end 135.120361 150.054036)
		(width 0.148)
		(layer "In9.Cu")
		(net 119)
	)
	(segment
		(start 136.534584 151.468257)
		(end 136.534583 151.468258)
		(width 0.148)
		(layer "In9.Cu")
		(net 119)
	)
	(segment
		(start 136.395314 152.314639)
		(end 136.395315 152.314638)
		(width 0.148)
		(layer "In9.Cu")
		(net 119)
	)
	(segment
		(start 136.395315 152.314638)
		(end 136.888137 151.821811)
		(width 0.148)
		(layer "In9.Cu")
		(net 119)
	)
	(segment
		(start 134.766804 149.346924)
		(end 134.766804 149.346925)
		(width 0.148)
		(layer "In9.Cu")
		(net 119)
	)
	(segment
		(start 135.120361 150.054036)
		(end 134.627534 150.546858)
		(width 0.148)
		(layer "In9.Cu")
		(net 119)
	)
	(segment
		(start 137.809535 154.082413)
		(end 137.809537 154.082414)
		(width 0.148)
		(layer "In9.Cu")
		(net 119)
	)
	(segment
		(start 139.716581 154.296701)
		(end 139.716581 154.296702)
		(width 0.148)
		(layer "In9.Cu")
		(net 119)
	)
	(segment
		(start 131.900001 147.3265)
		(end 131.900001 147.2775)
		(width 0.148)
		(layer "In9.Cu")
		(net 119)
	)
	(segment
		(start 139.00947 153.58959)
		(end 139.00947 153.589591)
		(width 0.148)
		(layer "In9.Cu")
		(net 119)
	)
	(segment
		(start 137.102425 153.02175)
		(end 137.102426 153.021749)
		(width 0.148)
		(layer "In9.Cu")
		(net 119)
	)
	(segment
		(start 137.102424 153.375302)
		(end 137.102426 153.375303)
		(width 0.148)
		(layer "In9.Cu")
		(net 119)
	)
	(segment
		(start 134.41325 149.346925)
		(end 133.920423 149.839747)
		(width 0.148)
		(layer "In9.Cu")
		(net 119)
	)
	(segment
		(start 133.566869 149.839747)
		(end 133.566871 149.839748)
		(width 0.148)
		(layer "In9.Cu")
		(net 119)
	)
	(segment
		(start 139.646948 155.426999)
		(end 139.646947 155.427)
		(width 0.148)
		(layer "In9.Cu")
		(net 119)
	)
	(segment
		(start 137.241694 152.175369)
		(end 136.748867 152.668191)
		(width 0.148)
		(layer "In9.Cu")
		(net 119)
	)
	(segment
		(start 138.516648 154.435971)
		(end 139.00947 153.943144)
		(width 0.148)
		(layer "In9.Cu")
		(net 119)
	)
	(segment
		(start 135.688204 151.607527)
		(end 136.181026 151.1147)
		(width 0.148)
		(layer "In9.Cu")
		(net 119)
	)
	(segment
		(start 133.28295 148.70945)
		(end 133.282949 148.709449)
		(width 0.148)
		(layer "In9.Cu")
		(net 119)
	)
	(segment
		(start 138.655917 153.58959)
		(end 138.655916 153.589591)
		(width 0.148)
		(layer "In9.Cu")
		(net 119)
	)
	(segment
		(start 139.223756 155.14308)
		(end 139.716581 154.650255)
		(width 0.148)
		(layer "In9.Cu")
		(net 119)
	)
	(segment
		(start 136.534583 151.468258)
		(end 136.041756 151.96108)
		(width 0.148)
		(layer "In9.Cu")
		(net 119)
	)
	(segment
		(start 135.827472 150.761147)
		(end 135.334645 151.253969)
		(width 0.148)
		(layer "In9.Cu")
		(net 119)
	)
	(segment
		(start 137.948806 152.882479)
		(end 137.948805 152.88248)
		(width 0.148)
		(layer "In9.Cu")
		(net 119)
	)
	(segment
		(start 139.363028 154.296701)
		(end 139.363027 154.296702)
		(width 0.148)
		(layer "In9.Cu")
		(net 119)
	)
	(arc
		(start 134.059693 148.993367)
		(mid 134.132916 148.81659)
		(end 134.059693 148.639813)
		(width 0.148)
		(layer "In9.Cu")
		(net 119)
	)
	(arc
		(start 138.302359 153.236033)
		(mid 138.375582 153.059256)
		(end 138.302359 152.882479)
		(width 0.148)
		(layer "In9.Cu")
		(net 119)
	)
	(arc
		(start 136.181026 150.761147)
		(mid 136.00425 150.687923)
		(end 135.827473 150.761146)
		(width 0.148)
		(layer "In9.Cu")
		(net 119)
	)
	(arc
		(start 138.302359 152.88248)
		(mid 138.125583 152.809256)
		(end 137.948806 152.882479)
		(width 0.148)
		(layer "In9.Cu")
		(net 119)
	)
	(arc
		(start 140.000501 155.427)
		(mid 139.823725 155.353776)
		(end 139.646948 155.426999)
		(width 0.148)
		(layer "In9.Cu")
		(net 119)
	)
	(arc
		(start 133.920423 149.839747)
		(mid 133.743646 149.91297)
		(end 133.566869 149.839747)
		(width 0.148)
		(layer "In9.Cu")
		(net 119)
	)
	(arc
		(start 138.163089 154.082413)
		(mid 137.986312 154.155636)
		(end 137.809535 154.082413)
		(width 0.148)
		(layer "In9.Cu")
		(net 119)
	)
	(arc
		(start 135.688204 151.961081)
		(mid 135.61498 151.784305)
		(end 135.688203 151.607528)
		(width 0.148)
		(layer "In9.Cu")
		(net 119)
	)
	(arc
		(start 134.766804 149.346925)
		(mid 134.590028 149.273701)
		(end 134.413251 149.346924)
		(width 0.148)
		(layer "In9.Cu")
		(net 119)
	)
	(arc
		(start 137.455978 153.375302)
		(mid 137.279201 153.448525)
		(end 137.102424 153.375302)
		(width 0.148)
		(layer "In9.Cu")
		(net 119)
	)
	(arc
		(start 134.627534 150.546858)
		(mid 134.450757 150.620081)
		(end 134.27398 150.546858)
		(width 0.148)
		(layer "In9.Cu")
		(net 119)
	)
	(arc
		(start 137.595248 152.528922)
		(mid 137.668471 152.352145)
		(end 137.595248 152.175368)
		(width 0.148)
		(layer "In9.Cu")
		(net 119)
	)
	(arc
		(start 134.766804 149.700478)
		(mid 134.840027 149.523701)
		(end 134.766804 149.346924)
		(width 0.148)
		(layer "In9.Cu")
		(net 119)
	)
	(arc
		(start 135.334645 151.253969)
		(mid 135.157868 151.327192)
		(end 134.981091 151.253969)
		(width 0.148)
		(layer "In9.Cu")
		(net 119)
	)
	(arc
		(start 139.00947 153.943144)
		(mid 139.082693 153.766367)
		(end 139.00947 153.58959)
		(width 0.148)
		(layer "In9.Cu")
		(net 119)
	)
	(arc
		(start 138.8702 154.789524)
		(mid 138.693423 154.862747)
		(end 138.516646 154.789524)
		(width 0.148)
		(layer "In9.Cu")
		(net 119)
	)
	(arc
		(start 136.181026 151.1147)
		(mid 136.254249 150.937923)
		(end 136.181026 150.761146)
		(width 0.148)
		(layer "In9.Cu")
		(net 119)
	)
	(arc
		(start 139.223756 155.496634)
		(mid 139.150532 155.319858)
		(end 139.223755 155.143081)
		(width 0.148)
		(layer "In9.Cu")
		(net 119)
	)
	(arc
		(start 139.716581 154.650255)
		(mid 139.789804 154.473478)
		(end 139.716581 154.296701)
		(width 0.148)
		(layer "In9.Cu")
		(net 119)
	)
	(arc
		(start 134.059693 148.639814)
		(mid 133.882917 148.56659)
		(end 133.70614 148.639813)
		(width 0.148)
		(layer "In9.Cu")
		(net 119)
	)
	(arc
		(start 136.888137 151.821811)
		(mid 136.96136 151.645034)
		(end 136.888137 151.468257)
		(width 0.148)
		(layer "In9.Cu")
		(net 119)
	)
	(arc
		(start 137.102426 153.375303)
		(mid 137.029202 153.198527)
		(end 137.102425 153.02175)
		(width 0.148)
		(layer "In9.Cu")
		(net 119)
	)
	(arc
		(start 133.566871 149.839748)
		(mid 133.493647 149.662972)
		(end 133.56687 149.486195)
		(width 0.148)
		(layer "In9.Cu")
		(net 119)
	)
	(arc
		(start 137.595248 152.175369)
		(mid 137.418472 152.102145)
		(end 137.241695 152.175368)
		(width 0.148)
		(layer "In9.Cu")
		(net 119)
	)
	(arc
		(start 136.888137 151.468258)
		(mid 136.711361 151.395034)
		(end 136.534584 151.468257)
		(width 0.148)
		(layer "In9.Cu")
		(net 119)
	)
	(arc
		(start 137.809537 154.082414)
		(mid 137.736313 153.905638)
		(end 137.809536 153.728861)
		(width 0.148)
		(layer "In9.Cu")
		(net 119)
	)
	(arc
		(start 134.981093 151.25397)
		(mid 134.907869 151.077194)
		(end 134.981092 150.900417)
		(width 0.148)
		(layer "In9.Cu")
		(net 119)
	)
	(arc
		(start 136.748867 152.668191)
		(mid 136.57209 152.741414)
		(end 136.395313 152.668191)
		(width 0.148)
		(layer "In9.Cu")
		(net 119)
	)
	(arc
		(start 135.473915 150.407589)
		(mid 135.547138 150.230812)
		(end 135.473915 150.054035)
		(width 0.148)
		(layer "In9.Cu")
		(net 119)
	)
	(arc
		(start 139.57731 155.496634)
		(mid 139.400534 155.569858)
		(end 139.223757 155.496635)
		(width 0.148)
		(layer "In9.Cu")
		(net 119)
	)
	(arc
		(start 136.041756 151.96108)
		(mid 135.864979 152.034303)
		(end 135.688202 151.96108)
		(width 0.148)
		(layer "In9.Cu")
		(net 119)
	)
	(arc
		(start 139.716581 154.296702)
		(mid 139.539805 154.223478)
		(end 139.363028 154.296701)
		(width 0.148)
		(layer "In9.Cu")
		(net 119)
	)
	(arc
		(start 133.636503 148.709449)
		(mid 133.459727 148.782673)
		(end 133.28295 148.70945)
		(width 0.148)
		(layer "In9.Cu")
		(net 119)
	)
	(arc
		(start 135.473915 150.054036)
		(mid 135.297139 149.980812)
		(end 135.120362 150.054035)
		(width 0.148)
		(layer "In9.Cu")
		(net 119)
	)
	(arc
		(start 138.516648 154.789525)
		(mid 138.443424 154.612749)
		(end 138.516647 154.435972)
		(width 0.148)
		(layer "In9.Cu")
		(net 119)
	)
	(arc
		(start 134.273982 150.546859)
		(mid 134.200758 150.370083)
		(end 134.273981 150.193306)
		(width 0.148)
		(layer "In9.Cu")
		(net 119)
	)
	(arc
		(start 139.00947 153.589591)
		(mid 138.832694 153.516367)
		(end 138.655917 153.58959)
		(width 0.148)
		(layer "In9.Cu")
		(net 119)
	)
	(arc
		(start 136.395315 152.668192)
		(mid 136.322091 152.491416)
		(end 136.395314 152.314639)
		(width 0.148)
		(layer "In9.Cu")
		(net 119)
	)
	(segment
		(start 132.650001 138.8025)
		(end 132.650001 139.8775)
		(width 0.201)
		(layer "F.Cu")
		(net 120)
	)
	(segment
		(start 140.375501 167.302)
		(end 140.875001 166.8025)
		(width 0.256)
		(layer "F.Cu")
		(net 120)
	)
	(via
		(at 132.650001 139.8775)
		(size 0.45)
		(drill 0.1)
		(layers "F.Cu" "B.Cu")
		(net 120)
	)
	(via
		(at 140.875001 166.8025)
		(size 0.45)
		(drill 0.1)
		(layers "F.Cu" "B.Cu")
		(net 120)
	)
	(segment
		(start 140.338501 166.266)
		(end 140.875001 166.8025)
		(width 0.1)
		(layer "In4.Cu")
		(net 120)
	)
	(segment
		(start 139.266 166.266)
		(end 140.338501 166.266)
		(width 0.1)
		(layer "In4.Cu")
		(net 120)
	)
	(segment
		(start 129.890501 153.640501)
		(end 137.4 161.15)
		(width 0.1)
		(layer "In4.Cu")
		(net 120)
	)
	(segment
		(start 137.72167 165.1775)
		(end 138.1775 165.1775)
		(width 0.1)
		(layer "In4.Cu")
		(net 120)
	)
	(segment
		(start 129.390501 147.886)
		(end 129.890501 148.386)
		(width 0.1)
		(layer "In4.Cu")
		(net 120)
	)
	(segment
		(start 138.1775 165.1775)
		(end 139.266 166.266)
		(width 0.1)
		(layer "In4.Cu")
		(net 120)
	)
	(segment
		(start 129.390501 146.586)
		(end 129.390501 147.886)
		(width 0.1)
		(layer "In4.Cu")
		(net 120)
	)
	(segment
		(start 137.4 164.85583)
		(end 137.72167 165.1775)
		(width 0.1)
		(layer "In4.Cu")
		(net 120)
	)
	(segment
		(start 132.6225 139.8775)
		(end 129.974501 142.525499)
		(width 0.1)
		(layer "In4.Cu")
		(net 120)
	)
	(segment
		(start 129.974501 146.002)
		(end 129.390501 146.586)
		(width 0.1)
		(layer "In4.Cu")
		(net 120)
	)
	(segment
		(start 129.890501 148.386)
		(end 129.890501 153.640501)
		(width 0.1)
		(layer "In4.Cu")
		(net 120)
	)
	(segment
		(start 129.974501 142.525499)
		(end 129.974501 146.002)
		(width 0.1)
		(layer "In4.Cu")
		(net 120)
	)
	(segment
		(start 137.4 161.15)
		(end 137.4 164.85583)
		(width 0.1)
		(layer "In4.Cu")
		(net 120)
	)
	(segment
		(start 132.650001 139.8775)
		(end 132.6225 139.8775)
		(width 0.1)
		(layer "In4.Cu")
		(net 120)
	)
	(segment
		(start 141.375501 164.302)
		(end 141.875001 163.8025)
		(width 0.256)
		(layer "F.Cu")
		(net 121)
	)
	(segment
		(start 132.900001 146.2025)
		(end 132.900001 147.2775)
		(width 0.201)
		(layer "F.Cu")
		(net 121)
	)
	(via
		(at 141.875001 163.8025)
		(size 0.45)
		(drill 0.1)
		(layers "F.Cu" "B.Cu")
		(net 121)
	)
	(via
		(at 132.900001 147.2775)
		(size 0.45)
		(drill 0.1)
		(layers "F.Cu" "B.Cu")
		(net 121)
	)
	(segment
		(start 132.900001 147.2775)
		(end 132.900001 151.900001)
		(width 0.1)
		(layer "In4.Cu")
		(net 121)
	)
	(segment
		(start 134.625517 152.495804)
		(end 134.625516 152.495802)
		(width 0.1)
		(layer "In4.Cu")
		(net 121)
	)
	(segment
		(start 134.944542 153.944542)
		(end 134.944544 153.944544)
		(width 0.1)
		(layer "In4.Cu")
		(net 121)
	)
	(segment
		(start 136.746836 154.970676)
		(end 136.746838 154.970677)
		(width 0.1)
		(layer "In4.Cu")
		(net 121)
	)
	(segment
		(start 136.039731 154.26357)
		(end 135.651649 154.651649)
		(width 0.1)
		(layer "In4.Cu")
		(net 121)
	)
	(segment
		(start 141.390501 160.390501)
		(end 141.390501 163.318)
		(width 0.1)
		(layer "In4.Cu")
		(net 121)
	)
	(segment
		(start 135.651651 154.651651)
		(end 135.26357 155.039731)
		(width 0.1)
		(layer "In4.Cu")
		(net 121)
	)
	(segment
		(start 133.353554 152.000001)
		(end 133.564856 151.788696)
		(width 0.1)
		(layer "In4.Cu")
		(net 121)
	)
	(segment
		(start 134.910016 154.686177)
		(end 135.686176 153.910015)
		(width 0.1)
		(layer "In4.Cu")
		(net 121)
	)
	(segment
		(start 141.390501 163.318)
		(end 141.875001 163.8025)
		(width 0.1)
		(layer "In4.Cu")
		(net 121)
	)
	(segment
		(start 133.353553 151.999999)
		(end 133.353554 152.000001)
		(width 0.1)
		(layer "In4.Cu")
		(net 121)
	)
	(segment
		(start 135.617123 155.393284)
		(end 136.393283 154.617122)
		(width 0.1)
		(layer "In4.Cu")
		(net 121)
	)
	(segment
		(start 134.910016 154.686176)
		(end 134.910016 154.686177)
		(width 0.1)
		(layer "In4.Cu")
		(net 121)
	)
	(segment
		(start 133.918409 152.14225)
		(end 133.918409 152.142249)
		(width 0.1)
		(layer "In4.Cu")
		(net 121)
	)
	(segment
		(start 136.039731 153.910018)
		(end 136.03973 153.910016)
		(width 0.1)
		(layer "In4.Cu")
		(net 121)
	)
	(segment
		(start 134.625517 152.849356)
		(end 134.237435 153.237435)
		(width 0.1)
		(layer "In4.Cu")
		(net 121)
	)
	(segment
		(start 134.202909 153.979069)
		(end 134.202909 153.97907)
		(width 0.1)
		(layer "In4.Cu")
		(net 121)
	)
	(segment
		(start 132.900001 151.900001)
		(end 133 152)
		(width 0.1)
		(layer "In4.Cu")
		(net 121)
	)
	(segment
		(start 136.746838 154.617125)
		(end 136.746837 154.617123)
		(width 0.1)
		(layer "In4.Cu")
		(net 121)
	)
	(segment
		(start 135.651649 154.651649)
		(end 135.651651 154.651651)
		(width 0.1)
		(layer "In4.Cu")
		(net 121)
	)
	(segment
		(start 133.495802 153.271963)
		(end 134.271962 152.495801)
		(width 0.1)
		(layer "In4.Cu")
		(net 121)
	)
	(segment
		(start 134.237437 153.237437)
		(end 133.849356 153.625517)
		(width 0.1)
		(layer "In4.Cu")
		(net 121)
	)
	(segment
		(start 134.237435 153.237435)
		(end 134.237437 153.237437)
		(width 0.1)
		(layer "In4.Cu")
		(net 121)
	)
	(segment
		(start 133.91841 151.788696)
		(end 133.91841 151.788697)
		(width 0.1)
		(layer "In4.Cu")
		(net 121)
	)
	(segment
		(start 134.556464 154.686177)
		(end 134.556463 154.686177)
		(width 0.1)
		(layer "In4.Cu")
		(net 121)
	)
	(segment
		(start 135.617123 155.393283)
		(end 135.617123 155.393284)
		(width 0.1)
		(layer "In4.Cu")
		(net 121)
	)
	(segment
		(start 134.202909 153.97907)
		(end 134.979069 153.202908)
		(width 0.1)
		(layer "In4.Cu")
		(net 121)
	)
	(segment
		(start 136.535534 155.535533)
		(end 141.390501 160.390501)
		(width 0.1)
		(layer "In4.Cu")
		(net 121)
	)
	(segment
		(start 135.332622 153.556462)
		(end 135.332624 153.556463)
		(width 0.1)
		(layer "In4.Cu")
		(net 121)
	)
	(segment
		(start 136.535533 155.535533)
		(end 136.535534 155.535533)
		(width 0.1)
		(layer "In4.Cu")
		(net 121)
	)
	(segment
		(start 133.495802 153.271962)
		(end 133.495802 153.271963)
		(width 0.1)
		(layer "In4.Cu")
		(net 121)
	)
	(segment
		(start 135.332624 153.556463)
		(end 134.944542 153.944542)
		(width 0.1)
		(layer "In4.Cu")
		(net 121)
	)
	(segment
		(start 134.944544 153.944544)
		(end 134.556463 154.332624)
		(width 0.1)
		(layer "In4.Cu")
		(net 121)
	)
	(segment
		(start 133.918409 152.142249)
		(end 133.142249 152.91841)
		(width 0.1)
		(layer "In4.Cu")
		(net 121)
	)
	(segment
		(start 134.625515 152.849355)
		(end 134.625517 152.849356)
		(width 0.1)
		(layer "In4.Cu")
		(net 121)
	)
	(segment
		(start 136.039729 154.263569)
		(end 136.039731 154.26357)
		(width 0.1)
		(layer "In4.Cu")
		(net 121)
	)
	(segment
		(start 133.14225 153.271963)
		(end 133.142249 153.271963)
		(width 0.1)
		(layer "In4.Cu")
		(net 121)
	)
	(segment
		(start 135.332624 153.202911)
		(end 135.332623 153.202909)
		(width 0.1)
		(layer "In4.Cu")
		(net 121)
	)
	(segment
		(start 136.746838 154.970677)
		(end 136.535533 155.181979)
		(width 0.1)
		(layer "In4.Cu")
		(net 121)
	)
	(segment
		(start 135.263571 155.393284)
		(end 135.26357 155.393284)
		(width 0.1)
		(layer "In4.Cu")
		(net 121)
	)
	(segment
		(start 133.849357 153.97907)
		(end 133.849356 153.97907)
		(width 0.1)
		(layer "In4.Cu")
		(net 121)
	)
	(arc
		(start 136.535533 155.181979)
		(mid 136.46231 155.358756)
		(end 136.535533 155.535533)
		(width 0.1)
		(layer "In4.Cu")
		(net 121)
	)
	(arc
		(start 133.91841 151.788697)
		(mid 133.991633 151.965474)
		(end 133.918409 152.14225)
		(width 0.1)
		(layer "In4.Cu")
		(net 121)
	)
	(arc
		(start 136.746837 154.617123)
		(mid 136.82006 154.7939)
		(end 136.746836 154.970676)
		(width 0.1)
		(layer "In4.Cu")
		(net 121)
	)
	(arc
		(start 134.271962 152.495801)
		(mid 134.448741 152.42258)
		(end 134.625517 152.495804)
		(width 0.1)
		(layer "In4.Cu")
		(net 121)
	)
	(arc
		(start 133 152)
		(mid 133.176777 152.073223)
		(end 133.353553 151.999999)
		(width 0.1)
		(layer "In4.Cu")
		(net 121)
	)
	(arc
		(start 134.625516 152.495802)
		(mid 134.698739 152.672579)
		(end 134.625515 152.849355)
		(width 0.1)
		(layer "In4.Cu")
		(net 121)
	)
	(arc
		(start 136.03973 153.910016)
		(mid 136.112953 154.086793)
		(end 136.039729 154.263569)
		(width 0.1)
		(layer "In4.Cu")
		(net 121)
	)
	(arc
		(start 135.26357 155.393284)
		(mid 135.440347 155.466507)
		(end 135.617123 155.393283)
		(width 0.1)
		(layer "In4.Cu")
		(net 121)
	)
	(arc
		(start 133.849356 153.625517)
		(mid 133.776133 153.802294)
		(end 133.849357 153.97907)
		(width 0.1)
		(layer "In4.Cu")
		(net 121)
	)
	(arc
		(start 135.332623 153.202909)
		(mid 135.405846 153.379686)
		(end 135.332622 153.556462)
		(width 0.1)
		(layer "In4.Cu")
		(net 121)
	)
	(arc
		(start 133.849356 153.97907)
		(mid 134.026133 154.052293)
		(end 134.202909 153.979069)
		(width 0.1)
		(layer "In4.Cu")
		(net 121)
	)
	(arc
		(start 134.556463 154.332624)
		(mid 134.48324 154.509401)
		(end 134.556464 154.686177)
		(width 0.1)
		(layer "In4.Cu")
		(net 121)
	)
	(arc
		(start 134.556463 154.686177)
		(mid 134.73324 154.7594)
		(end 134.910016 154.686176)
		(width 0.1)
		(layer "In4.Cu")
		(net 121)
	)
	(arc
		(start 133.142249 153.271963)
		(mid 133.319026 153.345186)
		(end 133.495802 153.271962)
		(width 0.1)
		(layer "In4.Cu")
		(net 121)
	)
	(arc
		(start 135.26357 155.039731)
		(mid 135.190347 155.216508)
		(end 135.263571 155.393284)
		(width 0.1)
		(layer "In4.Cu")
		(net 121)
	)
	(arc
		(start 133.142249 152.91841)
		(mid 133.069026 153.095187)
		(end 133.14225 153.271963)
		(width 0.1)
		(layer "In4.Cu")
		(net 121)
	)
	(arc
		(start 134.979069 153.202908)
		(mid 135.155848 153.129687)
		(end 135.332624 153.202911)
		(width 0.1)
		(layer "In4.Cu")
		(net 121)
	)
	(arc
		(start 136.393283 154.617122)
		(mid 136.570062 154.543901)
		(end 136.746838 154.617125)
		(width 0.1)
		(layer "In4.Cu")
		(net 121)
	)
	(arc
		(start 135.686176 153.910015)
		(mid 135.862955 153.836794)
		(end 136.039731 153.910018)
		(width 0.1)
		(layer "In4.Cu")
		(net 121)
	)
	(arc
		(start 133.564856 151.788696)
		(mid 133.741633 151.715473)
		(end 133.91841 151.788696)
		(width 0.1)
		(layer "In4.Cu")
		(net 121)
	)
	(segment
		(start 133.150001 138.8025)
		(end 133.150001 137.7275)
		(width 0.201)
		(layer "F.Cu")
		(net 122)
	)
	(segment
		(start 139.375502 164.302)
		(end 139.875001 163.8025)
		(width 0.256)
		(layer "F.Cu")
		(net 122)
	)
	(via
		(at 139.875001 163.8025)
		(size 0.45)
		(drill 0.1)
		(layers "F.Cu" "B.Cu")
		(net 122)
	)
	(via
		(at 133.150001 137.7275)
		(size 0.45)
		(drill 0.1)
		(layers "F.Cu" "B.Cu")
		(net 122)
	)
	(segment
		(start 139.825001 161.1515)
		(end 139.500001 161.4765)
		(width 0.1)
		(layer "In2.Cu")
		(net 122)
	)
	(segment
		(start 136.85 144)
		(end 136.85 146.175501)
		(width 0.1)
		(layer "In2.Cu")
		(net 122)
	)
	(segment
		(start 139.825001 154.875001)
		(end 139.825001 161.1515)
		(width 0.1)
		(layer "In2.Cu")
		(net 122)
	)
	(segment
		(start 136.4 151.45)
		(end 139.825001 154.875001)
		(width 0.1)
		(layer "In2.Cu")
		(net 122)
	)
	(segment
		(start 136.4 146.625501)
		(end 136.4 151.45)
		(width 0.1)
		(layer "In2.Cu")
		(net 122)
	)
	(segment
		(start 139.500001 161.4765)
		(end 139.500001 163.4275)
		(width 0.1)
		(layer "In2.Cu")
		(net 122)
	)
	(segment
		(start 133.150001 140.300001)
		(end 136.85 144)
		(width 0.1)
		(layer "In2.Cu")
		(net 122)
	)
	(segment
		(start 133.150001 137.7275)
		(end 133.150001 140.300001)
		(width 0.1)
		(layer "In2.Cu")
		(net 122)
	)
	(segment
		(start 136.85 146.175501)
		(end 136.4 146.625501)
		(width 0.1)
		(layer "In2.Cu")
		(net 122)
	)
	(segment
		(start 139.500001 163.4275)
		(end 139.875001 163.8025)
		(width 0.1)
		(layer "In2.Cu")
		(net 122)
	)
	(segment
		(start 91.374138 143.222499)
		(end 92.627501 143.222499)
		(width 0.16)
		(layer "F.Cu")
		(net 123)
	)
	(segment
		(start 86.282987 140.378486)
		(end 89.621514 140.378486)
		(width 0.16)
		(layer "F.Cu")
		(net 123)
	)
	(segment
		(start 91.126514 137.678486)
		(end 91.126514 140.083486)
		(width 0.16)
		(layer "F.Cu")
		(net 123)
	)
	(segment
		(start 93.207501 150.741)
		(end 93.302501 150.836)
		(width 0.16)
		(layer "F.Cu")
		(net 123)
	)
	(segment
		(start 93.302501 150.836)
		(end 93.302501 151.286)
		(width 0.16)
		(layer "F.Cu")
		(net 123)
	)
	(segment
		(start 93.207501 143.802499)
		(end 93.207501 144.187456)
		(width 0.16)
		(layer "F.Cu")
		(net 123)
	)
	(segment
		(start 93.207501 141.588297)
		(end 93.207501 142.102499)
		(width 0.16)
		(layer "F.Cu")
		(net 123)
	)
	(segment
		(start 91.421514 140.378486)
		(end 91.99769 140.378486)
		(width 0.16)
		(layer "F.Cu")
		(net 123)
	)
	(segment
		(start 93.207501 144.187456)
		(end 93.207501 150.741)
		(width 0.16)
		(layer "F.Cu")
		(net 123)
	)
	(segment
		(start 86.210014 139.416487)
		(end 85.980501 139.646)
		(width 0.16)
		(layer "F.Cu")
		(net 123)
	)
	(segment
		(start 92.627501 142.682499)
		(end 91.374138 142.682499)
		(width 0.16)
		(layer "F.Cu")
		(net 123)
	)
	(segment
		(start 86.9905 139.416487)
		(end 86.210014 139.416487)
		(width 0.16)
		(layer "F.Cu")
		(net 123)
	)
	(segment
		(start 89.916514 140.083486)
		(end 89.916514 137.678486)
		(width 0.16)
		(layer "F.Cu")
		(net 123)
	)
	(segment
		(start 85.980501 140.076)
		(end 86.282987 140.378486)
		(width 0.16)
		(layer "F.Cu")
		(net 123)
	)
	(segment
		(start 91.99769 140.378486)
		(end 93.207501 141.588297)
		(width 0.16)
		(layer "F.Cu")
		(net 123)
	)
	(segment
		(start 85.980501 139.646)
		(end 85.980501 140.076)
		(width 0.16)
		(layer "F.Cu")
		(net 123)
	)
	(arc
		(start 89.621514 140.378486)
		(mid 89.830111 140.292083)
		(end 89.916514 140.083486)
		(width 0.16)
		(layer "F.Cu")
		(net 123)
	)
	(arc
		(start 91.126514 140.083486)
		(mid 91.212917 140.292083)
		(end 91.421514 140.378486)
		(width 0.16)
		(layer "F.Cu")
		(net 123)
	)
	(arc
		(start 89.916514 137.678486)
		(mid 90.093714 137.250686)
		(end 90.521514 137.073486)
		(width 0.16)
		(layer "F.Cu")
		(net 123)
	)
	(arc
		(start 92.627501 143.222499)
		(mid 93.037623 143.392377)
		(end 93.207501 143.802499)
		(width 0.16)
		(layer "F.Cu")
		(net 123)
	)
	(arc
		(start 91.374138 142.682499)
		(mid 91.183219 142.76158)
		(end 91.104138 142.952499)
		(width 0.16)
		(layer "F.Cu")
		(net 123)
	)
	(arc
		(start 90.521514 137.073486)
		(mid 90.949314 137.250686)
		(end 91.126514 137.678486)
		(width 0.16)
		(layer "F.Cu")
		(net 123)
	)
	(arc
		(start 91.104138 142.952499)
		(mid 91.183219 143.143418)
		(end 91.374138 143.222499)
		(width 0.16)
		(layer "F.Cu")
		(net 123)
	)
	(arc
		(start 93.207501 142.102499)
		(mid 93.037623 142.512621)
		(end 92.627501 142.682499)
		(width 0.16)
		(layer "F.Cu")
		(net 123)
	)
	(segment
		(start 94.205501 137.80119)
		(end 94.205501 137.261796)
		(width 0.16)
		(layer "F.Cu")
		(net 124)
	)
	(segment
		(start 94.205501 137.261796)
		(end 92.246741 135.303036)
		(width 0.16)
		(layer "F.Cu")
		(net 124)
	)
	(segment
		(start 92.246741 135.303036)
		(end 91.725372 135.303036)
		(width 0.16)
		(layer "F.Cu")
		(net 124)
	)
	(segment
		(start 94.205501 150.741)
		(end 94.205501 139.981609)
		(width 0.16)
		(layer "F.Cu")
		(net 124)
	)
	(segment
		(start 89.319948 135.303036)
		(end 86.181987 135.303036)
		(width 0.16)
		(layer "F.Cu")
		(net 124)
	)
	(segment
		(start 86.148014 134.344037)
		(end 86.9805 134.344037)
		(width 0.16)
		(layer "F.Cu")
		(net 124)
	)
	(segment
		(start 90.925372 134.472288)
		(end 90.725372 134.472288)
		(width 0.16)
		(layer "F.Cu")
		(net 124)
	)
	(segment
		(start 91.480372 135.058037)
		(end 91.480372 135.027288)
		(width 0.16)
		(layer "F.Cu")
		(net 124)
	)
	(segment
		(start 94.300501 150.836)
		(end 94.205501 150.741)
		(width 0.16)
		(layer "F.Cu")
		(net 124)
	)
	(segment
		(start 93.630501 139.406609)
		(end 92.815501 139.406609)
		(width 0.16)
		(layer "F.Cu")
		(net 124)
	)
	(segment
		(start 85.940501 134.55155)
		(end 86.148014 134.344037)
		(width 0.16)
		(layer "F.Cu")
		(net 124)
	)
	(segment
		(start 94.205501 137.881609)
		(end 94.205501 137.80119)
		(width 0.16)
		(layer "F.Cu")
		(net 124)
	)
	(segment
		(start 86.181987 135.303036)
		(end 85.940501 135.06155)
		(width 0.16)
		(layer "F.Cu")
		(net 124)
	)
	(segment
		(start 94.300501 151.286)
		(end 94.300501 150.836)
		(width 0.16)
		(layer "F.Cu")
		(net 124)
	)
	(segment
		(start 85.940501 135.06155)
		(end 85.940501 134.55155)
		(width 0.16)
		(layer "F.Cu")
		(net 124)
	)
	(segment
		(start 92.550501 139.141609)
		(end 92.550501 138.931609)
		(width 0.16)
		(layer "F.Cu")
		(net 124)
	)
	(segment
		(start 89.725372 135.303037)
		(end 89.319948 135.303036)
		(width 0.16)
		(layer "F.Cu")
		(net 124)
	)
	(segment
		(start 90.170372 135.027288)
		(end 90.170372 135.058037)
		(width 0.16)
		(layer "F.Cu")
		(net 124)
	)
	(segment
		(start 91.725372 135.303036)
		(end 91.725372 135.303037)
		(width 0.16)
		(layer "F.Cu")
		(net 124)
	)
	(segment
		(start 92.815501 138.666609)
		(end 93.630501 138.666609)
		(width 0.16)
		(layer "F.Cu")
		(net 124)
	)
	(segment
		(start 89.925372 135.303037)
		(end 89.725372 135.303037)
		(width 0.16)
		(layer "F.Cu")
		(net 124)
	)
	(segment
		(start 94.205501 138.091609)
		(end 94.205501 137.881609)
		(width 0.16)
		(layer "F.Cu")
		(net 124)
	)
	(arc
		(start 91.480372 135.027288)
		(mid 91.317816 134.634844)
		(end 90.925372 134.472288)
		(width 0.16)
		(layer "F.Cu")
		(net 124)
	)
	(arc
		(start 94.205501 139.981609)
		(mid 94.037087 139.575023)
		(end 93.630501 139.406609)
		(width 0.16)
		(layer "F.Cu")
		(net 124)
	)
	(arc
		(start 90.725372 134.472288)
		(mid 90.332928 134.634844)
		(end 90.170372 135.027288)
		(width 0.16)
		(layer "F.Cu")
		(net 124)
	)
	(arc
		(start 91.725372 135.303037)
		(mid 91.552131 135.231278)
		(end 91.480372 135.058037)
		(width 0.16)
		(layer "F.Cu")
		(net 124)
	)
	(arc
		(start 90.170372 135.058037)
		(mid 90.098613 135.231278)
		(end 89.925372 135.303037)
		(width 0.16)
		(layer "F.Cu")
		(net 124)
	)
	(arc
		(start 93.630501 138.666609)
		(mid 94.037087 138.498195)
		(end 94.205501 138.091609)
		(width 0.16)
		(layer "F.Cu")
		(net 124)
	)
	(arc
		(start 92.815501 139.406609)
		(mid 92.628118 139.328992)
		(end 92.550501 139.141609)
		(width 0.16)
		(layer "F.Cu")
		(net 124)
	)
	(arc
		(start 92.550501 138.931609)
		(mid 92.628118 138.744226)
		(end 92.815501 138.666609)
		(width 0.16)
		(layer "F.Cu")
		(net 124)
	)
	(segment
		(start 86.191987 132.757486)
		(end 92.951191 132.757486)
		(width 0.16)
		(layer "F.Cu")
		(net 125)
	)
	(segment
		(start 85.950501 132.516)
		(end 86.191987 132.757486)
		(width 0.16)
		(layer "F.Cu")
		(net 125)
	)
	(segment
		(start 85.950501 132.006)
		(end 85.950501 132.516)
		(width 0.16)
		(layer "F.Cu")
		(net 125)
	)
	(segment
		(start 95.705501 150.741)
		(end 95.800501 150.836)
		(width 0.16)
		(layer "F.Cu")
		(net 125)
	)
	(segment
		(start 86.158014 131.798487)
		(end 85.950501 132.006)
		(width 0.16)
		(layer "F.Cu")
		(net 125)
	)
	(segment
		(start 86.9905 131.798487)
		(end 86.158014 131.798487)
		(width 0.16)
		(layer "F.Cu")
		(net 125)
	)
	(segment
		(start 95.800501 150.836)
		(end 95.800501 151.286)
		(width 0.16)
		(layer "F.Cu")
		(net 125)
	)
	(segment
		(start 95.705501 135.511796)
		(end 95.705501 150.741)
		(width 0.16)
		(layer "F.Cu")
		(net 125)
	)
	(segment
		(start 92.951191 132.757486)
		(end 95.705501 135.511796)
		(width 0.16)
		(layer "F.Cu")
		(net 125)
	)
	(segment
		(start 91.801501 151.286)
		(end 91.801501 150.836)
		(width 0.16)
		(layer "F.Cu")
		(net 126)
	)
	(segment
		(start 90.156501 145.287947)
		(end 90.156501 146.343499)
		(width 0.16)
		(layer "F.Cu")
		(net 126)
	)
	(segment
		(start 90.711501 146.898499)
		(end 90.861658 146.898499)
		(width 0.16)
		(layer "F.Cu")
		(net 126)
	)
	(segment
		(start 91.706501 145.087297)
		(end 89.864204 143.245)
		(width 0.16)
		(layer "F.Cu")
		(net 126)
	)
	(segment
		(start 90.861658 146.898499)
		(end 91.101501 146.898499)
		(width 0.16)
		(layer "F.Cu")
		(net 126)
	)
	(segment
		(start 85.846501 146.898499)
		(end 89.111501 146.898499)
		(width 0.16)
		(layer "F.Cu")
		(net 126)
	)
	(segment
		(start 89.864204 143.245)
		(end 86.488204 143.245)
		(width 0.16)
		(layer "F.Cu")
		(net 126)
	)
	(segment
		(start 91.801501 150.836)
		(end 91.706501 150.741)
		(width 0.16)
		(layer "F.Cu")
		(net 126)
	)
	(segment
		(start 91.706501 146.293499)
		(end 91.706501 145.087297)
		(width 0.16)
		(layer "F.Cu")
		(net 126)
	)
	(segment
		(start 86.3 142.647987)
		(end 86.9905 141.957487)
		(width 0.16)
		(layer "F.Cu")
		(net 126)
	)
	(segment
		(start 86.488204 143.245)
		(end 86.3 143.056796)
		(width 0.16)
		(layer "F.Cu")
		(net 126)
	)
	(segment
		(start 86.3 143.056796)
		(end 86.3 142.647987)
		(width 0.16)
		(layer "F.Cu")
		(net 126)
	)
	(segment
		(start 89.666501 146.343499)
		(end 89.666501 145.287947)
		(width 0.16)
		(layer "F.Cu")
		(net 126)
	)
	(segment
		(start 91.706501 150.741)
		(end 91.706501 148.093499)
		(width 0.16)
		(layer "F.Cu")
		(net 126)
	)
	(segment
		(start 91.101501 147.488499)
		(end 85.846501 147.488499)
		(width 0.16)
		(layer "F.Cu")
		(net 126)
	)
	(arc
		(start 91.101501 146.898499)
		(mid 91.529301 146.721299)
		(end 91.706501 146.293499)
		(width 0.16)
		(layer "F.Cu")
		(net 126)
	)
	(arc
		(start 85.551501 147.193499)
		(mid 85.637904 146.984902)
		(end 85.846501 146.898499)
		(width 0.16)
		(layer "F.Cu")
		(net 126)
	)
	(arc
		(start 89.111501 146.898499)
		(mid 89.503945 146.735943)
		(end 89.666501 146.343499)
		(width 0.16)
		(layer "F.Cu")
		(net 126)
	)
	(arc
		(start 85.846501 147.488499)
		(mid 85.637904 147.402096)
		(end 85.551501 147.193499)
		(width 0.16)
		(layer "F.Cu")
		(net 126)
	)
	(arc
		(start 89.911501 145.042947)
		(mid 90.084742 145.114706)
		(end 90.156501 145.287947)
		(width 0.16)
		(layer "F.Cu")
		(net 126)
	)
	(arc
		(start 90.156501 146.343499)
		(mid 90.319057 146.735943)
		(end 90.711501 146.898499)
		(width 0.16)
		(layer "F.Cu")
		(net 126)
	)
	(arc
		(start 89.666501 145.287947)
		(mid 89.73826 145.114706)
		(end 89.911501 145.042947)
		(width 0.16)
		(layer "F.Cu")
		(net 126)
	)
	(arc
		(start 91.706501 148.093499)
		(mid 91.529301 147.665699)
		(end 91.101501 147.488499)
		(width 0.16)
		(layer "F.Cu")
		(net 126)
	)
	(segment
		(start 92.815501 138.356609)
		(end 93.630501 138.356609)
		(width 0.16)
		(layer "F.Cu")
		(net 127)
	)
	(segment
		(start 93.895501 137.881609)
		(end 93.895501 137.80119)
		(width 0.16)
		(layer "F.Cu")
		(net 127)
	)
	(segment
		(start 87.809836 135.753037)
		(end 87.809836 135.780915)
		(width 0.16)
		(layer "F.Cu")
		(net 127)
	)
	(segment
		(start 90.480372 135.027288)
		(end 90.480372 135.058037)
		(width 0.16)
		(layer "F.Cu")
		(net 127)
	)
	(segment
		(start 93.800501 151.286)
		(end 93.800501 150.836)
		(width 0.16)
		(layer "F.Cu")
		(net 127)
	)
	(segment
		(start 84.4415 135.613037)
		(end 87.669836 135.613037)
		(width 0.16)
		(layer "F.Cu")
		(net 127)
	)
	(segment
		(start 90.925372 134.782288)
		(end 90.725372 134.782288)
		(width 0.16)
		(layer "F.Cu")
		(net 127)
	)
	(segment
		(start 89.925372 135.613037)
		(end 89.725372 135.613037)
		(width 0.16)
		(layer "F.Cu")
		(net 127)
	)
	(segment
		(start 89.069836 135.613037)
		(end 89.08 135.613037)
		(width 0.16)
		(layer "F.Cu")
		(net 127)
	)
	(segment
		(start 89.319948 135.613037)
		(end 89.08 135.613037)
		(width 0.16)
		(layer "F.Cu")
		(net 127)
	)
	(segment
		(start 88.299836 135.613037)
		(end 88.369836 135.613037)
		(width 0.16)
		(layer "F.Cu")
		(net 127)
	)
	(segment
		(start 87.949836 135.920915)
		(end 88.019836 135.920915)
		(width 0.16)
		(layer "F.Cu")
		(net 127)
	)
	(segment
		(start 88.159836 135.780915)
		(end 88.159836 135.753037)
		(width 0.16)
		(layer "F.Cu")
		(net 127)
	)
	(segment
		(start 88.649836 135.920946)
		(end 88.719836 135.920946)
		(width 0.16)
		(layer "F.Cu")
		(net 127)
	)
	(segment
		(start 93.800501 150.836)
		(end 93.895501 150.741)
		(width 0.16)
		(layer "F.Cu")
		(net 127)
	)
	(segment
		(start 88.999836 135.613037)
		(end 89.069836 135.613037)
		(width 0.16)
		(layer "F.Cu")
		(net 127)
	)
	(segment
		(start 88.859836 135.780946)
		(end 88.859836 135.753037)
		(width 0.16)
		(layer "F.Cu")
		(net 127)
	)
	(segment
		(start 93.895501 137.80119)
		(end 93.895501 137.390204)
		(width 0.16)
		(layer "F.Cu")
		(net 127)
	)
	(segment
		(start 93.895501 138.091609)
		(end 93.895501 137.881609)
		(width 0.16)
		(layer "F.Cu")
		(net 127)
	)
	(segment
		(start 91.170372 135.058037)
		(end 91.170372 135.027288)
		(width 0.16)
		(layer "F.Cu")
		(net 127)
	)
	(segment
		(start 93.895501 137.390204)
		(end 92.118334 135.613037)
		(width 0.16)
		(layer "F.Cu")
		(net 127)
	)
	(segment
		(start 89.725372 135.613037)
		(end 89.319948 135.613037)
		(width 0.16)
		(layer "F.Cu")
		(net 127)
	)
	(segment
		(start 93.895501 150.741)
		(end 93.895501 139.981609)
		(width 0.16)
		(layer "F.Cu")
		(net 127)
	)
	(segment
		(start 92.118334 135.613037)
		(end 91.725372 135.613037)
		(width 0.16)
		(layer "F.Cu")
		(net 127)
	)
	(segment
		(start 93.630501 139.716609)
		(end 92.815501 139.716609)
		(width 0.16)
		(layer "F.Cu")
		(net 127)
	)
	(segment
		(start 92.240501 139.141609)
		(end 92.240501 138.931609)
		(width 0.16)
		(layer "F.Cu")
		(net 127)
	)
	(segment
		(start 88.509836 135.753037)
		(end 88.509836 135.780946)
		(width 0.16)
		(layer "F.Cu")
		(net 127)
	)
	(arc
		(start 91.725372 135.613037)
		(mid 91.332928 135.450481)
		(end 91.170372 135.058037)
		(width 0.16)
		(layer "F.Cu")
		(net 127)
	)
	(arc
		(start 87.669836 135.613037)
		(mid 87.768831 135.654042)
		(end 87.809836 135.753037)
		(width 0.16)
		(layer "F.Cu")
		(net 127)
	)
	(arc
		(start 88.159836 135.753037)
		(mid 88.200841 135.654042)
		(end 88.299836 135.613037)
		(width 0.16)
		(layer "F.Cu")
		(net 127)
	)
	(arc
		(start 93.630501 138.356609)
		(mid 93.817884 138.278992)
		(end 93.895501 138.091609)
		(width 0.16)
		(layer "F.Cu")
		(net 127)
	)
	(arc
		(start 90.725372 134.782288)
		(mid 90.552131 134.854047)
		(end 90.480372 135.027288)
		(width 0.16)
		(layer "F.Cu")
		(net 127)
	)
	(arc
		(start 90.480372 135.058037)
		(mid 90.317816 135.450481)
		(end 89.925372 135.613037)
		(width 0.16)
		(layer "F.Cu")
		(net 127)
	)
	(arc
		(start 92.815501 139.716609)
		(mid 92.408915 139.548195)
		(end 92.240501 139.141609)
		(width 0.16)
		(layer "F.Cu")
		(net 127)
	)
	(arc
		(start 88.859836 135.753037)
		(mid 88.900841 135.654042)
		(end 88.999836 135.613037)
		(width 0.16)
		(layer "F.Cu")
		(net 127)
	)
	(arc
		(start 93.895501 139.981609)
		(mid 93.817884 139.794226)
		(end 93.630501 139.716609)
		(width 0.16)
		(layer "F.Cu")
		(net 127)
	)
	(arc
		(start 91.170372 135.027288)
		(mid 91.098613 134.854047)
		(end 90.925372 134.782288)
		(width 0.16)
		(layer "F.Cu")
		(net 127)
	)
	(arc
		(start 87.809836 135.780915)
		(mid 87.850841 135.87991)
		(end 87.949836 135.920915)
		(width 0.16)
		(layer "F.Cu")
		(net 127)
	)
	(arc
		(start 88.019836 135.920915)
		(mid 88.118831 135.87991)
		(end 88.159836 135.780915)
		(width 0.16)
		(layer "F.Cu")
		(net 127)
	)
	(arc
		(start 92.240501 138.931609)
		(mid 92.408915 138.525023)
		(end 92.815501 138.356609)
		(width 0.16)
		(layer "F.Cu")
		(net 127)
	)
	(arc
		(start 88.719836 135.920946)
		(mid 88.818831 135.879941)
		(end 88.859836 135.780946)
		(width 0.16)
		(layer "F.Cu")
		(net 127)
	)
	(arc
		(start 88.509836 135.780946)
		(mid 88.550841 135.879941)
		(end 88.649836 135.920946)
		(width 0.16)
		(layer "F.Cu")
		(net 127)
	)
	(arc
		(start 88.369836 135.613037)
		(mid 88.468831 135.654042)
		(end 88.509836 135.753037)
		(width 0.16)
		(layer "F.Cu")
		(net 127)
	)
	(segment
		(start 92.822784 133.067487)
		(end 95.395501 135.640204)
		(width 0.16)
		(layer "F.Cu")
		(net 128)
	)
	(segment
		(start 95.395501 135.640204)
		(end 95.395501 150.741)
		(width 0.16)
		(layer "F.Cu")
		(net 128)
	)
	(segment
		(start 88.651988 133.233881)
		(end 88.651988 133.217487)
		(width 0.16)
		(layer "F.Cu")
		(net 128)
	)
	(segment
		(start 88.051988 133.233881)
		(end 88.051988 133.217487)
		(width 0.16)
		(layer "F.Cu")
		(net 128)
	)
	(segment
		(start 88.801988 133.067487)
		(end 90.051988 133.067487)
		(width 0.16)
		(layer "F.Cu")
		(net 128)
	)
	(segment
		(start 90.051988 133.067487)
		(end 92.822784 133.067487)
		(width 0.16)
		(layer "F.Cu")
		(net 128)
	)
	(segment
		(start 95.300501 150.836)
		(end 95.300501 151.286)
		(width 0.16)
		(layer "F.Cu")
		(net 128)
	)
	(segment
		(start 84.4515 133.067487)
		(end 87.601988 133.067487)
		(width 0.16)
		(layer "F.Cu")
		(net 128)
	)
	(segment
		(start 88.351988 133.217487)
		(end 88.351988 133.233881)
		(width 0.16)
		(layer "F.Cu")
		(net 128)
	)
	(segment
		(start 87.751988 133.217487)
		(end 87.751988 133.233881)
		(width 0.16)
		(layer "F.Cu")
		(net 128)
	)
	(segment
		(start 95.395501 150.741)
		(end 95.300501 150.836)
		(width 0.16)
		(layer "F.Cu")
		(net 128)
	)
	(arc
		(start 88.651988 133.217487)
		(mid 88.695922 133.111421)
		(end 88.801988 133.067487)
		(width 0.16)
		(layer "F.Cu")
		(net 128)
	)
	(arc
		(start 88.201988 133.067487)
		(mid 88.308054 133.111421)
		(end 88.351988 133.217487)
		(width 0.16)
		(layer "F.Cu")
		(net 128)
	)
	(arc
		(start 88.051988 133.217487)
		(mid 88.095922 133.111421)
		(end 88.201988 133.067487)
		(width 0.16)
		(layer "F.Cu")
		(net 128)
	)
	(arc
		(start 87.901988 133.383881)
		(mid 88.008054 133.339947)
		(end 88.051988 133.233881)
		(width 0.16)
		(layer "F.Cu")
		(net 128)
	)
	(arc
		(start 87.601988 133.067487)
		(mid 87.708054 133.111421)
		(end 87.751988 133.217487)
		(width 0.16)
		(layer "F.Cu")
		(net 128)
	)
	(arc
		(start 88.501988 133.383881)
		(mid 88.608054 133.339947)
		(end 88.651988 133.233881)
		(width 0.16)
		(layer "F.Cu")
		(net 128)
	)
	(arc
		(start 87.751988 133.233881)
		(mid 87.795922 133.339947)
		(end 87.901988 133.383881)
		(width 0.16)
		(layer "F.Cu")
		(net 128)
	)
	(arc
		(start 88.351988 133.233881)
		(mid 88.395922 133.339947)
		(end 88.501988 133.383881)
		(width 0.16)
		(layer "F.Cu")
		(net 128)
	)
	(segment
		(start 92.897501 141.716705)
		(end 92.897501 142.102499)
		(width 0.16)
		(layer "F.Cu")
		(net 129)
	)
	(segment
		(start 88.208014 140.688487)
		(end 88.863784 140.688487)
		(width 0.16)
		(layer "F.Cu")
		(net 129)
	)
	(segment
		(start 92.627501 142.372499)
		(end 91.374138 142.372499)
		(width 0.16)
		(layer "F.Cu")
		(net 129)
	)
	(segment
		(start 91.869283 140.688487)
		(end 92.897501 141.716705)
		(width 0.16)
		(layer "F.Cu")
		(net 129)
	)
	(segment
		(start 87.818014 140.818487)
		(end 87.818014 140.849878)
		(width 0.16)
		(layer "F.Cu")
		(net 129)
	)
	(segment
		(start 91.421514 140.688486)
		(end 91.869283 140.688487)
		(width 0.16)
		(layer "F.Cu")
		(net 129)
	)
	(segment
		(start 88.078014 140.849878)
		(end 88.078014 140.818487)
		(width 0.16)
		(layer "F.Cu")
		(net 129)
	)
	(segment
		(start 90.816514 137.678486)
		(end 90.816514 140.083486)
		(width 0.16)
		(layer "F.Cu")
		(net 129)
	)
	(segment
		(start 92.897501 143.802499)
		(end 92.897501 144.187456)
		(width 0.16)
		(layer "F.Cu")
		(net 129)
	)
	(segment
		(start 90.226514 140.083486)
		(end 90.226514 137.678486)
		(width 0.16)
		(layer "F.Cu")
		(net 129)
	)
	(segment
		(start 85.952988 140.688487)
		(end 87.688014 140.688487)
		(width 0.16)
		(layer "F.Cu")
		(net 129)
	)
	(segment
		(start 91.374138 143.532499)
		(end 92.627501 143.532499)
		(width 0.16)
		(layer "F.Cu")
		(net 129)
	)
	(segment
		(start 92.897501 144.187456)
		(end 92.897501 150.741)
		(width 0.16)
		(layer "F.Cu")
		(net 129)
	)
	(segment
		(start 85.942988 140.688487)
		(end 85.952988 140.688487)
		(width 0.16)
		(layer "F.Cu")
		(net 129)
	)
	(segment
		(start 92.802501 150.836)
		(end 92.802501 151.286)
		(width 0.16)
		(layer "F.Cu")
		(net 129)
	)
	(segment
		(start 88.863784 140.688487)
		(end 89.621514 140.688486)
		(width 0.16)
		(layer "F.Cu")
		(net 129)
	)
	(segment
		(start 85.682988 140.938487)
		(end 85.692988 140.938487)
		(width 0.16)
		(layer "F.Cu")
		(net 129)
	)
	(segment
		(start 92.897501 150.741)
		(end 92.802501 150.836)
		(width 0.16)
		(layer "F.Cu")
		(net 129)
	)
	(segment
		(start 84.4515 140.688487)
		(end 85.432988 140.688487)
		(width 0.16)
		(layer "F.Cu")
		(net 129)
	)
	(arc
		(start 85.817988 140.813487)
		(mid 85.8546 140.725099)
		(end 85.942988 140.688487)
		(width 0.16)
		(layer "F.Cu")
		(net 129)
	)
	(arc
		(start 90.226514 137.678486)
		(mid 90.312917 137.469889)
		(end 90.521514 137.383486)
		(width 0.16)
		(layer "F.Cu")
		(net 129)
	)
	(arc
		(start 90.521514 137.383486)
		(mid 90.730111 137.469889)
		(end 90.816514 137.678486)
		(width 0.16)
		(layer "F.Cu")
		(net 129)
	)
	(arc
		(start 90.816514 140.083486)
		(mid 90.993714 140.511286)
		(end 91.421514 140.688486)
		(width 0.16)
		(layer "F.Cu")
		(net 129)
	)
	(arc
		(start 87.688014 140.688487)
		(mid 87.779938 140.726563)
		(end 87.818014 140.818487)
		(width 0.16)
		(layer "F.Cu")
		(net 129)
	)
	(arc
		(start 91.374138 142.372499)
		(mid 90.964016 142.542377)
		(end 90.794138 142.952499)
		(width 0.16)
		(layer "F.Cu")
		(net 129)
	)
	(arc
		(start 90.794138 142.952499)
		(mid 90.964016 143.362621)
		(end 91.374138 143.532499)
		(width 0.16)
		(layer "F.Cu")
		(net 129)
	)
	(arc
		(start 89.621514 140.688486)
		(mid 90.049314 140.511286)
		(end 90.226514 140.083486)
		(width 0.16)
		(layer "F.Cu")
		(net 129)
	)
	(arc
		(start 88.078014 140.818487)
		(mid 88.11609 140.726563)
		(end 88.208014 140.688487)
		(width 0.16)
		(layer "F.Cu")
		(net 129)
	)
	(arc
		(start 85.692988 140.938487)
		(mid 85.781376 140.901875)
		(end 85.817988 140.813487)
		(width 0.16)
		(layer "F.Cu")
		(net 129)
	)
	(arc
		(start 92.897501 142.102499)
		(mid 92.81842 142.293418)
		(end 92.627501 142.372499)
		(width 0.16)
		(layer "F.Cu")
		(net 129)
	)
	(arc
		(start 85.557988 140.813487)
		(mid 85.5946 140.901875)
		(end 85.682988 140.938487)
		(width 0.16)
		(layer "F.Cu")
		(net 129)
	)
	(arc
		(start 87.948014 140.979878)
		(mid 88.039938 140.941802)
		(end 88.078014 140.849878)
		(width 0.16)
		(layer "F.Cu")
		(net 129)
	)
	(arc
		(start 92.627501 143.532499)
		(mid 92.81842 143.61158)
		(end 92.897501 143.802499)
		(width 0.16)
		(layer "F.Cu")
		(net 129)
	)
	(arc
		(start 87.818014 140.849878)
		(mid 87.85609 140.941802)
		(end 87.948014 140.979878)
		(width 0.16)
		(layer "F.Cu")
		(net 129)
	)
	(arc
		(start 85.432988 140.688487)
		(mid 85.521376 140.725099)
		(end 85.557988 140.813487)
		(width 0.16)
		(layer "F.Cu")
		(net 129)
	)
	(segment
		(start 91.396501 150.741)
		(end 91.396501 148.093499)
		(width 0.16)
		(layer "F.Cu")
		(net 130)
	)
	(segment
		(start 90.711501 146.588499)
		(end 90.861658 146.588499)
		(width 0.16)
		(layer "F.Cu")
		(net 130)
	)
	(segment
		(start 91.396501 145.215705)
		(end 89.735796 143.555)
		(width 0.16)
		(layer "F.Cu")
		(net 130)
	)
	(segment
		(start 86.355 143.555)
		(end 86.027487 143.227487)
		(width 0.16)
		(layer "F.Cu")
		(net 130)
	)
	(segment
		(start 86.027487 143.227487)
		(end 84.4515 143.227487)
		(width 0.16)
		(layer "F.Cu")
		(net 130)
	)
	(segment
		(start 91.301501 151.286)
		(end 91.301501 150.836)
		(width 0.16)
		(layer "F.Cu")
		(net 130)
	)
	(segment
		(start 91.101501 147.798499)
		(end 85.846501 147.798499)
		(width 0.16)
		(layer "F.Cu")
		(net 130)
	)
	(segment
		(start 90.466501 145.287947)
		(end 90.466501 146.343499)
		(width 0.16)
		(layer "F.Cu")
		(net 130)
	)
	(segment
		(start 85.846501 146.588499)
		(end 89.111501 146.588499)
		(width 0.16)
		(layer "F.Cu")
		(net 130)
	)
	(segment
		(start 90.861658 146.588499)
		(end 91.101501 146.588499)
		(width 0.16)
		(layer "F.Cu")
		(net 130)
	)
	(segment
		(start 91.301501 150.836)
		(end 91.396501 150.741)
		(width 0.16)
		(layer "F.Cu")
		(net 130)
	)
	(segment
		(start 89.735796 143.555)
		(end 86.355 143.555)
		(width 0.16)
		(layer "F.Cu")
		(net 130)
	)
	(segment
		(start 89.356501 146.343499)
		(end 89.356501 145.287947)
		(width 0.16)
		(layer "F.Cu")
		(net 130)
	)
	(segment
		(start 91.396501 146.293499)
		(end 91.396501 145.215705)
		(width 0.16)
		(layer "F.Cu")
		(net 130)
	)
	(arc
		(start 91.396501 148.093499)
		(mid 91.310098 147.884902)
		(end 91.101501 147.798499)
		(width 0.16)
		(layer "F.Cu")
		(net 130)
	)
	(arc
		(start 90.466501 146.343499)
		(mid 90.53826 146.51674)
		(end 90.711501 146.588499)
		(width 0.16)
		(layer "F.Cu")
		(net 130)
	)
	(arc
		(start 89.356501 145.287947)
		(mid 89.519057 144.895503)
		(end 89.911501 144.732947)
		(width 0.16)
		(layer "F.Cu")
		(net 130)
	)
	(arc
		(start 91.101501 146.588499)
		(mid 91.310098 146.502096)
		(end 91.396501 146.293499)
		(width 0.16)
		(layer "F.Cu")
		(net 130)
	)
	(arc
		(start 85.241501 147.193499)
		(mid 85.418701 146.765699)
		(end 85.846501 146.588499)
		(width 0.16)
		(layer "F.Cu")
		(net 130)
	)
	(arc
		(start 85.846501 147.798499)
		(mid 85.418701 147.621299)
		(end 85.241501 147.193499)
		(width 0.16)
		(layer "F.Cu")
		(net 130)
	)
	(arc
		(start 89.111501 146.588499)
		(mid 89.284742 146.51674)
		(end 89.356501 146.343499)
		(width 0.16)
		(layer "F.Cu")
		(net 130)
	)
	(arc
		(start 89.911501 144.732947)
		(mid 90.303945 144.895503)
		(end 90.466501 145.287947)
		(width 0.16)
		(layer "F.Cu")
		(net 130)
	)
	(segment
		(start 182.140107 186.375)
		(end 182.140107 187.162107)
		(width 0.2)
		(layer "F.Cu")
		(net 131)
	)
	(segment
		(start 199.696 191.324)
		(end 199.273 191.324)
		(width 0.1)
		(layer "F.Cu")
		(net 131)
	)
	(segment
		(start 182.140107 187.162107)
		(end 182.179107 187.201107)
		(width 0.2)
		(layer "F.Cu")
		(net 131)
	)
	(via
		(at 182.179107 187.201107)
		(size 0.45)
		(drill 0.1)
		(layers "F.Cu" "B.Cu")
		(net 131)
	)
	(via
		(at 199.273 191.324)
		(size 0.45)
		(drill 0.1)
		(layers "F.Cu" "B.Cu")
		(net 131)
	)
	(segment
		(start 181.987356 187.392858)
		(end 181.987356 189.645934)
		(width 0.1)
		(layer "In4.Cu")
		(net 131)
	)
	(segment
		(start 181.987356 189.645934)
		(end 183.941422 191.6)
		(width 0.1)
		(layer "In4.Cu")
		(net 131)
	)
	(segment
		(start 197.658578 190.3)
		(end 198.641422 190.3)
		(width 0.1)
		(layer "In4.Cu")
		(net 131)
	)
	(segment
		(start 198.641422 190.3)
		(end 199.098 190.756578)
		(width 0.1)
		(layer "In4.Cu")
		(net 131)
	)
	(segment
		(start 182.179107 187.201107)
		(end 181.987356 187.392858)
		(width 0.1)
		(layer "In4.Cu")
		(net 131)
	)
	(segment
		(start 199.098 191.149)
		(end 199.273 191.324)
		(width 0.1)
		(layer "In4.Cu")
		(net 131)
	)
	(segment
		(start 196.358578 191.6)
		(end 197.658578 190.3)
		(width 0.1)
		(layer "In4.Cu")
		(net 131)
	)
	(segment
		(start 199.098 190.756578)
		(end 199.098 191.149)
		(width 0.1)
		(layer "In4.Cu")
		(net 131)
	)
	(segment
		(start 183.941422 191.6)
		(end 196.358578 191.6)
		(width 0.1)
		(layer "In4.Cu")
		(net 131)
	)
	(segment
		(start 94.800501 151.358851)
		(end 94.800501 150.458851)
		(width 0.15)
		(layer "F.Cu")
		(net 132)
	)
	(segment
		(start 92.300501 151.358851)
		(end 92.300501 150.458851)
		(width 0.15)
		(layer "F.Cu")
		(net 132)
	)
	(via
		(at 94.800501 150.458851)
		(size 0.45)
		(drill 0.1)
		(layers "F.Cu" "B.Cu")
		(net 132)
	)
	(via
		(at 92.300501 150.458851)
		(size 0.45)
		(drill 0.1)
		(layers "F.Cu" "B.Cu")
		(net 132)
	)
	(segment
		(start 94.1 151.55)
		(end 95.3 151.55)
		(width 0.256)
		(layer "B.Cu")
		(net 132)
	)
	(segment
		(start 93.036829 150.767157)
		(end 93.036829 151.513171)
		(width 0.256)
		(layer "B.Cu")
		(net 132)
	)
	(segment
		(start 93.974829 152.558157)
		(end 94.05 152.482986)
		(width 0.256)
		(layer "B.Cu")
		(net 132)
	)
	(segment
		(start 95.6 151.25)
		(end 95.6 150.784)
		(width 0.256)
		(layer "B.Cu")
		(net 132)
	)
	(segment
		(start 91.5 150.767157)
		(end 91.5 151.25)
		(width 0.256)
		(layer "B.Cu")
		(net 132)
	)
	(segment
		(start 94.05 151.55)
		(end 93.9 151.55)
		(width 0.256)
		(layer "B.Cu")
		(net 132)
	)
	(segment
		(start 93.9 151.55)
		(end 94.1 151.55)
		(width 0.256)
		(layer "B.Cu")
		(net 132)
	)
	(segment
		(start 94.05 152.482986)
		(end 94.05 151.55)
		(width 0.256)
		(layer "B.Cu")
		(net 132)
	)
	(segment
		(start 93.021829 150.768157)
		(end 92.712523 150.458851)
		(width 0.2)
		(layer "B.Cu")
		(net 132)
	)
	(segment
		(start 93.036829 151.513171)
		(end 93 151.55)
		(width 0.256)
		(layer "B.Cu")
		(net 132)
	)
	(segment
		(start 92.712523 150.458851)
		(end 92.300501 150.458851)
		(width 0.2)
		(layer "B.Cu")
		(net 132)
	)
	(segment
		(start 94.061829 151.511829)
		(end 94.1 151.55)
		(width 0.256)
		(layer "B.Cu")
		(net 132)
	)
	(segment
		(start 94.371135 150.458851)
		(end 94.061829 150.768157)
		(width 0.2)
		(layer "B.Cu")
		(net 132)
	)
	(segment
		(start 93 151.55)
		(end 93.9 151.55)
		(width 0.256)
		(layer "B.Cu")
		(net 132)
	)
	(segment
		(start 91.5 151.25)
		(end 91.8 151.55)
		(width 0.256)
		(layer "B.Cu")
		(net 132)
	)
	(segment
		(start 94.061829 150.767157)
		(end 94.061829 151.511829)
		(width 0.256)
		(layer "B.Cu")
		(net 132)
	)
	(segment
		(start 94.800501 150.458851)
		(end 94.371135 150.458851)
		(width 0.2)
		(layer "B.Cu")
		(net 132)
	)
	(segment
		(start 91.8 151.55)
		(end 93 151.55)
		(width 0.256)
		(layer "B.Cu")
		(net 132)
	)
	(segment
		(start 95.3 151.55)
		(end 95.6 151.25)
		(width 0.256)
		(layer "B.Cu")
		(net 132)
	)
	(segment
		(start 98.523352 154.036)
		(end 100.400501 155.913149)
		(width 0.2)
		(layer "F.Cu")
		(net 133)
	)
	(segment
		(start 96.97765 154.036)
		(end 98.523352 154.036)
		(width 0.2)
		(layer "F.Cu")
		(net 133)
	)
	(segment
		(start 101.500501 155.973851)
		(end 100.400501 155.973851)
		(width 0.2)
		(layer "F.Cu")
		(net 133)
	)
	(segment
		(start 102.600501 155.973851)
		(end 101.500501 155.973851)
		(width 0.2)
		(layer "F.Cu")
		(net 133)
	)
	(segment
		(start 103.800501 156.223149)
		(end 103.551203 155.973851)
		(width 0.2)
		(layer "F.Cu")
		(net 133)
	)
	(segment
		(start 103.551203 155.973851)
		(end 102.600501 155.973851)
		(width 0.2)
		(layer "F.Cu")
		(net 133)
	)
	(segment
		(start 96.300501 151.358851)
		(end 96.300501 150.458851)
		(width 0.15)
		(layer "F.Cu")
		(net 134)
	)
	(segment
		(start 90.800501 151.358851)
		(end 90.800501 150.458851)
		(width 0.15)
		(layer "F.Cu")
		(net 134)
	)
	(via
		(at 96.300501 150.458851)
		(size 0.45)
		(drill 0.1)
		(layers "F.Cu" "B.Cu")
		(net 134)
	)
	(via
		(at 90.800501 150.458851)
		(size 0.45)
		(drill 0.1)
		(layers "F.Cu" "B.Cu")
		(net 134)
	)
	(segment
		(start 96.300501 150.458851)
		(end 96.649807 150.808157)
		(width 0.2)
		(layer "B.Cu")
		(net 134)
	)
	(segment
		(start 96.649807 150.808157)
		(end 97.401829 150.808157)
		(width 0.2)
		(layer "B.Cu")
		(net 134)
	)
	(segment
		(start 89.086829 150.118157)
		(end 90.086829 150.118157)
		(width 0.2)
		(layer "B.Cu")
		(net 134)
	)
	(segment
		(start 90.800501 150.458851)
		(end 90.427523 150.458851)
		(width 0.2)
		(layer "B.Cu")
		(net 134)
	)
	(segment
		(start 97.500501 150.709485)
		(end 97.500501 149.558851)
		(width 0.2)
		(layer "B.Cu")
		(net 134)
	)
	(segment
		(start 91.366829 148.838157)
		(end 90.086829 150.118157)
		(width 0.2)
		(layer "B.Cu")
		(net 134)
	)
	(segment
		(start 97.500501 149.558851)
		(end 96.779807 148.838157)
		(width 0.2)
		(layer "B.Cu")
		(net 134)
	)
	(segment
		(start 97.401829 150.808157)
		(end 97.500501 150.709485)
		(width 0.2)
		(layer "B.Cu")
		(net 134)
	)
	(segment
		(start 96.779807 148.838157)
		(end 91.366829 148.838157)
		(width 0.2)
		(layer "B.Cu")
		(net 134)
	)
	(segment
		(start 90.427523 150.458851)
		(end 90.086829 150.118157)
		(width 0.2)
		(layer "B.Cu")
		(net 134)
	)
	(segment
		(start 144.375502 187.301)
		(end 144.875001 187.8005)
		(width 0.256)
		(layer "F.Cu")
		(net 135)
	)
	(via
		(at 144.875001 187.8005)
		(size 0.45)
		(drill 0.1)
		(layers "F.Cu" "B.Cu")
		(net 135)
	)
	(via
		(at 124.55 203.6)
		(size 0.45)
		(drill 0.1)
		(layers "F.Cu" "B.Cu")
		(net 135)
	)
	(segment
		(start 124.525 205.825)
		(end 124.525 203.625)
		(width 0.201)
		(layer "B.Cu")
		(net 135)
	)
	(segment
		(start 124.525501 210.801)
		(end 124.525501 205.825501)
		(width 0.201)
		(layer "B.Cu")
		(net 135)
	)
	(segment
		(start 124.55 202.885)
		(end 124.515 202.85)
		(width 0.256)
		(layer "B.Cu")
		(net 135)
	)
	(segment
		(start 124.55 203.6)
		(end 124.55 202.885)
		(width 0.256)
		(layer "B.Cu")
		(net 135)
	)
	(segment
		(start 124.525 203.625)
		(end 124.55 203.6)
		(width 0.201)
		(layer "B.Cu")
		(net 135)
	)
	(segment
		(start 124.525501 205.825501)
		(end 124.525 205.825)
		(width 0.201)
		(layer "B.Cu")
		(net 135)
	)
	(segment
		(start 124.515 201.825)
		(end 124.515 202.85)
		(width 0.256)
		(layer "B.Cu")
		(net 135)
	)
	(segment
		(start 144.875001 190.924999)
		(end 144.875001 187.8005)
		(width 0.1)
		(layer "In6.Cu")
		(net 135)
	)
	(segment
		(start 132.2 203.6)
		(end 144.875001 190.924999)
		(width 0.1)
		(layer "In6.Cu")
		(net 135)
	)
	(segment
		(start 124.55 203.6)
		(end 132.2 203.6)
		(width 0.1)
		(layer "In6.Cu")
		(net 135)
	)
	(segment
		(start 140.375501 165.301999)
		(end 140.875001 164.8025)
		(width 0.256)
		(layer "F.Cu")
		(net 136)
	)
	(segment
		(start 133.400001 146.2025)
		(end 133.400001 145.1275)
		(width 0.201)
		(layer "F.Cu")
		(net 136)
	)
	(via
		(at 140.875001 164.8025)
		(size 0.45)
		(drill 0.1)
		(layers "F.Cu" "B.Cu")
		(net 136)
	)
	(via
		(at 133.400001 145.1275)
		(size 0.45)
		(drill 0.1)
		(layers "F.Cu" "B.Cu")
		(net 136)
	)
	(segment
		(start 139.209425 160.222803)
		(end 139.209426 160.222802)
		(width 0.1)
		(layer "In4.Cu")
		(net 136)
	)
	(segment
		(start 140.299999 160.546447)
		(end 140.3 160.546446)
		(width 0.1)
		(layer "In4.Cu")
		(net 136)
	)
	(segment
		(start 132.190501 147.886)
		(end 132.390501 147.686)
		(width 0.1)
		(layer "In4.Cu")
		(net 136)
	)
	(segment
		(start 139.209426 160.222802)
		(end 139.6228 159.809423)
		(width 0.1)
		(layer "In4.Cu")
		(net 136)
	)
	(segment
		(start 137.795204 158.80858)
		(end 138.208578 158.395201)
		(width 0.1)
		(layer "In4.Cu")
		(net 136)
	)
	(segment
		(start 140.390501 160.990501)
		(end 140.3 160.9)
		(width 0.1)
		(layer "In4.Cu")
		(net 136)
	)
	(segment
		(start 140.329911 160.16298)
		(end 140.329911 160.162981)
		(width 0.1)
		(layer "In4.Cu")
		(net 136)
	)
	(segment
		(start 132.190501 152.790501)
		(end 132.190501 147.886)
		(width 0.1)
		(layer "In4.Cu")
		(net 136)
	)
	(segment
		(start 138.502314 159.515692)
		(end 138.502315 159.515691)
		(width 0.1)
		(layer "In4.Cu")
		(net 136)
	)
	(segment
		(start 136.410892 157.010891)
		(end 136.410893 157.010893)
		(width 0.1)
		(layer "In4.Cu")
		(net 136)
	)
	(segment
		(start 137.088093 158.101469)
		(end 137.501467 157.68809)
		(width 0.1)
		(layer "In4.Cu")
		(net 136)
	)
	(segment
		(start 139.622799 159.45587)
		(end 139.6228 159.45587)
		(width 0.1)
		(layer "In4.Cu")
		(net 136)
	)
	(segment
		(start 139.976357 160.162981)
		(end 139.562978 160.576355)
		(width 0.1)
		(layer "In4.Cu")
		(net 136)
	)
	(segment
		(start 139.209425 160.576354)
		(end 139.209426 160.576356)
		(width 0.1)
		(layer "In4.Cu")
		(net 136)
	)
	(segment
		(start 136.410893 157.010893)
		(end 132.190501 152.790501)
		(width 0.1)
		(layer "In4.Cu")
		(net 136)
	)
	(segment
		(start 136.380981 157.394359)
		(end 136.380982 157.394358)
		(width 0.1)
		(layer "In4.Cu")
		(net 136)
	)
	(segment
		(start 137.855025 158.041647)
		(end 137.855024 158.041648)
		(width 0.1)
		(layer "In4.Cu")
		(net 136)
	)
	(segment
		(start 140.390501 164.318)
		(end 140.390501 160.990501)
		(width 0.1)
		(layer "In4.Cu")
		(net 136)
	)
	(segment
		(start 136.380982 157.394358)
		(end 136.410892 157.364445)
		(width 0.1)
		(layer "In4.Cu")
		(net 136)
	)
	(segment
		(start 137.795203 158.808581)
		(end 137.795204 158.80858)
		(width 0.1)
		(layer "In4.Cu")
		(net 136)
	)
	(segment
		(start 139.269247 159.455869)
		(end 139.269246 159.45587)
		(width 0.1)
		(layer "In4.Cu")
		(net 136)
	)
	(segment
		(start 136.380981 157.74791)
		(end 136.380982 157.747912)
		(width 0.1)
		(layer "In4.Cu")
		(net 136)
	)
	(segment
		(start 139.269246 159.45587)
		(end 138.855867 159.869244)
		(width 0.1)
		(layer "In4.Cu")
		(net 136)
	)
	(segment
		(start 137.088092 158.455021)
		(end 137.088093 158.455023)
		(width 0.1)
		(layer "In4.Cu")
		(net 136)
	)
	(segment
		(start 138.915688 158.748759)
		(end 138.915689 158.748759)
		(width 0.1)
		(layer "In4.Cu")
		(net 136)
	)
	(segment
		(start 137.795203 159.162132)
		(end 137.795204 159.162134)
		(width 0.1)
		(layer "In4.Cu")
		(net 136)
	)
	(segment
		(start 137.147913 157.334537)
		(end 136.734534 157.747911)
		(width 0.1)
		(layer "In4.Cu")
		(net 136)
	)
	(segment
		(start 132.390501 147.686)
		(end 132.390501 146.137)
		(width 0.1)
		(layer "In4.Cu")
		(net 136)
	)
	(segment
		(start 138.502315 159.515691)
		(end 138.915689 159.102312)
		(width 0.1)
		(layer "In4.Cu")
		(net 136)
	)
	(segment
		(start 138.562136 158.748758)
		(end 138.562135 158.748759)
		(width 0.1)
		(layer "In4.Cu")
		(net 136)
	)
	(segment
		(start 140.875001 164.8025)
		(end 140.390501 164.318)
		(width 0.1)
		(layer "In4.Cu")
		(net 136)
	)
	(segment
		(start 140.3 160.546446)
		(end 140.329911 160.516534)
		(width 0.1)
		(layer "In4.Cu")
		(net 136)
	)
	(segment
		(start 138.502314 159.869243)
		(end 138.502315 159.869245)
		(width 0.1)
		(layer "In4.Cu")
		(net 136)
	)
	(segment
		(start 137.855024 158.041648)
		(end 137.441645 158.455022)
		(width 0.1)
		(layer "In4.Cu")
		(net 136)
	)
	(segment
		(start 137.088092 158.10147)
		(end 137.088093 158.101469)
		(width 0.1)
		(layer "In4.Cu")
		(net 136)
	)
	(segment
		(start 137.501466 157.334537)
		(end 137.501467 157.334537)
		(width 0.1)
		(layer "In4.Cu")
		(net 136)
	)
	(segment
		(start 138.208577 158.041648)
		(end 138.208578 158.041648)
		(width 0.1)
		(layer "In4.Cu")
		(net 136)
	)
	(segment
		(start 139.976358 160.16298)
		(end 139.976357 160.162981)
		(width 0.1)
		(layer "In4.Cu")
		(net 136)
	)
	(segment
		(start 132.390501 146.137)
		(end 133.400001 145.1275)
		(width 0.1)
		(layer "In4.Cu")
		(net 136)
	)
	(segment
		(start 138.562135 158.748759)
		(end 138.148756 159.162133)
		(width 0.1)
		(layer "In4.Cu")
		(net 136)
	)
	(segment
		(start 137.147914 157.334536)
		(end 137.147913 157.334537)
		(width 0.1)
		(layer "In4.Cu")
		(net 136)
	)
	(arc
		(start 138.502315 159.869245)
		(mid 138.429091 159.692469)
		(end 138.502314 159.515692)
		(width 0.1)
		(layer "In4.Cu")
		(net 136)
	)
	(arc
		(start 137.088093 158.455023)
		(mid 137.014869 158.278247)
		(end 137.088092 158.10147)
		(width 0.1)
		(layer "In4.Cu")
		(net 136)
	)
	(arc
		(start 139.6228 159.45587)
		(mid 139.446024 159.382646)
		(end 139.269247 159.455869)
		(width 0.1)
		(layer "In4.Cu")
		(net 136)
	)
	(arc
		(start 138.915689 159.102312)
		(mid 138.988912 158.925535)
		(end 138.915688 158.748759)
		(width 0.1)
		(layer "In4.Cu")
		(net 136)
	)
	(arc
		(start 138.208578 158.395201)
		(mid 138.281801 158.218424)
		(end 138.208577 158.041648)
		(width 0.1)
		(layer "In4.Cu")
		(net 136)
	)
	(arc
		(start 137.441645 158.455022)
		(mid 137.264868 158.528245)
		(end 137.088092 158.455021)
		(width 0.1)
		(layer "In4.Cu")
		(net 136)
	)
	(arc
		(start 138.208578 158.041648)
		(mid 138.031802 157.968424)
		(end 137.855025 158.041647)
		(width 0.1)
		(layer "In4.Cu")
		(net 136)
	)
	(arc
		(start 136.410892 157.364445)
		(mid 136.484115 157.187668)
		(end 136.410892 157.010891)
		(width 0.1)
		(layer "In4.Cu")
		(net 136)
	)
	(arc
		(start 137.501467 157.68809)
		(mid 137.57469 157.511313)
		(end 137.501466 157.334537)
		(width 0.1)
		(layer "In4.Cu")
		(net 136)
	)
	(arc
		(start 138.855867 159.869244)
		(mid 138.67909 159.942467)
		(end 138.502314 159.869243)
		(width 0.1)
		(layer "In4.Cu")
		(net 136)
	)
	(arc
		(start 136.734534 157.747911)
		(mid 136.557757 157.821134)
		(end 136.380981 157.74791)
		(width 0.1)
		(layer "In4.Cu")
		(net 136)
	)
	(arc
		(start 139.562978 160.576355)
		(mid 139.386201 160.649578)
		(end 139.209425 160.576354)
		(width 0.1)
		(layer "In4.Cu")
		(net 136)
	)
	(arc
		(start 140.3 160.9)
		(mid 140.226776 160.723224)
		(end 140.299999 160.546447)
		(width 0.1)
		(layer "In4.Cu")
		(net 136)
	)
	(arc
		(start 139.209426 160.576356)
		(mid 139.136202 160.39958)
		(end 139.209425 160.222803)
		(width 0.1)
		(layer "In4.Cu")
		(net 136)
	)
	(arc
		(start 140.329911 160.162981)
		(mid 140.153135 160.089757)
		(end 139.976358 160.16298)
		(width 0.1)
		(layer "In4.Cu")
		(net 136)
	)
	(arc
		(start 137.501467 157.334537)
		(mid 137.324691 157.261313)
		(end 137.147914 157.334536)
		(width 0.1)
		(layer "In4.Cu")
		(net 136)
	)
	(arc
		(start 140.329911 160.516534)
		(mid 140.403134 160.339757)
		(end 140.329911 160.16298)
		(width 0.1)
		(layer "In4.Cu")
		(net 136)
	)
	(arc
		(start 136.380982 157.747912)
		(mid 136.307758 157.571136)
		(end 136.380981 157.394359)
		(width 0.1)
		(layer "In4.Cu")
		(net 136)
	)
	(arc
		(start 138.148756 159.162133)
		(mid 137.971979 159.235356)
		(end 137.795203 159.162132)
		(width 0.1)
		(layer "In4.Cu")
		(net 136)
	)
	(arc
		(start 138.915689 158.748759)
		(mid 138.738913 158.675535)
		(end 138.562136 158.748758)
		(width 0.1)
		(layer "In4.Cu")
		(net 136)
	)
	(arc
		(start 137.795204 159.162134)
		(mid 137.72198 158.985358)
		(end 137.795203 158.808581)
		(width 0.1)
		(layer "In4.Cu")
		(net 136)
	)
	(arc
		(start 139.6228 159.809423)
		(mid 139.696023 159.632646)
		(end 139.622799 159.45587)
		(width 0.1)
		(layer "In4.Cu")
		(net 136)
	)
	(segment
		(start 107.400001 146.2025)
		(end 107.400001 145.1275)
		(width 0.201)
		(layer "F.Cu")
		(net 137)
	)
	(via
		(at 107.400001 145.1275)
		(size 0.45)
		(drill 0.1)
		(layers "F.Cu" "B.Cu")
		(net 137)
	)
	(segment
		(start 107.4 142.885)
		(end 107.400001 145.1275)
		(width 0.256)
		(layer "B.Cu")
		(net 137)
	)
	(segment
		(start 107.43 142.885)
		(end 108.4 141.915)
		(width 0.256)
		(layer "B.Cu")
		(net 137)
	)
	(segment
		(start 107.4 142.885)
		(end 107.43 142.885)
		(width 0.256)
		(layer "B.Cu")
		(net 137)
	)
	(segment
		(start 133.650001 138.8025)
		(end 133.650001 139.8775)
		(width 0.201)
		(layer "F.Cu")
		(net 138)
	)
	(segment
		(start 140.375501 166.302)
		(end 140.875001 165.8025)
		(width 0.256)
		(layer "F.Cu")
		(net 138)
	)
	(via
		(at 140.875001 165.8025)
		(size 0.45)
		(drill 0.1)
		(layers "F.Cu" "B.Cu")
		(net 138)
	)
	(via
		(at 133.650001 139.8775)
		(size 0.45)
		(drill 0.1)
		(layers "F.Cu" "B.Cu")
		(net 138)
	)
	(segment
		(start 139.386 165.386)
		(end 140.458501 165.386)
		(width 0.1)
		(layer "In4.Cu")
		(net 138)
	)
	(segment
		(start 138.6 164.6)
		(end 139.386 165.386)
		(width 0.1)
		(layer "In4.Cu")
		(net 138)
	)
	(segment
		(start 140.458501 165.386)
		(end 140.875001 165.8025)
		(width 0.1)
		(layer "In4.Cu")
		(net 138)
	)
	(segment
		(start 130.690501 153.690501)
		(end 138.6 161.6)
		(width 0.1)
		(layer "In4.Cu")
		(net 138)
	)
	(segment
		(start 130.690501 147.886)
		(end 130.690501 153.690501)
		(width 0.1)
		(layer "In4.Cu")
		(net 138)
	)
	(segment
		(start 130.390501 147.586)
		(end 130.690501 147.886)
		(width 0.1)
		(layer "In4.Cu")
		(net 138)
	)
	(segment
		(start 130.974501 142.525499)
		(end 130.974501 145.902)
		(width 0.1)
		(layer "In4.Cu")
		(net 138)
	)
	(segment
		(start 138.6 161.6)
		(end 138.6 164.6)
		(width 0.1)
		(layer "In4.Cu")
		(net 138)
	)
	(segment
		(start 130.390501 146.486)
		(end 130.390501 147.586)
		(width 0.1)
		(layer "In4.Cu")
		(net 138)
	)
	(segment
		(start 133.650001 139.8775)
		(end 133.6225 139.8775)
		(width 0.1)
		(layer "In4.Cu")
		(net 138)
	)
	(segment
		(start 133.6225 139.8775)
		(end 130.974501 142.525499)
		(width 0.1)
		(layer "In4.Cu")
		(net 138)
	)
	(segment
		(start 130.974501 145.902)
		(end 130.390501 146.486)
		(width 0.1)
		(layer "In4.Cu")
		(net 138)
	)
	(segment
		(start 142.375501 164.302)
		(end 142.875001 163.8025)
		(width 0.256)
		(layer "F.Cu")
		(net 139)
	)
	(segment
		(start 134.400001 146.2025)
		(end 134.400001 145.1275)
		(width 0.201)
		(layer "F.Cu")
		(net 139)
	)
	(via
		(at 142.875001 163.8025)
		(size 0.45)
		(drill 0.1)
		(layers "F.Cu" "B.Cu")
		(net 139)
	)
	(via
		(at 134.400001 145.1275)
		(size 0.45)
		(drill 0.1)
		(layers "F.Cu" "B.Cu")
		(net 139)
	)
	(segment
		(start 141.127068 159.208713)
		(end 141.127067 159.208712)
		(width 0.1)
		(layer "In4.Cu")
		(net 139)
	)
	(segment
		(start 138.298623 156.026714)
		(end 138.776713 155.548622)
		(width 0.1)
		(layer "In4.Cu")
		(net 139)
	)
	(segment
		(start 142.312268 158.730623)
		(end 142.312269 158.730623)
		(width 0.1)
		(layer "In4.Cu")
		(net 139)
	)
	(segment
		(start 133.525001 146.0025)
		(end 134.400001 145.1275)
		(width 0.1)
		(layer "In4.Cu")
		(net 139)
	)
	(segment
		(start 137.591512 155.319603)
		(end 138.069602 154.841511)
		(width 0.1)
		(layer "In4.Cu")
		(net 139)
	)
	(segment
		(start 137.591511 155.319604)
		(end 137.591512 155.319603)
		(width 0.1)
		(layer "In4.Cu")
		(net 139)
	)
	(segment
		(start 138.069603 154.487958)
		(end 138.069602 154.487957)
		(width 0.1)
		(layer "In4.Cu")
		(net 139)
	)
	(segment
		(start 142.400501 159.650501)
		(end 142.25 159.5)
		(width 0.1)
		(layer "In4.Cu")
		(net 139)
	)
	(segment
		(start 137.300225 154.550226)
		(end 133.690501 150.940501)
		(width 0.1)
		(layer "In4.Cu")
		(net 139)
	)
	(segment
		(start 139.13027 155.902179)
		(end 138.652177 156.380268)
		(width 0.1)
		(layer "In4.Cu")
		(net 139)
	)
	(segment
		(start 139.712845 157.440936)
		(end 140.190935 156.962844)
		(width 0.1)
		(layer "In4.Cu")
		(net 139)
	)
	(segment
		(start 139.837382 156.609289)
		(end 139.837381 156.60929)
		(width 0.1)
		(layer "In4.Cu")
		(net 139)
	)
	(segment
		(start 140.544493 157.3164)
		(end 140.544492 157.316401)
		(width 0.1)
		(layer "In4.Cu")
		(net 139)
	)
	(segment
		(start 133.525001 147.7205)
		(end 133.525001 146.0025)
		(width 0.1)
		(layer "In4.Cu")
		(net 139)
	)
	(segment
		(start 137.591513 155.673158)
		(end 137.591512 155.673157)
		(width 0.1)
		(layer "In4.Cu")
		(net 139)
	)
	(segment
		(start 138.298624 156.380269)
		(end 138.298623 156.380268)
		(width 0.1)
		(layer "In4.Cu")
		(net 139)
	)
	(segment
		(start 141.251603 158.023512)
		(end 140.77351 158.501601)
		(width 0.1)
		(layer "In4.Cu")
		(net 139)
	)
	(segment
		(start 142.400501 163.328)
		(end 142.400501 159.650501)
		(width 0.1)
		(layer "In4.Cu")
		(net 139)
	)
	(segment
		(start 138.776714 155.195069)
		(end 138.776713 155.195068)
		(width 0.1)
		(layer "In4.Cu")
		(net 139)
	)
	(segment
		(start 138.298622 156.026715)
		(end 138.298623 156.026714)
		(width 0.1)
		(layer "In4.Cu")
		(net 139)
	)
	(segment
		(start 141.251604 158.023511)
		(end 141.251603 158.023512)
		(width 0.1)
		(layer "In4.Cu")
		(net 139)
	)
	(segment
		(start 139.005733 156.733826)
		(end 139.005734 156.733825)
		(width 0.1)
		(layer "In4.Cu")
		(net 139)
	)
	(segment
		(start 138.42316 155.195067)
		(end 138.423159 155.195068)
		(width 0.1)
		(layer "In4.Cu")
		(net 139)
	)
	(segment
		(start 139.712844 157.440937)
		(end 139.712845 157.440936)
		(width 0.1)
		(layer "In4.Cu")
		(net 139)
	)
	(segment
		(start 141.127067 158.855158)
		(end 141.605157 158.377066)
		(width 0.1)
		(layer "In4.Cu")
		(net 139)
	)
	(segment
		(start 142.249999 159.146447)
		(end 142.25 159.146446)
		(width 0.1)
		(layer "In4.Cu")
		(net 139)
	)
	(segment
		(start 139.483825 155.90218)
		(end 139.483824 155.902179)
		(width 0.1)
		(layer "In4.Cu")
		(net 139)
	)
	(segment
		(start 137.716048 154.487957)
		(end 137.653778 154.550226)
		(width 0.1)
		(layer "In4.Cu")
		(net 139)
	)
	(segment
		(start 140.419955 158.148048)
		(end 140.419956 158.148047)
		(width 0.1)
		(layer "In4.Cu")
		(net 139)
	)
	(segment
		(start 139.130271 155.902178)
		(end 139.13027 155.902179)
		(width 0.1)
		(layer "In4.Cu")
		(net 139)
	)
	(segment
		(start 133.690501 147.886)
		(end 133.525001 147.7205)
		(width 0.1)
		(layer "In4.Cu")
		(net 139)
	)
	(segment
		(start 141.127066 158.855159)
		(end 141.127067 158.855158)
		(width 0.1)
		(layer "In4.Cu")
		(net 139)
	)
	(segment
		(start 138.423159 155.195068)
		(end 137.945066 155.673157)
		(width 0.1)
		(layer "In4.Cu")
		(net 139)
	)
	(segment
		(start 141.958716 158.730622)
		(end 141.958715 158.730623)
		(width 0.1)
		(layer "In4.Cu")
		(net 139)
	)
	(segment
		(start 137.300225 154.550225)
		(end 137.300225 154.550226)
		(width 0.1)
		(layer "In4.Cu")
		(net 139)
	)
	(segment
		(start 139.837381 156.60929)
		(end 139.359288 157.087379)
		(width 0.1)
		(layer "In4.Cu")
		(net 139)
	)
	(segment
		(start 140.419957 158.501602)
		(end 140.419956 158.501601)
		(width 0.1)
		(layer "In4.Cu")
		(net 139)
	)
	(segment
		(start 140.190936 156.609291)
		(end 140.190935 156.60929)
		(width 0.1)
		(layer "In4.Cu")
		(net 139)
	)
	(segment
		(start 140.419956 158.148047)
		(end 140.898046 157.669955)
		(width 0.1)
		(layer "In4.Cu")
		(net 139)
	)
	(segment
		(start 140.544492 157.316401)
		(end 140.066399 157.79449)
		(width 0.1)
		(layer "In4.Cu")
		(net 139)
	)
	(segment
		(start 139.712846 157.794491)
		(end 139.712845 157.79449)
		(width 0.1)
		(layer "In4.Cu")
		(net 139)
	)
	(segment
		(start 141.958715 158.730623)
		(end 141.480621 159.208712)
		(width 0.1)
		(layer "In4.Cu")
		(net 139)
	)
	(segment
		(start 137.716049 154.487956)
		(end 137.716048 154.487957)
		(width 0.1)
		(layer "In4.Cu")
		(net 139)
	)
	(segment
		(start 142.875001 163.8025)
		(end 142.400501 163.328)
		(width 0.1)
		(layer "In4.Cu")
		(net 139)
	)
	(segment
		(start 141.605158 158.023513)
		(end 141.605157 158.023512)
		(width 0.1)
		(layer "In4.Cu")
		(net 139)
	)
	(segment
		(start 133.690501 150.940501)
		(end 133.690501 147.886)
		(width 0.1)
		(layer "In4.Cu")
		(net 139)
	)
	(segment
		(start 139.005735 157.08738)
		(end 139.005734 157.087379)
		(width 0.1)
		(layer "In4.Cu")
		(net 139)
	)
	(segment
		(start 142.25 159.146446)
		(end 142.312269 159.084176)
		(width 0.1)
		(layer "In4.Cu")
		(net 139)
	)
	(segment
		(start 139.005734 156.733825)
		(end 139.483824 156.255733)
		(width 0.1)
		(layer "In4.Cu")
		(net 139)
	)
	(segment
		(start 140.898047 157.316402)
		(end 140.898046 157.316401)
		(width 0.1)
		(layer "In4.Cu")
		(net 139)
	)
	(arc
		(start 137.945066 155.673157)
		(mid 137.76829 155.746381)
		(end 137.591513 155.673158)
		(width 0.1)
		(layer "In4.Cu")
		(net 139)
	)
	(arc
		(start 140.419956 158.501601)
		(mid 140.346732 158.324825)
		(end 140.419955 158.148048)
		(width 0.1)
		(layer "In4.Cu")
		(net 139)
	)
	(arc
		(start 141.127067 159.208712)
		(mid 141.053843 159.031936)
		(end 141.127066 158.855159)
		(width 0.1)
		(layer "In4.Cu")
		(net 139)
	)
	(arc
		(start 140.190935 156.962844)
		(mid 140.264159 156.786068)
		(end 140.190936 156.609291)
		(width 0.1)
		(layer "In4.Cu")
		(net 139)
	)
	(arc
		(start 142.25 159.5)
		(mid 142.176776 159.323224)
		(end 142.249999 159.146447)
		(width 0.1)
		(layer "In4.Cu")
		(net 139)
	)
	(arc
		(start 140.898046 157.669955)
		(mid 140.97127 157.493179)
		(end 140.898047 157.316402)
		(width 0.1)
		(layer "In4.Cu")
		(net 139)
	)
	(arc
		(start 138.298623 156.380268)
		(mid 138.225399 156.203492)
		(end 138.298622 156.026715)
		(width 0.1)
		(layer "In4.Cu")
		(net 139)
	)
	(arc
		(start 141.605157 158.023512)
		(mid 141.428381 157.950288)
		(end 141.251604 158.023511)
		(width 0.1)
		(layer "In4.Cu")
		(net 139)
	)
	(arc
		(start 140.898046 157.316401)
		(mid 140.72127 157.243177)
		(end 140.544493 157.3164)
		(width 0.1)
		(layer "In4.Cu")
		(net 139)
	)
	(arc
		(start 138.069602 154.841511)
		(mid 138.142826 154.664735)
		(end 138.069603 154.487958)
		(width 0.1)
		(layer "In4.Cu")
		(net 139)
	)
	(arc
		(start 140.066399 157.79449)
		(mid 139.889623 157.867714)
		(end 139.712846 157.794491)
		(width 0.1)
		(layer "In4.Cu")
		(net 139)
	)
	(arc
		(start 137.653778 154.550226)
		(mid 137.477001 154.623449)
		(end 137.300225 154.550225)
		(width 0.1)
		(layer "In4.Cu")
		(net 139)
	)
	(arc
		(start 141.605157 158.377066)
		(mid 141.678381 158.20029)
		(end 141.605158 158.023513)
		(width 0.1)
		(layer "In4.Cu")
		(net 139)
	)
	(arc
		(start 140.190935 156.60929)
		(mid 140.014159 156.536066)
		(end 139.837382 156.609289)
		(width 0.1)
		(layer "In4.Cu")
		(net 139)
	)
	(arc
		(start 142.312269 158.730623)
		(mid 142.135493 158.657399)
		(end 141.958716 158.730622)
		(width 0.1)
		(layer "In4.Cu")
		(net 139)
	)
	(arc
		(start 141.480621 159.208712)
		(mid 141.303845 159.281936)
		(end 141.127068 159.208713)
		(width 0.1)
		(layer "In4.Cu")
		(net 139)
	)
	(arc
		(start 139.359288 157.087379)
		(mid 139.182512 157.160603)
		(end 139.005735 157.08738)
		(width 0.1)
		(layer "In4.Cu")
		(net 139)
	)
	(arc
		(start 139.712845 157.79449)
		(mid 139.639621 157.617714)
		(end 139.712844 157.440937)
		(width 0.1)
		(layer "In4.Cu")
		(net 139)
	)
	(arc
		(start 138.069602 154.487957)
		(mid 137.892826 154.414733)
		(end 137.716049 154.487956)
		(width 0.1)
		(layer "In4.Cu")
		(net 139)
	)
	(arc
		(start 139.483824 155.902179)
		(mid 139.307048 155.828955)
		(end 139.130271 155.902178)
		(width 0.1)
		(layer "In4.Cu")
		(net 139)
	)
	(arc
		(start 140.77351 158.501601)
		(mid 140.596734 158.574825)
		(end 140.419957 158.501602)
		(width 0.1)
		(layer "In4.Cu")
		(net 139)
	)
	(arc
		(start 138.652177 156.380268)
		(mid 138.475401 156.453492)
		(end 138.298624 156.380269)
		(width 0.1)
		(layer "In4.Cu")
		(net 139)
	)
	(arc
		(start 137.591512 155.673157)
		(mid 137.518288 155.496381)
		(end 137.591511 155.319604)
		(width 0.1)
		(layer "In4.Cu")
		(net 139)
	)
	(arc
		(start 138.776713 155.548622)
		(mid 138.849937 155.371846)
		(end 138.776714 155.195069)
		(width 0.1)
		(layer "In4.Cu")
		(net 139)
	)
	(arc
		(start 142.312269 159.084176)
		(mid 142.385492 158.907399)
		(end 142.312268 158.730623)
		(width 0.1)
		(layer "In4.Cu")
		(net 139)
	)
	(arc
		(start 138.776713 155.195068)
		(mid 138.599937 155.121844)
		(end 138.42316 155.195067)
		(width 0.1)
		(layer "In4.Cu")
		(net 139)
	)
	(arc
		(start 139.005734 157.087379)
		(mid 138.93251 156.910603)
		(end 139.005733 156.733826)
		(width 0.1)
		(layer "In4.Cu")
		(net 139)
	)
	(arc
		(start 139.483824 156.255733)
		(mid 139.557048 156.078957)
		(end 139.483825 155.90218)
		(width 0.1)
		(layer "In4.Cu")
		(net 139)
	)
	(segment
		(start 137.150001 138.8025)
		(end 137.150001 137.7275)
		(width 0.201)
		(layer "F.Cu")
		(net 140)
	)
	(via
		(at 137.150001 137.7275)
		(size 0.45)
		(drill 0.1)
		(layers "F.Cu" "B.Cu")
		(net 140)
	)
	(segment
		(start 137.150001 140.514999)
		(end 135.75 141.915)
		(width 0.201)
		(layer "B.Cu")
		(net 140)
	)
	(segment
		(start 137.150001 137.7275)
		(end 137.150001 140.514999)
		(width 0.201)
		(layer "B.Cu")
		(net 140)
	)
	(segment
		(start 135.75 141.915)
		(end 133.75 141.915)
		(width 0.201)
		(layer "B.Cu")
		(net 140)
	)
	(segment
		(start 189.3615 162)
		(end 188.9385 162)
		(width 0.1)
		(layer "F.Cu")
		(net 141)
	)
	(segment
		(start 183.851107 167.496999)
		(end 184.632714 167.497)
		(width 0.2)
		(layer "F.Cu")
		(net 141)
	)
	(segment
		(start 184.632714 167.497)
		(end 184.677214 167.541501)
		(width 0.2)
		(layer "F.Cu")
		(net 141)
	)
	(via
		(at 184.677214 167.541501)
		(size 0.45)
		(drill 0.1)
		(layers "F.Cu" "B.Cu")
		(net 141)
	)
	(via
		(at 188.9385 162)
		(size 0.45)
		(drill 0.1)
		(layers "F.Cu" "B.Cu")
		(net 141)
	)
	(segment
		(start 188.7635 162.175)
		(end 188.9385 162)
		(width 0.1)
		(layer "In4.Cu")
		(net 141)
	)
	(segment
		(start 184.868965 167.34975)
		(end 186.891672 167.34975)
		(width 0.1)
		(layer "In4.Cu")
		(net 141)
	)
	(segment
		(start 186.891672 167.34975)
		(end 189.3 164.941422)
		(width 0.1)
		(layer "In4.Cu")
		(net 141)
	)
	(segment
		(start 189.3 164.941422)
		(end 189.3 163.358578)
		(width 0.1)
		(layer "In4.Cu")
		(net 141)
	)
	(segment
		(start 189.3 163.358578)
		(end 188.7635 162.822078)
		(width 0.1)
		(layer "In4.Cu")
		(net 141)
	)
	(segment
		(start 188.7635 162.822078)
		(end 188.7635 162.175)
		(width 0.1)
		(layer "In4.Cu")
		(net 141)
	)
	(segment
		(start 184.677214 167.541501)
		(end 184.868965 167.34975)
		(width 0.1)
		(layer "In4.Cu")
		(net 141)
	)
	(segment
		(start 180.926107 167.497)
		(end 180.139 167.497)
		(width 0.2)
		(layer "F.Cu")
		(net 142)
	)
	(segment
		(start 180.139 167.497)
		(end 180.1 167.536)
		(width 0.2)
		(layer "F.Cu")
		(net 142)
	)
	(segment
		(start 199.749501 159.699)
		(end 199.326501 159.699)
		(width 0.1)
		(layer "F.Cu")
		(net 142)
	)
	(via
		(at 199.326501 159.699)
		(size 0.45)
		(drill 0.1)
		(layers "F.Cu" "B.Cu")
		(net 142)
	)
	(via
		(at 180.1 167.536)
		(size 0.45)
		(drill 0.1)
		(layers "F.Cu" "B.Cu")
		(net 142)
	)
	(segment
		(start 199.151501 159.874)
		(end 199.326501 159.699)
		(width 0.1)
		(layer "In4.Cu")
		(net 142)
	)
	(segment
		(start 185.841422 160.7)
		(end 186.958578 160.7)
		(width 0.1)
		(layer "In4.Cu")
		(net 142)
	)
	(segment
		(start 184.5 162.041422)
		(end 185.841422 160.7)
		(width 0.1)
		(layer "In4.Cu")
		(net 142)
	)
	(segment
		(start 198.041422 161.3)
		(end 199.151501 160.189921)
		(width 0.1)
		(layer "In4.Cu")
		(net 142)
	)
	(segment
		(start 180.291751 167.344249)
		(end 181.297173 167.344249)
		(width 0.1)
		(layer "In4.Cu")
		(net 142)
	)
	(segment
		(start 186.958578 160.7)
		(end 187.558578 161.3)
		(width 0.1)
		(layer "In4.Cu")
		(net 142)
	)
	(segment
		(start 199.151501 160.189921)
		(end 199.151501 159.874)
		(width 0.1)
		(layer "In4.Cu")
		(net 142)
	)
	(segment
		(start 184.5 164.141422)
		(end 184.5 162.041422)
		(width 0.1)
		(layer "In4.Cu")
		(net 142)
	)
	(segment
		(start 181.297173 167.344249)
		(end 184.5 164.141422)
		(width 0.1)
		(layer "In4.Cu")
		(net 142)
	)
	(segment
		(start 180.1 167.536)
		(end 180.291751 167.344249)
		(width 0.1)
		(layer "In4.Cu")
		(net 142)
	)
	(segment
		(start 187.558578 161.3)
		(end 198.041422 161.3)
		(width 0.1)
		(layer "In4.Cu")
		(net 142)
	)
	(segment
		(start 183.137107 187.887107)
		(end 183.137107 186.375)
		(width 0.2)
		(layer "F.Cu")
		(net 143)
	)
	(segment
		(start 183.176107 187.926107)
		(end 183.137107 187.887107)
		(width 0.2)
		(layer "F.Cu")
		(net 143)
	)
	(segment
		(start 188 189.1)
		(end 188.422 189.1)
		(width 0.1)
		(layer "F.Cu")
		(net 143)
	)
	(via
		(at 183.176107 187.926107)
		(size 0.45)
		(drill 0.1)
		(layers "F.Cu" "B.Cu")
		(net 143)
	)
	(via
		(at 188.423 189.099)
		(size 0.45)
		(drill 0.1)
		(layers "F.Cu" "B.Cu")
		(net 143)
	)
	(segment
		(start 184.108173 189.142488)
		(end 184.108172 189.142486)
		(width 0.1)
		(layer "In4.Cu")
		(net 143)
	)
	(segment
		(start 183.754619 188.965709)
		(end 183.719264 189.001065)
		(width 0.1)
		(layer "In4.Cu")
		(net 143)
	)
	(segment
		(start 184.108171 189.319263)
		(end 184.108172 189.319262)
		(width 0.1)
		(layer "In4.Cu")
		(net 143)
	)
	(segment
		(start 183.176107 187.926107)
		(end 182.984357 188.117857)
		(width 0.1)
		(layer "In4.Cu")
		(net 143)
	)
	(segment
		(start 188.598 190.160578)
		(end 188.598 189.274)
		(width 0.1)
		(layer "In4.Cu")
		(net 143)
	)
	(segment
		(start 184.941422 190.4)
		(end 188.358578 190.4)
		(width 0.1)
		(layer "In4.Cu")
		(net 143)
	)
	(segment
		(start 188.598 189.274)
		(end 188.423 189.099)
		(width 0.1)
		(layer "In4.Cu")
		(net 143)
	)
	(segment
		(start 183.896041 189.177841)
		(end 183.89604 189.177842)
		(width 0.1)
		(layer "In4.Cu")
		(net 143)
	)
	(segment
		(start 188.358578 190.4)
		(end 188.598 190.160578)
		(width 0.1)
		(layer "In4.Cu")
		(net 143)
	)
	(segment
		(start 183.542488 188.824288)
		(end 183.542487 188.824289)
		(width 0.1)
		(layer "In4.Cu")
		(net 143)
	)
	(segment
		(start 183.89604 189.177842)
		(end 183.931396 189.142487)
		(width 0.1)
		(layer "In4.Cu")
		(net 143)
	)
	(segment
		(start 183.75462 188.788935)
		(end 183.754619 188.788933)
		(width 0.1)
		(layer "In4.Cu")
		(net 143)
	)
	(segment
		(start 184.108172 189.319262)
		(end 184.072817 189.354618)
		(width 0.1)
		(layer "In4.Cu")
		(net 143)
	)
	(segment
		(start 183.542487 188.824289)
		(end 183.577843 188.788934)
		(width 0.1)
		(layer "In4.Cu")
		(net 143)
	)
	(segment
		(start 184.072816 189.531394)
		(end 184.941422 190.4)
		(width 0.1)
		(layer "In4.Cu")
		(net 143)
	)
	(segment
		(start 182.984357 188.117857)
		(end 182.984357 188.442935)
		(width 0.1)
		(layer "In4.Cu")
		(net 143)
	)
	(segment
		(start 183.754618 188.96571)
		(end 183.754619 188.965709)
		(width 0.1)
		(layer "In4.Cu")
		(net 143)
	)
	(segment
		(start 182.984357 188.442935)
		(end 183.365711 188.824289)
		(width 0.1)
		(layer "In4.Cu")
		(net 143)
	)
	(arc
		(start 183.719264 189.177842)
		(mid 183.807653 189.214453)
		(end 183.896041 189.177841)
		(width 0.1)
		(layer "In4.Cu")
		(net 143)
	)
	(arc
		(start 183.365711 188.824289)
		(mid 183.4541 188.8609)
		(end 183.542488 188.824288)
		(width 0.1)
		(layer "In4.Cu")
		(net 143)
	)
	(arc
		(start 183.931396 189.142487)
		(mid 184.019785 189.105876)
		(end 184.108173 189.142488)
		(width 0.1)
		(layer "In4.Cu")
		(net 143)
	)
	(arc
		(start 183.754619 188.788933)
		(mid 183.79123 188.877322)
		(end 183.754618 188.96571)
		(width 0.1)
		(layer "In4.Cu")
		(net 143)
	)
	(arc
		(start 183.719264 189.001065)
		(mid 183.682653 189.089454)
		(end 183.719265 189.177842)
		(width 0.1)
		(layer "In4.Cu")
		(net 143)
	)
	(arc
		(start 183.577843 188.788934)
		(mid 183.666232 188.752323)
		(end 183.75462 188.788935)
		(width 0.1)
		(layer "In4.Cu")
		(net 143)
	)
	(arc
		(start 184.072817 189.354618)
		(mid 184.036206 189.443007)
		(end 184.072818 189.531395)
		(width 0.1)
		(layer "In4.Cu")
		(net 143)
	)
	(arc
		(start 184.108172 189.142486)
		(mid 184.144783 189.230875)
		(end 184.108171 189.319263)
		(width 0.1)
		(layer "In4.Cu")
		(net 143)
	)
	(segment
		(start 181.595606 169.762107)
		(end 181.640107 169.717607)
		(width 0.2)
		(layer "F.Cu")
		(net 144)
	)
	(segment
		(start 198.827001 173.974998)
		(end 199.250001 173.974998)
		(width 0.1)
		(layer "F.Cu")
		(net 144)
	)
	(segment
		(start 181.640107 169.717607)
		(end 181.640107 168.211)
		(width 0.2)
		(layer "F.Cu")
		(net 144)
	)
	(via
		(at 181.595606 169.762107)
		(size 0.45)
		(drill 0.1)
		(layers "F.Cu" "B.Cu")
		(net 144)
	)
	(via
		(at 199.250001 173.974998)
		(size 0.45)
		(drill 0.1)
		(layers "F.Cu" "B.Cu")
		(net 144)
	)
	(segment
		(start 191.241422 172.6)
		(end 198.958578 172.6)
		(width 0.1)
		(layer "In4.Cu")
		(net 144)
	)
	(segment
		(start 189.241422 174.6)
		(end 191.241422 172.6)
		(width 0.1)
		(layer "In4.Cu")
		(net 144)
	)
	(segment
		(start 181.787356 169.953857)
		(end 181.787356 171.428778)
		(width 0.1)
		(layer "In4.Cu")
		(net 144)
	)
	(segment
		(start 184.958578 174.6)
		(end 189.241422 174.6)
		(width 0.1)
		(layer "In4.Cu")
		(net 144)
	)
	(segment
		(start 181.787356 171.428778)
		(end 184.958578 174.6)
		(width 0.1)
		(layer "In4.Cu")
		(net 144)
	)
	(segment
		(start 199.425001 173.799998)
		(end 199.250001 173.974998)
		(width 0.1)
		(layer "In4.Cu")
		(net 144)
	)
	(segment
		(start 199.425001 173.066423)
		(end 199.425001 173.799998)
		(width 0.1)
		(layer "In4.Cu")
		(net 144)
	)
	(segment
		(start 181.595606 169.762107)
		(end 181.787356 169.953857)
		(width 0.1)
		(layer "In4.Cu")
		(net 144)
	)
	(segment
		(start 198.958578 172.6)
		(end 199.425001 173.066423)
		(width 0.1)
		(layer "In4.Cu")
		(net 144)
	)
	(segment
		(start 181.640108 186.375)
		(end 181.640107 187.156607)
		(width 0.2)
		(layer "F.Cu")
		(net 145)
	)
	(segment
		(start 181.640107 187.156607)
		(end 181.595606 187.201107)
		(width 0.2)
		(layer "F.Cu")
		(net 145)
	)
	(segment
		(start 198.3 191.325)
		(end 198.722 191.325)
		(width 0.1)
		(layer "F.Cu")
		(net 145)
	)
	(via
		(at 181.595606 187.201107)
		(size 0.45)
		(drill 0.1)
		(layers "F.Cu" "B.Cu")
		(net 145)
	)
	(via
		(at 198.723 191.324)
		(size 0.45)
		(drill 0.1)
		(layers "F.Cu" "B.Cu")
		(net 145)
	)
	(segment
		(start 196.441422 191.8)
		(end 197.741422 190.5)
		(width 0.1)
		(layer "In4.Cu")
		(net 145)
	)
	(segment
		(start 181.787356 189.728778)
		(end 183.858578 191.8)
		(width 0.1)
		(layer "In4.Cu")
		(net 145)
	)
	(segment
		(start 198.898 191.149)
		(end 198.723 191.324)
		(width 0.1)
		(layer "In4.Cu")
		(net 145)
	)
	(segment
		(start 181.595606 187.201107)
		(end 181.787356 187.392857)
		(width 0.1)
		(layer "In4.Cu")
		(net 145)
	)
	(segment
		(start 198.898 190.839422)
		(end 198.898 191.149)
		(width 0.1)
		(layer "In4.Cu")
		(net 145)
	)
	(segment
		(start 198.558578 190.5)
		(end 198.898 190.839422)
		(width 0.1)
		(layer "In4.Cu")
		(net 145)
	)
	(segment
		(start 181.787356 187.392857)
		(end 181.787356 189.728778)
		(width 0.1)
		(layer "In4.Cu")
		(net 145)
	)
	(segment
		(start 197.741422 190.5)
		(end 198.558578 190.5)
		(width 0.1)
		(layer "In4.Cu")
		(net 145)
	)
	(segment
		(start 183.858578 191.8)
		(end 196.441422 191.8)
		(width 0.1)
		(layer "In4.Cu")
		(net 145)
	)
	(segment
		(start 187.9655 162.000999)
		(end 188.3875 162.000999)
		(width 0.1)
		(layer "F.Cu")
		(net 146)
	)
	(segment
		(start 183.851107 166.997)
		(end 184.638214 166.997)
		(width 0.2)
		(layer "F.Cu")
		(net 146)
	)
	(segment
		(start 184.638214 166.997)
		(end 184.677214 166.958)
		(width 0.2)
		(layer "F.Cu")
		(net 146)
	)
	(via
		(at 188.3885 162)
		(size 0.45)
		(drill 0.1)
		(layers "F.Cu" "B.Cu")
		(net 146)
	)
	(via
		(at 184.677214 166.958)
		(size 0.45)
		(drill 0.1)
		(layers "F.Cu" "B.Cu")
		(net 146)
	)
	(segment
		(start 184.677214 166.958)
		(end 184.868964 167.14975)
		(width 0.1)
		(layer "In4.Cu")
		(net 146)
	)
	(segment
		(start 186.32025 167.14975)
		(end 186.37025 167.14975)
		(width 0.1)
		(layer "In4.Cu")
		(net 146)
	)
	(segment
		(start 189.1 163.441422)
		(end 188.5635 162.904922)
		(width 0.1)
		(layer "In4.Cu")
		(net 146)
	)
	(segment
		(start 186.808828 167.14975)
		(end 189.1 164.858578)
		(width 0.1)
		(layer "In4.Cu")
		(net 146)
	)
	(segment
		(start 186.37025 167.14975)
		(end 186.808828 167.14975)
		(width 0.1)
		(layer "In4.Cu")
		(net 146)
	)
	(segment
		(start 184.868964 167.14975)
		(end 185.32025 167.14975)
		(width 0.1)
		(layer "In4.Cu")
		(net 146)
	)
	(segment
		(start 188.5635 162.175)
		(end 188.3885 162)
		(width 0.1)
		(layer "In4.Cu")
		(net 146)
	)
	(segment
		(start 189.1 164.858578)
		(end 189.1 163.441422)
		(width 0.1)
		(layer "In4.Cu")
		(net 146)
	)
	(segment
		(start 188.5635 162.904922)
		(end 188.5635 162.175)
		(width 0.1)
		(layer "In4.Cu")
		(net 146)
	)
	(arc
		(start 186.19525 167.02475)
		(mid 186.231862 167.113138)
		(end 186.32025 167.14975)
		(width 0.1)
		(layer "In4.Cu")
		(net 146)
	)
	(arc
		(start 185.57025 166.89975)
		(mid 185.658638 166.936362)
		(end 185.69525 167.02475)
		(width 0.1)
		(layer "In4.Cu")
		(net 146)
	)
	(arc
		(start 185.32025 167.14975)
		(mid 185.408638 167.113138)
		(end 185.44525 167.02475)
		(width 0.1)
		(layer "In4.Cu")
		(net 146)
	)
	(arc
		(start 185.69525 167.02475)
		(mid 185.731862 167.113138)
		(end 185.82025 167.14975)
		(width 0.1)
		(layer "In4.Cu")
		(net 146)
	)
	(arc
		(start 186.07025 166.89975)
		(mid 186.158638 166.936362)
		(end 186.19525 167.02475)
		(width 0.1)
		(layer "In4.Cu")
		(net 146)
	)
	(arc
		(start 185.44525 167.02475)
		(mid 185.481862 166.936362)
		(end 185.57025 166.89975)
		(width 0.1)
		(layer "In4.Cu")
		(net 146)
	)
	(arc
		(start 185.94525 167.02475)
		(mid 185.981862 166.936362)
		(end 186.07025 166.89975)
		(width 0.1)
		(layer "In4.Cu")
		(net 146)
	)
	(arc
		(start 185.82025 167.14975)
		(mid 185.908638 167.113138)
		(end 185.94525 167.02475)
		(width 0.1)
		(layer "In4.Cu")
		(net 146)
	)
	(segment
		(start 134.650001 138.8025)
		(end 134.650001 139.8775)
		(width 0.201)
		(layer "F.Cu")
		(net 147)
	)
	(segment
		(start 139.375501 165.302)
		(end 139.875001 164.802501)
		(width 0.256)
		(layer "F.Cu")
		(net 147)
	)
	(via
		(at 134.650001 139.8775)
		(size 0.45)
		(drill 0.1)
		(layers "F.Cu" "B.Cu")
		(net 147)
	)
	(via
		(at 139.875001 164.802501)
		(size 0.45)
		(drill 0.1)
		(layers "F.Cu" "B.Cu")
		(net 147)
	)
	(segment
		(start 134.650001 139.8775)
		(end 131.9 142.627501)
		(width 0.1)
		(layer "In4.Cu")
		(net 147)
	)
	(segment
		(start 131.390501 153.390501)
		(end 139.3 161.3)
		(width 0.1)
		(layer "In4.Cu")
		(net 147)
	)
	(segment
		(start 131.390501 146.5365)
		(end 131.390501 153.390501)
		(width 0.1)
		(layer "In4.Cu")
		(net 147)
	)
	(segment
		(start 139.3 164.2275)
		(end 139.875001 164.802501)
		(width 0.1)
		(layer "In4.Cu")
		(net 147)
	)
	(segment
		(start 131.9 146.027001)
		(end 131.390501 146.5365)
		(width 0.1)
		(layer "In4.Cu")
		(net 147)
	)
	(segment
		(start 139.3 161.3)
		(end 139.3 164.2275)
		(width 0.1)
		(layer "In4.Cu")
		(net 147)
	)
	(segment
		(start 131.9 142.627501)
		(end 131.9 146.027001)
		(width 0.1)
		(layer "In4.Cu")
		(net 147)
	)
	(segment
		(start 143.375501 165.302)
		(end 143.875002 164.8025)
		(width 0.256)
		(layer "F.Cu")
		(net 148)
	)
	(segment
		(start 134.900001 146.2025)
		(end 134.900001 147.2775)
		(width 0.201)
		(layer "F.Cu")
		(net 148)
	)
	(via
		(at 134.900001 147.2775)
		(size 0.45)
		(drill 0.1)
		(layers "F.Cu" "B.Cu")
		(net 148)
	)
	(via
		(at 143.875002 164.8025)
		(size 0.45)
		(drill 0.1)
		(layers "F.Cu" "B.Cu")
		(net 148)
	)
	(segment
		(start 142.720956 156.80416)
		(end 142.720955 156.804161)
		(width 0.1)
		(layer "In4.Cu")
		(net 148)
	)
	(segment
		(start 139.538953 153.268606)
		(end 139.538954 153.268606)
		(width 0.1)
		(layer "In4.Cu")
		(net 148)
	)
	(segment
		(start 140.536383 155.80673)
		(end 140.536384 155.806732)
		(width 0.1)
		(layer "In4.Cu")
		(net 148)
	)
	(segment
		(start 142.013844 156.09705)
		(end 141.597047 156.513842)
		(width 0.1)
		(layer "In4.Cu")
		(net 148)
	)
	(segment
		(start 139.892511 153.975717)
		(end 139.475714 154.392509)
		(width 0.1)
		(layer "In4.Cu")
		(net 148)
	)
	(segment
		(start 143.500001 164.427499)
		(end 143.500001 161.249999)
		(width 0.1)
		(layer "In4.Cu")
		(net 148)
	)
	(segment
		(start 143.75 161)
		(end 143.75 158.25)
		(width 0.1)
		(layer "In4.Cu")
		(net 148)
	)
	(segment
		(start 138.831842 152.561495)
		(end 138.831843 152.561495)
		(width 0.1)
		(layer "In4.Cu")
		(net 148)
	)
	(segment
		(start 138.47829 152.561494)
		(end 138.478289 152.561495)
		(width 0.1)
		(layer "In4.Cu")
		(net 148)
	)
	(segment
		(start 139.185401 153.268605)
		(end 139.1854 153.268606)
		(width 0.1)
		(layer "In4.Cu")
		(net 148)
	)
	(segment
		(start 139.122162 154.038956)
		(end 139.538954 153.622159)
		(width 0.1)
		(layer "In4.Cu")
		(net 148)
	)
	(segment
		(start 143.75 157.896446)
		(end 143.78162 157.864825)
		(width 0.1)
		(layer "In4.Cu")
		(net 148)
	)
	(segment
		(start 142.657716 157.928063)
		(end 142.657717 157.928065)
		(width 0.1)
		(layer "In4.Cu")
		(net 148)
	)
	(segment
		(start 139.122161 154.392508)
		(end 139.122162 154.39251)
		(width 0.1)
		(layer "In4.Cu")
		(net 148)
	)
	(segment
		(start 138.093114 152.593115)
		(end 138.093115 152.593115)
		(width 0.1)
		(layer "In4.Cu")
		(net 148)
	)
	(segment
		(start 141.950605 156.867401)
		(end 141.950606 156.8674)
		(width 0.1)
		(layer "In4.Cu")
		(net 148)
	)
	(segment
		(start 141.243494 156.513841)
		(end 141.243495 156.513843)
		(width 0.1)
		(layer "In4.Cu")
		(net 148)
	)
	(segment
		(start 141.243494 156.16029)
		(end 141.243495 156.160289)
		(width 0.1)
		(layer "In4.Cu")
		(net 148)
	)
	(segment
		(start 142.013845 156.097049)
		(end 142.013844 156.09705)
		(width 0.1)
		(layer "In4.Cu")
		(net 148)
	)
	(segment
		(start 134.900001 149.400001)
		(end 134.900001 147.2775)
		(width 0.1)
		(layer "In4.Cu")
		(net 148)
	)
	(segment
		(start 142.367397 156.09705)
		(end 142.367398 156.09705)
		(width 0.1)
		(layer "In4.Cu")
		(net 148)
	)
	(segment
		(start 142.720955 156.804161)
		(end 142.304158 157.220953)
		(width 0.1)
		(layer "In4.Cu")
		(net 148)
	)
	(segment
		(start 141.660286 155.389939)
		(end 141.660287 155.389939)
		(width 0.1)
		(layer "In4.Cu")
		(net 148)
	)
	(segment
		(start 141.306734 155.389938)
		(end 141.306733 155.389939)
		(width 0.1)
		(layer "In4.Cu")
		(net 148)
	)
	(segment
		(start 138.093115 152.593115)
		(end 134.900001 149.400001)
		(width 0.1)
		(layer "In4.Cu")
		(net 148)
	)
	(segment
		(start 143.875002 164.8025)
		(end 143.500001 164.427499)
		(width 0.1)
		(layer "In4.Cu")
		(net 148)
	)
	(segment
		(start 142.657717 157.574511)
		(end 143.074509 157.157714)
		(width 0.1)
		(layer "In4.Cu")
		(net 148)
	)
	(segment
		(start 143.78162 157.511271)
		(end 143.78162 157.511272)
		(width 0.1)
		(layer "In4.Cu")
		(net 148)
	)
	(segment
		(start 142.657716 157.574512)
		(end 142.657717 157.574511)
		(width 0.1)
		(layer "In4.Cu")
		(net 148)
	)
	(segment
		(start 138.478289 152.561495)
		(end 138.446668 152.593115)
		(width 0.1)
		(layer "In4.Cu")
		(net 148)
	)
	(segment
		(start 139.892512 153.975716)
		(end 139.892511 153.975717)
		(width 0.1)
		(layer "In4.Cu")
		(net 148)
	)
	(segment
		(start 141.306733 155.389939)
		(end 140.889936 155.806731)
		(width 0.1)
		(layer "In4.Cu")
		(net 148)
	)
	(segment
		(start 143.428066 157.511272)
		(end 143.011269 157.928064)
		(width 0.1)
		(layer "In4.Cu")
		(net 148)
	)
	(segment
		(start 138.41505 153.331846)
		(end 138.415051 153.331845)
		(width 0.1)
		(layer "In4.Cu")
		(net 148)
	)
	(segment
		(start 140.599622 154.682828)
		(end 140.182825 155.09962)
		(width 0.1)
		(layer "In4.Cu")
		(net 148)
	)
	(segment
		(start 139.829273 154.746067)
		(end 140.246065 154.32927)
		(width 0.1)
		(layer "In4.Cu")
		(net 148)
	)
	(segment
		(start 143.074508 156.804161)
		(end 143.074509 156.804161)
		(width 0.1)
		(layer "In4.Cu")
		(net 148)
	)
	(segment
		(start 141.243495 156.160289)
		(end 141.660287 155.743492)
		(width 0.1)
		(layer "In4.Cu")
		(net 148)
	)
	(segment
		(start 139.829272 155.099619)
		(end 139.829273 155.099621)
		(width 0.1)
		(layer "In4.Cu")
		(net 148)
	)
	(segment
		(start 139.122161 154.038957)
		(end 139.122162 154.038956)
		(width 0.1)
		(layer "In4.Cu")
		(net 148)
	)
	(segment
		(start 139.829272 154.746068)
		(end 139.829273 154.746067)
		(width 0.1)
		(layer "In4.Cu")
		(net 148)
	)
	(segment
		(start 138.41505 153.685397)
		(end 138.415051 153.685399)
		(width 0.1)
		(layer "In4.Cu")
		(net 148)
	)
	(segment
		(start 141.950606 156.8674)
		(end 142.367398 156.450603)
		(width 0.1)
		(layer "In4.Cu")
		(net 148)
	)
	(segment
		(start 140.599623 154.682827)
		(end 140.599622 154.682828)
		(width 0.1)
		(layer "In4.Cu")
		(net 148)
	)
	(segment
		(start 140.536384 155.453178)
		(end 140.953176 155.036381)
		(width 0.1)
		(layer "In4.Cu")
		(net 148)
	)
	(segment
		(start 143.500001 161.249999)
		(end 143.75 161)
		(width 0.1)
		(layer "In4.Cu")
		(net 148)
	)
	(segment
		(start 140.536383 155.453179)
		(end 140.536384 155.453178)
		(width 0.1)
		(layer "In4.Cu")
		(net 148)
	)
	(segment
		(start 140.953175 154.682828)
		(end 140.953176 154.682828)
		(width 0.1)
		(layer "In4.Cu")
		(net 148)
	)
	(segment
		(start 143.428067 157.511271)
		(end 143.428066 157.511272)
		(width 0.1)
		(layer "In4.Cu")
		(net 148)
	)
	(segment
		(start 140.246064 153.975717)
		(end 140.246065 153.975717)
		(width 0.1)
		(layer "In4.Cu")
		(net 148)
	)
	(segment
		(start 143.749999 157.896447)
		(end 143.75 157.896446)
		(width 0.1)
		(layer "In4.Cu")
		(net 148)
	)
	(segment
		(start 139.1854 153.268606)
		(end 138.768603 153.685398)
		(width 0.1)
		(layer "In4.Cu")
		(net 148)
	)
	(segment
		(start 141.950605 157.220952)
		(end 141.950606 157.220954)
		(width 0.1)
		(layer "In4.Cu")
		(net 148)
	)
	(segment
		(start 138.415051 153.331845)
		(end 138.831843 152.915048)
		(width 0.1)
		(layer "In4.Cu")
		(net 148)
	)
	(arc
		(start 139.475714 154.392509)
		(mid 139.298937 154.465732)
		(end 139.122161 154.392508)
		(width 0.1)
		(layer "In4.Cu")
		(net 148)
	)
	(arc
		(start 141.660287 155.743492)
		(mid 141.73351 155.566715)
		(end 141.660286 155.389939)
		(width 0.1)
		(layer "In4.Cu")
		(net 148)
	)
	(arc
		(start 143.011269 157.928064)
		(mid 142.834492 158.001287)
		(end 142.657716 157.928063)
		(width 0.1)
		(layer "In4.Cu")
		(net 148)
	)
	(arc
		(start 138.768603 153.685398)
		(mid 138.591826 153.758621)
		(end 138.41505 153.685397)
		(width 0.1)
		(layer "In4.Cu")
		(net 148)
	)
	(arc
		(start 143.78162 157.864825)
		(mid 143.854843 157.688048)
		(end 143.78162 157.511271)
		(width 0.1)
		(layer "In4.Cu")
		(net 148)
	)
	(arc
		(start 140.246065 154.32927)
		(mid 140.319288 154.152493)
		(end 140.246064 153.975717)
		(width 0.1)
		(layer "In4.Cu")
		(net 148)
	)
	(arc
		(start 140.182825 155.09962)
		(mid 140.006048 155.172843)
		(end 139.829272 155.099619)
		(width 0.1)
		(layer "In4.Cu")
		(net 148)
	)
	(arc
		(start 140.246065 153.975717)
		(mid 140.069289 153.902493)
		(end 139.892512 153.975716)
		(width 0.1)
		(layer "In4.Cu")
		(net 148)
	)
	(arc
		(start 139.829273 155.099621)
		(mid 139.756049 154.922845)
		(end 139.829272 154.746068)
		(width 0.1)
		(layer "In4.Cu")
		(net 148)
	)
	(arc
		(start 143.074509 156.804161)
		(mid 142.897733 156.730937)
		(end 142.720956 156.80416)
		(width 0.1)
		(layer "In4.Cu")
		(net 148)
	)
	(arc
		(start 139.538954 153.268606)
		(mid 139.362178 153.195382)
		(end 139.185401 153.268605)
		(width 0.1)
		(layer "In4.Cu")
		(net 148)
	)
	(arc
		(start 138.415051 153.685399)
		(mid 138.341827 153.508623)
		(end 138.41505 153.331846)
		(width 0.1)
		(layer "In4.Cu")
		(net 148)
	)
	(arc
		(start 142.367398 156.450603)
		(mid 142.440621 156.273826)
		(end 142.367397 156.09705)
		(width 0.1)
		(layer "In4.Cu")
		(net 148)
	)
	(arc
		(start 141.660287 155.389939)
		(mid 141.483511 155.316715)
		(end 141.306734 155.389938)
		(width 0.1)
		(layer "In4.Cu")
		(net 148)
	)
	(arc
		(start 138.446668 152.593115)
		(mid 138.269891 152.666338)
		(end 138.093114 152.593115)
		(width 0.1)
		(layer "In4.Cu")
		(net 148)
	)
	(arc
		(start 141.243495 156.513843)
		(mid 141.170271 156.337067)
		(end 141.243494 156.16029)
		(width 0.1)
		(layer "In4.Cu")
		(net 148)
	)
	(arc
		(start 142.657717 157.928065)
		(mid 142.584493 157.751289)
		(end 142.657716 157.574512)
		(width 0.1)
		(layer "In4.Cu")
		(net 148)
	)
	(arc
		(start 138.831843 152.915048)
		(mid 138.905066 152.738271)
		(end 138.831842 152.561495)
		(width 0.1)
		(layer "In4.Cu")
		(net 148)
	)
	(arc
		(start 142.367398 156.09705)
		(mid 142.190622 156.023826)
		(end 142.013845 156.097049)
		(width 0.1)
		(layer "In4.Cu")
		(net 148)
	)
	(arc
		(start 141.597047 156.513842)
		(mid 141.42027 156.587065)
		(end 141.243494 156.513841)
		(width 0.1)
		(layer "In4.Cu")
		(net 148)
	)
	(arc
		(start 143.074509 157.157714)
		(mid 143.147732 156.980937)
		(end 143.074508 156.804161)
		(width 0.1)
		(layer "In4.Cu")
		(net 148)
	)
	(arc
		(start 140.536384 155.806732)
		(mid 140.46316 155.629956)
		(end 140.536383 155.453179)
		(width 0.1)
		(layer "In4.Cu")
		(net 148)
	)
	(arc
		(start 138.831843 152.561495)
		(mid 138.655067 152.488271)
		(end 138.47829 152.561494)
		(width 0.1)
		(layer "In4.Cu")
		(net 148)
	)
	(arc
		(start 139.538954 153.622159)
		(mid 139.612177 153.445382)
		(end 139.538953 153.268606)
		(width 0.1)
		(layer "In4.Cu")
		(net 148)
	)
	(arc
		(start 139.122162 154.39251)
		(mid 139.048938 154.215734)
		(end 139.122161 154.038957)
		(width 0.1)
		(layer "In4.Cu")
		(net 148)
	)
	(arc
		(start 143.78162 157.511272)
		(mid 143.604844 157.438048)
		(end 143.428067 157.511271)
		(width 0.1)
		(layer "In4.Cu")
		(net 148)
	)
	(arc
		(start 140.953176 154.682828)
		(mid 140.7764 154.609604)
		(end 140.599623 154.682827)
		(width 0.1)
		(layer "In4.Cu")
		(net 148)
	)
	(arc
		(start 142.304158 157.220953)
		(mid 142.127381 157.294176)
		(end 141.950605 157.220952)
		(width 0.1)
		(layer "In4.Cu")
		(net 148)
	)
	(arc
		(start 141.950606 157.220954)
		(mid 141.877382 157.044178)
		(end 141.950605 156.867401)
		(width 0.1)
		(layer "In4.Cu")
		(net 148)
	)
	(arc
		(start 143.75 158.25)
		(mid 143.676776 158.073224)
		(end 143.749999 157.896447)
		(width 0.1)
		(layer "In4.Cu")
		(net 148)
	)
	(arc
		(start 140.953176 155.036381)
		(mid 141.026399 154.859604)
		(end 140.953175 154.682828)
		(width 0.1)
		(layer "In4.Cu")
		(net 148)
	)
	(arc
		(start 140.889936 155.806731)
		(mid 140.713159 155.879954)
		(end 140.536383 155.80673)
		(width 0.1)
		(layer "In4.Cu")
		(net 148)
	)
	(segment
		(start 143.375501 167.302)
		(end 143.875001 166.8025)
		(width 0.256)
		(layer "F.Cu")
		(net 149)
	)
	(segment
		(start 135.150001 138.8025)
		(end 135.150001 137.7275)
		(width 0.201)
		(layer "F.Cu")
		(net 149)
	)
	(via
		(at 135.150001 137.7275)
		(size 0.45)
		(drill 0.1)
		(layers "F.Cu" "B.Cu")
		(net 149)
	)
	(via
		(at 143.875001 166.8025)
		(size 0.45)
		(drill 0.1)
		(layers "F.Cu" "B.Cu")
		(net 149)
	)
	(segment
		(start 134.860182 142.900001)
		(end 134.900001 142.900001)
		(width 0.1)
		(layer "In4.Cu")
		(net 149)
	)
	(segment
		(start 134.974501 144.375499)
		(end 134.974501 146.453)
		(width 0.1)
		(layer "In4.Cu")
		(net 149)
	)
	(segment
		(start 134.375001 147.0525)
		(end 134.375001 150.200001)
		(width 0.1)
		(layer "In4.Cu")
		(net 149)
	)
	(segment
		(start 134.860182 140.900001)
		(end 135.43982 140.900001)
		(width 0.1)
		(layer "In4.Cu")
		(net 149)
	)
	(segment
		(start 135.150001 137.7275)
		(end 135.150001 140.150001)
		(width 0.1)
		(layer "In4.Cu")
		(net 149)
	)
	(segment
		(start 143.250001 159.075001)
		(end 143.250001 166.1775)
		(width 0.1)
		(layer "In4.Cu")
		(net 149)
	)
	(segment
		(start 135.43982 142.400001)
		(end 134.860182 142.400001)
		(width 0.1)
		(layer "In4.Cu")
		(net 149)
	)
	(segment
		(start 135.43982 141.400001)
		(end 134.860182 141.400001)
		(width 0.1)
		(layer "In4.Cu")
		(net 149)
	)
	(segment
		(start 134.375001 150.200001)
		(end 143.250001 159.075001)
		(width 0.1)
		(layer "In4.Cu")
		(net 149)
	)
	(segment
		(start 134.974501 146.453)
		(end 134.375001 147.0525)
		(width 0.1)
		(layer "In4.Cu")
		(net 149)
	)
	(segment
		(start 143.250001 166.1775)
		(end 143.875001 166.8025)
		(width 0.1)
		(layer "In4.Cu")
		(net 149)
	)
	(segment
		(start 135.150001 144.199999)
		(end 134.974501 144.375499)
		(width 0.1)
		(layer "In4.Cu")
		(net 149)
	)
	(segment
		(start 134.900001 140.400001)
		(end 134.860182 140.400001)
		(width 0.1)
		(layer "In4.Cu")
		(net 149)
	)
	(segment
		(start 134.860182 141.900001)
		(end 135.43982 141.900001)
		(width 0.1)
		(layer "In4.Cu")
		(net 149)
	)
	(segment
		(start 135.150001 143.150001)
		(end 135.150001 144.199999)
		(width 0.1)
		(layer "In4.Cu")
		(net 149)
	)
	(arc
		(start 135.43982 140.900001)
		(mid 135.616597 140.973224)
		(end 135.68982 141.150001)
		(width 0.1)
		(layer "In4.Cu")
		(net 149)
	)
	(arc
		(start 135.43982 141.900001)
		(mid 135.616597 141.973224)
		(end 135.68982 142.150001)
		(width 0.1)
		(layer "In4.Cu")
		(net 149)
	)
	(arc
		(start 134.860182 141.400001)
		(mid 134.683405 141.473224)
		(end 134.610182 141.650001)
		(width 0.1)
		(layer "In4.Cu")
		(net 149)
	)
	(arc
		(start 134.610182 142.650001)
		(mid 134.683405 142.826778)
		(end 134.860182 142.900001)
		(width 0.1)
		(layer "In4.Cu")
		(net 149)
	)
	(arc
		(start 135.150001 140.150001)
		(mid 135.076778 140.326778)
		(end 134.900001 140.400001)
		(width 0.1)
		(layer "In4.Cu")
		(net 149)
	)
	(arc
		(start 134.610182 140.650001)
		(mid 134.683405 140.826778)
		(end 134.860182 140.900001)
		(width 0.1)
		(layer "In4.Cu")
		(net 149)
	)
	(arc
		(start 134.610182 141.650001)
		(mid 134.683405 141.826778)
		(end 134.860182 141.900001)
		(width 0.1)
		(layer "In4.Cu")
		(net 149)
	)
	(arc
		(start 135.68982 141.150001)
		(mid 135.616597 141.326778)
		(end 135.43982 141.400001)
		(width 0.1)
		(layer "In4.Cu")
		(net 149)
	)
	(arc
		(start 134.860182 140.400001)
		(mid 134.683405 140.473224)
		(end 134.610182 140.650001)
		(width 0.1)
		(layer "In4.Cu")
		(net 149)
	)
	(arc
		(start 135.68982 142.150001)
		(mid 135.616597 142.326778)
		(end 135.43982 142.400001)
		(width 0.1)
		(layer "In4.Cu")
		(net 149)
	)
	(arc
		(start 134.900001 142.900001)
		(mid 135.076778 142.973224)
		(end 135.150001 143.150001)
		(width 0.1)
		(layer "In4.Cu")
		(net 149)
	)
	(arc
		(start 134.860182 142.400001)
		(mid 134.683405 142.473224)
		(end 134.610182 142.650001)
		(width 0.1)
		(layer "In4.Cu")
		(net 149)
	)
	(segment
		(start 135.900001 146.2025)
		(end 135.900001 147.2775)
		(width 0.201)
		(layer "F.Cu")
		(net 150)
	)
	(segment
		(start 143.375501 166.302)
		(end 143.875001 165.8025)
		(width 0.256)
		(layer "F.Cu")
		(net 150)
	)
	(via
		(at 135.900001 147.2775)
		(size 0.45)
		(drill 0.1)
		(layers "F.Cu" "B.Cu")
		(net 150)
	)
	(via
		(at 143.875001 165.8025)
		(size 0.45)
		(drill 0.1)
		(layers "F.Cu" "B.Cu")
		(net 150)
	)
	(segment
		(start 139.881052 151.136713)
		(end 139.881052 151.136712)
		(width 0.1)
		(layer "In4.Cu")
		(net 150)
	)
	(segment
		(start 143.416572 154.672233)
		(end 143.416572 154.672232)
		(width 0.1)
		(layer "In4.Cu")
		(net 150)
	)
	(segment
		(start 143.275784 155.520124)
		(end 143.770121 155.025782)
		(width 0.1)
		(layer "In4.Cu")
		(net 150)
	)
	(segment
		(start 142.709468 153.965128)
		(end 142.462299 154.212298)
		(width 0.1)
		(layer "In4.Cu")
		(net 150)
	)
	(segment
		(start 140.588156 151.843817)
		(end 140.588156 151.843816)
		(width 0.1)
		(layer "In4.Cu")
		(net 150)
	)
	(segment
		(start 135.900001 147.650001)
		(end 138.75 150.5)
		(width 0.1)
		(layer "In4.Cu")
		(net 150)
	)
	(segment
		(start 140.340987 152.090986)
		(end 140.340985 152.090985)
		(width 0.1)
		(layer "In4.Cu")
		(net 150)
	)
	(segment
		(start 142.215126 154.813019)
		(end 142.215127 154.81302)
		(width 0.1)
		(layer "In4.Cu")
		(net 150)
	)
	(segment
		(start 140.800918 153.398811)
		(end 140.800919 153.398812)
		(width 0.1)
		(layer "In4.Cu")
		(net 150)
	)
	(segment
		(start 142.56868 154.81302)
		(end 143.063017 154.318678)
		(width 0.1)
		(layer "In4.Cu")
		(net 150)
	)
	(segment
		(start 142.709468 153.611575)
		(end 142.709469 153.611576)
		(width 0.1)
		(layer "In4.Cu")
		(net 150)
	)
	(segment
		(start 142.002364 153.258024)
		(end 141.755195 153.505194)
		(width 0.1)
		(layer "In4.Cu")
		(net 150)
	)
	(segment
		(start 143.169401 154.919401)
		(end 142.922231 155.16657)
		(width 0.1)
		(layer "In4.Cu")
		(net 150)
	)
	(segment
		(start 142.92223 155.520123)
		(end 142.922231 155.520124)
		(width 0.1)
		(layer "In4.Cu")
		(net 150)
	)
	(segment
		(start 142.462299 154.212298)
		(end 142.462297 154.212297)
		(width 0.1)
		(layer "In4.Cu")
		(net 150)
	)
	(segment
		(start 139.633883 151.383882)
		(end 139.633881 151.383881)
		(width 0.1)
		(layer "In4.Cu")
		(net 150)
	)
	(segment
		(start 140.447368 152.691707)
		(end 140.447368 152.691708)
		(width 0.1)
		(layer "In4.Cu")
		(net 150)
	)
	(segment
		(start 143.982888 156.227227)
		(end 143.982888 156.227228)
		(width 0.1)
		(layer "In4.Cu")
		(net 150)
	)
	(segment
		(start 141.048091 152.79809)
		(end 141.048089 152.798089)
		(width 0.1)
		(layer "In4.Cu")
		(net 150)
	)
	(segment
		(start 140.340985 152.090985)
		(end 140.093815 152.338154)
		(width 0.1)
		(layer "In4.Cu")
		(net 150)
	)
	(segment
		(start 139.740264 151.984603)
		(end 139.740264 151.984604)
		(width 0.1)
		(layer "In4.Cu")
		(net 150)
	)
	(segment
		(start 142.462297 154.212297)
		(end 142.215127 154.459466)
		(width 0.1)
		(layer "In4.Cu")
		(net 150)
	)
	(segment
		(start 141.29526 152.197367)
		(end 141.295261 152.197368)
		(width 0.1)
		(layer "In4.Cu")
		(net 150)
	)
	(segment
		(start 139.881052 151.136712)
		(end 139.633883 151.383882)
		(width 0.1)
		(layer "In4.Cu")
		(net 150)
	)
	(segment
		(start 144.500001 161.4265)
		(end 144.5 165.177501)
		(width 0.1)
		(layer "In4.Cu")
		(net 150)
	)
	(segment
		(start 144.5 165.177501)
		(end 143.875001 165.8025)
		(width 0.1)
		(layer "In4.Cu")
		(net 150)
	)
	(segment
		(start 143.876505 155.626505)
		(end 143.629335 155.873674)
		(width 0.1)
		(layer "In4.Cu")
		(net 150)
	)
	(segment
		(start 141.755193 153.505193)
		(end 141.508023 153.752362)
		(width 0.1)
		(layer "In4.Cu")
		(net 150)
	)
	(segment
		(start 142.002364 152.904471)
		(end 142.002365 152.904472)
		(width 0.1)
		(layer "In4.Cu")
		(net 150)
	)
	(segment
		(start 141.154472 153.398811)
		(end 141.154472 153.398812)
		(width 0.1)
		(layer "In4.Cu")
		(net 150)
	)
	(segment
		(start 143.275784 155.520123)
		(end 143.275784 155.520124)
		(width 0.1)
		(layer "In4.Cu")
		(net 150)
	)
	(segment
		(start 142.56868 154.813019)
		(end 142.56868 154.81302)
		(width 0.1)
		(layer "In4.Cu")
		(net 150)
	)
	(segment
		(start 141.755195 153.505194)
		(end 141.755193 153.505193)
		(width 0.1)
		(layer "In4.Cu")
		(net 150)
	)
	(segment
		(start 144.406834 156.156835)
		(end 144.406834 156.156834)
		(width 0.1)
		(layer "In4.Cu")
		(net 150)
	)
	(segment
		(start 140.588156 151.490263)
		(end 140.588157 151.490264)
		(width 0.1)
		(layer "In4.Cu")
		(net 150)
	)
	(segment
		(start 144.123676 155.025783)
		(end 144.123677 155.025784)
		(width 0.1)
		(layer "In4.Cu")
		(net 150)
	)
	(segment
		(start 143.416572 154.318679)
		(end 143.416573 154.31868)
		(width 0.1)
		(layer "In4.Cu")
		(net 150)
	)
	(segment
		(start 141.29526 152.550921)
		(end 141.29526 152.55092)
		(width 0.1)
		(layer "In4.Cu")
		(net 150)
	)
	(segment
		(start 141.508022 154.105915)
		(end 141.508023 154.105916)
		(width 0.1)
		(layer "In4.Cu")
		(net 150)
	)
	(segment
		(start 139.033159 151.277498)
		(end 139.033159 151.277499)
		(width 0.1)
		(layer "In4.Cu")
		(net 150)
	)
	(segment
		(start 139.881052 150.783159)
		(end 139.881053 150.78316)
		(width 0.1)
		(layer "In4.Cu")
		(net 150)
	)
	(segment
		(start 143.416572 154.672232)
		(end 143.169403 154.919402)
		(width 0.1)
		(layer "In4.Cu")
		(net 150)
	)
	(segment
		(start 144.890501 156.640501)
		(end 144.890501 161.036)
		(width 0.1)
		(layer "In4.Cu")
		(net 150)
	)
	(segment
		(start 140.447368 152.691708)
		(end 140.941705 152.197366)
		(width 0.1)
		(layer "In4.Cu")
		(net 150)
	)
	(segment
		(start 141.154472 153.398812)
		(end 141.648809 152.90447)
		(width 0.1)
		(layer "In4.Cu")
		(net 150)
	)
	(segment
		(start 138.75 150.853553)
		(end 138.679606 150.923946)
		(width 0.1)
		(layer "In4.Cu")
		(net 150)
	)
	(segment
		(start 142.002364 153.258025)
		(end 142.002364 153.258024)
		(width 0.1)
		(layer "In4.Cu")
		(net 150)
	)
	(segment
		(start 139.033159 151.277499)
		(end 139.527497 150.783158)
		(width 0.1)
		(layer "In4.Cu")
		(net 150)
	)
	(segment
		(start 143.982888 156.227228)
		(end 144.053281 156.156834)
		(width 0.1)
		(layer "In4.Cu")
		(net 150)
	)
	(segment
		(start 138.749999 150.853553)
		(end 138.75 150.853553)
		(width 0.1)
		(layer "In4.Cu")
		(net 150)
	)
	(segment
		(start 143.876507 155.626506)
		(end 143.876505 155.626505)
		(width 0.1)
		(layer "In4.Cu")
		(net 150)
	)
	(segment
		(start 140.588156 151.843816)
		(end 140.340987 152.090986)
		(width 0.1)
		(layer "In4.Cu")
		(net 150)
	)
	(segment
		(start 139.633881 151.383881)
		(end 139.386711 151.63105)
		(width 0.1)
		(layer "In4.Cu")
		(net 150)
	)
	(segment
		(start 138.679607 151.277499)
		(end 138.679606 151.277499)
		(width 0.1)
		(layer "In4.Cu")
		(net 150)
	)
	(segment
		(start 141.861576 154.105915)
		(end 141.861576 154.105916)
		(width 0.1)
		(layer "In4.Cu")
		(net 150)
	)
	(segment
		(start 141.048089 152.798089)
		(end 140.800919 153.045258)
		(width 0.1)
		(layer "In4.Cu")
		(net 150)
	)
	(segment
		(start 139.38671 151.984603)
		(end 139.386711 151.984604)
		(width 0.1)
		(layer "In4.Cu")
		(net 150)
	)
	(segment
		(start 140.093814 152.691707)
		(end 140.093815 152.691708)
		(width 0.1)
		(layer "In4.Cu")
		(net 150)
	)
	(segment
		(start 144.890501 161.036)
		(end 144.500001 161.4265)
		(width 0.1)
		(layer "In4.Cu")
		(net 150)
	)
	(segment
		(start 141.861576 154.105916)
		(end 142.355913 153.611574)
		(width 0.1)
		(layer "In4.Cu")
		(net 150)
	)
	(segment
		(start 142.709468 153.965129)
		(end 142.709468 153.965128)
		(width 0.1)
		(layer "In4.Cu")
		(net 150)
	)
	(segment
		(start 144.123676 155.379337)
		(end 144.123676 155.379336)
		(width 0.1)
		(layer "In4.Cu")
		(net 150)
	)
	(segment
		(start 139.740264 151.984604)
		(end 140.234601 151.490262)
		(width 0.1)
		(layer "In4.Cu")
		(net 150)
	)
	(segment
		(start 141.29526 152.55092)
		(end 141.048091 152.79809)
		(width 0.1)
		(layer "In4.Cu")
		(net 150)
	)
	(segment
		(start 135.900001 147.2775)
		(end 135.900001 147.650001)
		(width 0.1)
		(layer "In4.Cu")
		(net 150)
	)
	(segment
		(start 144.123676 155.379336)
		(end 143.876507 155.626506)
		(width 0.1)
		(layer "In4.Cu")
		(net 150)
	)
	(segment
		(start 144.406834 156.156834)
		(end 144.890501 156.640501)
		(width 0.1)
		(layer "In4.Cu")
		(net 150)
	)
	(segment
		(start 143.629334 156.227227)
		(end 143.629335 156.227228)
		(width 0.1)
		(layer "In4.Cu")
		(net 150)
	)
	(segment
		(start 143.169403 154.919402)
		(end 143.169401 154.919401)
		(width 0.1)
		(layer "In4.Cu")
		(net 150)
	)
	(arc
		(start 141.508023 153.752362)
		(mid 141.434799 153.929138)
		(end 141.508022 154.105915)
		(width 0.1)
		(layer "In4.Cu")
		(net 150)
	)
	(arc
		(start 142.922231 155.520124)
		(mid 143.099008 155.593347)
		(end 143.275784 155.520123)
		(width 0.1)
		(layer "In4.Cu")
		(net 150)
	)
	(arc
		(start 144.123677 155.025784)
		(mid 144.1969 155.202561)
		(end 144.123676 155.379337)
		(width 0.1)
		(layer "In4.Cu")
		(net 150)
	)
	(arc
		(start 139.527497 150.783158)
		(mid 139.704275 150.709936)
		(end 139.881052 150.783159)
		(width 0.1)
		(layer "In4.Cu")
		(net 150)
	)
	(arc
		(start 140.093815 152.691708)
		(mid 140.270592 152.764931)
		(end 140.447368 152.691707)
		(width 0.1)
		(layer "In4.Cu")
		(net 150)
	)
	(arc
		(start 143.629335 155.873674)
		(mid 143.556111 156.05045)
		(end 143.629334 156.227227)
		(width 0.1)
		(layer "In4.Cu")
		(net 150)
	)
	(arc
		(start 138.75 150.5)
		(mid 138.823223 150.676777)
		(end 138.749999 150.853553)
		(width 0.1)
		(layer "In4.Cu")
		(net 150)
	)
	(arc
		(start 139.386711 151.63105)
		(mid 139.313487 151.807826)
		(end 139.38671 151.984603)
		(width 0.1)
		(layer "In4.Cu")
		(net 150)
	)
	(arc
		(start 142.355913 153.611574)
		(mid 142.532691 153.538352)
		(end 142.709468 153.611575)
		(width 0.1)
		(layer "In4.Cu")
		(net 150)
	)
	(arc
		(start 141.648809 152.90447)
		(mid 141.825587 152.831248)
		(end 142.002364 152.904471)
		(width 0.1)
		(layer "In4.Cu")
		(net 150)
	)
	(arc
		(start 143.770121 155.025782)
		(mid 143.946899 154.95256)
		(end 144.123676 155.025783)
		(width 0.1)
		(layer "In4.Cu")
		(net 150)
	)
	(arc
		(start 144.053281 156.156834)
		(mid 144.230058 156.083611)
		(end 144.406834 156.156835)
		(width 0.1)
		(layer "In4.Cu")
		(net 150)
	)
	(arc
		(start 142.709469 153.611576)
		(mid 142.782692 153.788353)
		(end 142.709468 153.965129)
		(width 0.1)
		(layer "In4.Cu")
		(net 150)
	)
	(arc
		(start 142.215127 154.459466)
		(mid 142.141903 154.636242)
		(end 142.215126 154.813019)
		(width 0.1)
		(layer "In4.Cu")
		(net 150)
	)
	(arc
		(start 140.588157 151.490264)
		(mid 140.66138 151.667041)
		(end 140.588156 151.843817)
		(width 0.1)
		(layer "In4.Cu")
		(net 150)
	)
	(arc
		(start 142.002365 152.904472)
		(mid 142.075588 153.081249)
		(end 142.002364 153.258025)
		(width 0.1)
		(layer "In4.Cu")
		(net 150)
	)
	(arc
		(start 142.922231 155.16657)
		(mid 142.849007 155.343346)
		(end 142.92223 155.520123)
		(width 0.1)
		(layer "In4.Cu")
		(net 150)
	)
	(arc
		(start 140.093815 152.338154)
		(mid 140.020591 152.51493)
		(end 140.093814 152.691707)
		(width 0.1)
		(layer "In4.Cu")
		(net 150)
	)
	(arc
		(start 143.063017 154.318678)
		(mid 143.239795 154.245456)
		(end 143.416572 154.318679)
		(width 0.1)
		(layer "In4.Cu")
		(net 150)
	)
	(arc
		(start 138.679606 151.277499)
		(mid 138.856383 151.350722)
		(end 139.033159 151.277498)
		(width 0.1)
		(layer "In4.Cu")
		(net 150)
	)
	(arc
		(start 140.800919 153.045258)
		(mid 140.727695 153.222034)
		(end 140.800918 153.398811)
		(width 0.1)
		(layer "In4.Cu")
		(net 150)
	)
	(arc
		(start 138.679606 150.923946)
		(mid 138.606383 151.100723)
		(end 138.679607 151.277499)
		(width 0.1)
		(layer "In4.Cu")
		(net 150)
	)
	(arc
		(start 139.881053 150.78316)
		(mid 139.954276 150.959937)
		(end 139.881052 151.136713)
		(width 0.1)
		(layer "In4.Cu")
		(net 150)
	)
	(arc
		(start 140.941705 152.197366)
		(mid 141.118483 152.124144)
		(end 141.29526 152.197367)
		(width 0.1)
		(layer "In4.Cu")
		(net 150)
	)
	(arc
		(start 143.629335 156.227228)
		(mid 143.806112 156.300451)
		(end 143.982888 156.227227)
		(width 0.1)
		(layer "In4.Cu")
		(net 150)
	)
	(arc
		(start 141.508023 154.105916)
		(mid 141.6848 154.179139)
		(end 141.861576 154.105915)
		(width 0.1)
		(layer "In4.Cu")
		(net 150)
	)
	(arc
		(start 140.800919 153.398812)
		(mid 140.977696 153.472035)
		(end 141.154472 153.398811)
		(width 0.1)
		(layer "In4.Cu")
		(net 150)
	)
	(arc
		(start 141.295261 152.197368)
		(mid 141.368484 152.374145)
		(end 141.29526 152.550921)
		(width 0.1)
		(layer "In4.Cu")
		(net 150)
	)
	(arc
		(start 143.416573 154.31868)
		(mid 143.489796 154.495457)
		(end 143.416572 154.672233)
		(width 0.1)
		(layer "In4.Cu")
		(net 150)
	)
	(arc
		(start 142.215127 154.81302)
		(mid 142.391904 154.886243)
		(end 142.56868 154.813019)
		(width 0.1)
		(layer "In4.Cu")
		(net 150)
	)
	(arc
		(start 140.234601 151.490262)
		(mid 140.411379 151.41704)
		(end 140.588156 151.490263)
		(width 0.1)
		(layer "In4.Cu")
		(net 150)
	)
	(arc
		(start 139.386711 151.984604)
		(mid 139.563488 152.057827)
		(end 139.740264 151.984603)
		(width 0.1)
		(layer "In4.Cu")
		(net 150)
	)
	(segment
		(start 136.150001 138.8025)
		(end 136.150001 137.7275)
		(width 0.201)
		(layer "F.Cu")
		(net 151)
	)
	(segment
		(start 143.375501 164.302)
		(end 143.875001 163.8025)
		(width 0.256)
		(layer "F.Cu")
		(net 151)
	)
	(via
		(at 143.875001 163.8025)
		(size 0.45)
		(drill 0.1)
		(layers "F.Cu" "B.Cu")
		(net 151)
	)
	(via
		(at 136.150001 137.7275)
		(size 0.45)
		(drill 0.1)
		(layers "F.Cu" "B.Cu")
		(net 151)
	)
	(segment
		(start 136.150501 144.049499)
		(end 135.890501 144.309499)
		(width 0.1)
		(layer "In4.Cu")
		(net 151)
	)
	(segment
		(start 135.375001 148.375001)
		(end 135.75 148.75)
		(width 0.1)
		(layer "In4.Cu")
		(net 151)
	)
	(segment
		(start 136.414615 149.853148)
		(end 136.853146 149.414613)
		(width 0.1)
		(layer "In4.Cu")
		(net 151)
	)
	(segment
		(start 144.250001 157.250001)
		(end 144.250001 163.4265)
		(width 0.1)
		(layer "In4.Cu")
		(net 151)
	)
	(segment
		(start 135.890501 146.637)
		(end 135.375001 147.1525)
		(width 0.1)
		(layer "In4.Cu")
		(net 151)
	)
	(segment
		(start 136.499595 149.061064)
		(end 136.499595 149.061063)
		(width 0.1)
		(layer "In4.Cu")
		(net 151)
	)
	(segment
		(start 135.375001 147.1525)
		(end 135.375001 148.375001)
		(width 0.1)
		(layer "In4.Cu")
		(net 151)
	)
	(segment
		(start 135.890501 144.309499)
		(end 135.890501 146.637)
		(width 0.1)
		(layer "In4.Cu")
		(net 151)
	)
	(segment
		(start 137.121719 150.560251)
		(end 137.121719 150.560252)
		(width 0.1)
		(layer "In4.Cu")
		(net 151)
	)
	(segment
		(start 136.499595 149.061063)
		(end 136.061062 149.499595)
		(width 0.1)
		(layer "In4.Cu")
		(net 151)
	)
	(segment
		(start 137.517762 150.517762)
		(end 137.517761 150.517762)
		(width 0.1)
		(layer "In4.Cu")
		(net 151)
	)
	(segment
		(start 136.150501 137.728)
		(end 136.150501 144.049499)
		(width 0.1)
		(layer "In4.Cu")
		(net 151)
	)
	(segment
		(start 137.121719 150.560252)
		(end 137.164208 150.517762)
		(width 0.1)
		(layer "In4.Cu")
		(net 151)
	)
	(segment
		(start 136.061063 149.853148)
		(end 136.061062 149.853148)
		(width 0.1)
		(layer "In4.Cu")
		(net 151)
	)
	(segment
		(start 137.206701 149.768168)
		(end 136.768166 150.206699)
		(width 0.1)
		(layer "In4.Cu")
		(net 151)
	)
	(segment
		(start 137.206699 149.768167)
		(end 137.206701 149.768168)
		(width 0.1)
		(layer "In4.Cu")
		(net 151)
	)
	(segment
		(start 136.103554 148.750001)
		(end 136.146042 148.70751)
		(width 0.1)
		(layer "In4.Cu")
		(net 151)
	)
	(segment
		(start 144.250001 163.4265)
		(end 143.875001 163.8015)
		(width 0.1)
		(layer "In4.Cu")
		(net 151)
	)
	(segment
		(start 136.768167 150.560252)
		(end 136.768166 150.560252)
		(width 0.1)
		(layer "In4.Cu")
		(net 151)
	)
	(segment
		(start 137.517761 150.517762)
		(end 144.250001 157.250001)
		(width 0.1)
		(layer "In4.Cu")
		(net 151)
	)
	(segment
		(start 136.103553 148.749999)
		(end 136.103554 148.750001)
		(width 0.1)
		(layer "In4.Cu")
		(net 151)
	)
	(segment
		(start 136.499596 148.70751)
		(end 136.499596 148.707511)
		(width 0.1)
		(layer "In4.Cu")
		(net 151)
	)
	(segment
		(start 137.206701 149.414616)
		(end 137.2067 149.414614)
		(width 0.1)
		(layer "In4.Cu")
		(net 151)
	)
	(segment
		(start 143.875001 163.8015)
		(end 143.875001 163.8025)
		(width 0.1)
		(layer "In4.Cu")
		(net 151)
	)
	(segment
		(start 136.414615 149.853147)
		(end 136.414615 149.853148)
		(width 0.1)
		(layer "In4.Cu")
		(net 151)
	)
	(segment
		(start 136.150001 137.7275)
		(end 136.150501 137.728)
		(width 0.1)
		(layer "In4.Cu")
		(net 151)
	)
	(arc
		(start 136.853146 149.414613)
		(mid 137.029925 149.341392)
		(end 137.206701 149.414616)
		(width 0.1)
		(layer "In4.Cu")
		(net 151)
	)
	(arc
		(start 136.146042 148.70751)
		(mid 136.322819 148.634287)
		(end 136.499596 148.70751)
		(width 0.1)
		(layer "In4.Cu")
		(net 151)
	)
	(arc
		(start 136.061062 149.853148)
		(mid 136.237839 149.926371)
		(end 136.414615 149.853147)
		(width 0.1)
		(layer "In4.Cu")
		(net 151)
	)
	(arc
		(start 135.75 148.75)
		(mid 135.926777 148.823223)
		(end 136.103553 148.749999)
		(width 0.1)
		(layer "In4.Cu")
		(net 151)
	)
	(arc
		(start 136.061062 149.499595)
		(mid 135.987839 149.676372)
		(end 136.061063 149.853148)
		(width 0.1)
		(layer "In4.Cu")
		(net 151)
	)
	(arc
		(start 136.768166 150.206699)
		(mid 136.694943 150.383476)
		(end 136.768167 150.560252)
		(width 0.1)
		(layer "In4.Cu")
		(net 151)
	)
	(arc
		(start 136.499596 148.707511)
		(mid 136.572819 148.884288)
		(end 136.499595 149.061064)
		(width 0.1)
		(layer "In4.Cu")
		(net 151)
	)
	(arc
		(start 137.2067 149.414614)
		(mid 137.279923 149.591391)
		(end 137.206699 149.768167)
		(width 0.1)
		(layer "In4.Cu")
		(net 151)
	)
	(arc
		(start 137.164208 150.517762)
		(mid 137.340985 150.444539)
		(end 137.517762 150.517762)
		(width 0.1)
		(layer "In4.Cu")
		(net 151)
	)
	(arc
		(start 136.768166 150.560252)
		(mid 136.944943 150.633475)
		(end 137.121719 150.560251)
		(width 0.1)
		(layer "In4.Cu")
		(net 151)
	)
	(segment
		(start 136.400001 146.2025)
		(end 136.400001 145.1275)
		(width 0.201)
		(layer "F.Cu")
		(net 152)
	)
	(segment
		(start 144.375501 165.301999)
		(end 144.875 164.8025)
		(width 0.256)
		(layer "F.Cu")
		(net 152)
	)
	(via
		(at 136.400001 145.1275)
		(size 0.45)
		(drill 0.1)
		(layers "F.Cu" "B.Cu")
		(net 152)
	)
	(via
		(at 144.875 164.8025)
		(size 0.45)
		(drill 0.1)
		(layers "F.Cu" "B.Cu")
		(net 152)
	)
	(segment
		(start 140.5 150)
		(end 139 150)
		(width 0.1)
		(layer "In4.Cu")
		(net 152)
	)
	(segment
		(start 142.017056 151.972506)
		(end 142.017057 151.972505)
		(width 0.1)
		(layer "In4.Cu")
		(net 152)
	)
	(segment
		(start 143.533172 152.577722)
		(end 143.533171 152.577723)
		(width 0.1)
		(layer "In4.Cu")
		(net 152)
	)
	(segment
		(start 145.300501 154.800501)
		(end 145.25 154.75)
		(width 0.1)
		(layer "In4.Cu")
		(net 152)
	)
	(segment
		(start 142.017057 151.972505)
		(end 142.472503 151.517054)
		(width 0.1)
		(layer "In4.Cu")
		(net 152)
	)
	(segment
		(start 141.309945 151.265395)
		(end 141.309946 151.265394)
		(width 0.1)
		(layer "In4.Cu")
		(net 152)
	)
	(segment
		(start 142.724166 153.033169)
		(end 142.724168 153.03317)
		(width 0.1)
		(layer "In4.Cu")
		(net 152)
	)
	(segment
		(start 142.82606 151.870612)
		(end 142.370609 152.326058)
		(width 0.1)
		(layer "In4.Cu")
		(net 152)
	)
	(segment
		(start 141.309946 151.265394)
		(end 141.765392 150.809943)
		(width 0.1)
		(layer "In4.Cu")
		(net 152)
	)
	(segment
		(start 145.300501 164.376999)
		(end 145.300501 154.800501)
		(width 0.1)
		(layer "In4.Cu")
		(net 152)
	)
	(segment
		(start 143.179614 151.870611)
		(end 143.179614 151.870612)
		(width 0.1)
		(layer "In4.Cu")
		(net 152)
	)
	(segment
		(start 143.431277 153.74028)
		(end 143.431279 153.740281)
		(width 0.1)
		(layer "In4.Cu")
		(net 152)
	)
	(segment
		(start 141.765392 150.456389)
		(end 141.765392 150.45639)
		(width 0.1)
		(layer "In4.Cu")
		(net 152)
	)
	(segment
		(start 143.886725 152.577722)
		(end 143.886725 152.577723)
		(width 0.1)
		(layer "In4.Cu")
		(net 152)
	)
	(segment
		(start 142.472503 151.1635)
		(end 142.472503 151.163501)
		(width 0.1)
		(layer "In4.Cu")
		(net 152)
	)
	(segment
		(start 144.947394 153.991943)
		(end 144.947393 153.991944)
		(width 0.1)
		(layer "In4.Cu")
		(net 152)
	)
	(segment
		(start 144.947393 153.991944)
		(end 144.491942 154.447391)
		(width 0.1)
		(layer "In4.Cu")
		(net 152)
	)
	(segment
		(start 145.300948 153.991945)
		(end 145.300947 153.991944)
		(width 0.1)
		(layer "In4.Cu")
		(net 152)
	)
	(segment
		(start 143.431278 153.386728)
		(end 143.431279 153.386727)
		(width 0.1)
		(layer "In4.Cu")
		(net 152)
	)
	(segment
		(start 143.533171 152.577723)
		(end 143.07772 153.033169)
		(width 0.1)
		(layer "In4.Cu")
		(net 152)
	)
	(segment
		(start 143.431279 153.386727)
		(end 143.886725 152.931276)
		(width 0.1)
		(layer "In4.Cu")
		(net 152)
	)
	(segment
		(start 141.411839 150.456389)
		(end 141.411838 150.45639)
		(width 0.1)
		(layer "In4.Cu")
		(net 152)
	)
	(segment
		(start 142.826061 151.870611)
		(end 142.82606 151.870612)
		(width 0.1)
		(layer "In4.Cu")
		(net 152)
	)
	(segment
		(start 136.400001 147.400001)
		(end 136.400001 145.1275)
		(width 0.1)
		(layer "In4.Cu")
		(net 152)
	)
	(segment
		(start 142.017055 152.326058)
		(end 142.017057 152.326059)
		(width 0.1)
		(layer "In4.Cu")
		(net 152)
	)
	(segment
		(start 139 150)
		(end 136.400001 147.400001)
		(width 0.1)
		(layer "In4.Cu")
		(net 152)
	)
	(segment
		(start 142.724168 152.679616)
		(end 143.179614 152.224165)
		(width 0.1)
		(layer "In4.Cu")
		(net 152)
	)
	(segment
		(start 145.249999 154.396447)
		(end 145.25 154.396446)
		(width 0.1)
		(layer "In4.Cu")
		(net 152)
	)
	(segment
		(start 142.118949 151.163501)
		(end 141.663498 151.618947)
		(width 0.1)
		(layer "In4.Cu")
		(net 152)
	)
	(segment
		(start 142.724167 152.679617)
		(end 142.724168 152.679616)
		(width 0.1)
		(layer "In4.Cu")
		(net 152)
	)
	(segment
		(start 144.593836 153.284833)
		(end 144.593836 153.284834)
		(width 0.1)
		(layer "In4.Cu")
		(net 152)
	)
	(segment
		(start 141.007336 150.507337)
		(end 140.5 150)
		(width 0.1)
		(layer "In4.Cu")
		(net 152)
	)
	(segment
		(start 145.25 154.396446)
		(end 145.300947 154.345498)
		(width 0.1)
		(layer "In4.Cu")
		(net 152)
	)
	(segment
		(start 142.11895 151.1635)
		(end 142.118949 151.163501)
		(width 0.1)
		(layer "In4.Cu")
		(net 152)
	)
	(segment
		(start 144.13839 154.093838)
		(end 144.593836 153.638387)
		(width 0.1)
		(layer "In4.Cu")
		(net 152)
	)
	(segment
		(start 141.007337 150.507338)
		(end 141.007336 150.507337)
		(width 0.1)
		(layer "In4.Cu")
		(net 152)
	)
	(segment
		(start 141.411838 150.45639)
		(end 141.36089 150.507337)
		(width 0.1)
		(layer "In4.Cu")
		(net 152)
	)
	(segment
		(start 144.138388 154.447391)
		(end 144.13839 154.447392)
		(width 0.1)
		(layer "In4.Cu")
		(net 152)
	)
	(segment
		(start 144.138389 154.093839)
		(end 144.13839 154.093838)
		(width 0.1)
		(layer "In4.Cu")
		(net 152)
	)
	(segment
		(start 141.309944 151.618947)
		(end 141.309946 151.618948)
		(width 0.1)
		(layer "In4.Cu")
		(net 152)
	)
	(segment
		(start 144.875 164.8025)
		(end 145.300501 164.376999)
		(width 0.1)
		(layer "In4.Cu")
		(net 152)
	)
	(segment
		(start 144.240282 153.284834)
		(end 143.784831 153.74028)
		(width 0.1)
		(layer "In4.Cu")
		(net 152)
	)
	(segment
		(start 144.240283 153.284833)
		(end 144.240282 153.284834)
		(width 0.1)
		(layer "In4.Cu")
		(net 152)
	)
	(arc
		(start 143.784831 153.74028)
		(mid 143.608054 153.813503)
		(end 143.431277 153.74028)
		(width 0.1)
		(layer "In4.Cu")
		(net 152)
	)
	(arc
		(start 145.25 154.75)
		(mid 145.176776 154.573224)
		(end 145.249999 154.396447)
		(width 0.1)
		(layer "In4.Cu")
		(net 152)
	)
	(arc
		(start 144.593836 153.638387)
		(mid 144.667059 153.46161)
		(end 144.593836 153.284833)
		(width 0.1)
		(layer "In4.Cu")
		(net 152)
	)
	(arc
		(start 142.017057 152.326059)
		(mid 141.943833 152.149283)
		(end 142.017056 151.972506)
		(width 0.1)
		(layer "In4.Cu")
		(net 152)
	)
	(arc
		(start 142.370609 152.326058)
		(mid 142.193832 152.399281)
		(end 142.017055 152.326058)
		(width 0.1)
		(layer "In4.Cu")
		(net 152)
	)
	(arc
		(start 141.765392 150.809943)
		(mid 141.838615 150.633166)
		(end 141.765392 150.456389)
		(width 0.1)
		(layer "In4.Cu")
		(net 152)
	)
	(arc
		(start 143.431279 153.740281)
		(mid 143.358055 153.563505)
		(end 143.431278 153.386728)
		(width 0.1)
		(layer "In4.Cu")
		(net 152)
	)
	(arc
		(start 145.300947 154.345498)
		(mid 145.374171 154.168722)
		(end 145.300948 153.991945)
		(width 0.1)
		(layer "In4.Cu")
		(net 152)
	)
	(arc
		(start 142.724168 153.03317)
		(mid 142.650944 152.856394)
		(end 142.724167 152.679617)
		(width 0.1)
		(layer "In4.Cu")
		(net 152)
	)
	(arc
		(start 141.36089 150.507337)
		(mid 141.184114 150.580561)
		(end 141.007337 150.507338)
		(width 0.1)
		(layer "In4.Cu")
		(net 152)
	)
	(arc
		(start 141.309946 151.618948)
		(mid 141.236722 151.442172)
		(end 141.309945 151.265395)
		(width 0.1)
		(layer "In4.Cu")
		(net 152)
	)
	(arc
		(start 142.472503 151.163501)
		(mid 142.295727 151.090277)
		(end 142.11895 151.1635)
		(width 0.1)
		(layer "In4.Cu")
		(net 152)
	)
	(arc
		(start 144.491942 154.447391)
		(mid 144.315165 154.520614)
		(end 144.138388 154.447391)
		(width 0.1)
		(layer "In4.Cu")
		(net 152)
	)
	(arc
		(start 143.886725 152.577723)
		(mid 143.709949 152.504499)
		(end 143.533172 152.577722)
		(width 0.1)
		(layer "In4.Cu")
		(net 152)
	)
	(arc
		(start 145.300947 153.991944)
		(mid 145.124171 153.91872)
		(end 144.947394 153.991943)
		(width 0.1)
		(layer "In4.Cu")
		(net 152)
	)
	(arc
		(start 143.179614 152.224165)
		(mid 143.252837 152.047388)
		(end 143.179614 151.870611)
		(width 0.1)
		(layer "In4.Cu")
		(net 152)
	)
	(arc
		(start 143.886725 152.931276)
		(mid 143.959948 152.754499)
		(end 143.886725 152.577722)
		(width 0.1)
		(layer "In4.Cu")
		(net 152)
	)
	(arc
		(start 144.13839 154.447392)
		(mid 144.065166 154.270616)
		(end 144.138389 154.093839)
		(width 0.1)
		(layer "In4.Cu")
		(net 152)
	)
	(arc
		(start 141.663498 151.618947)
		(mid 141.486721 151.69217)
		(end 141.309944 151.618947)
		(width 0.1)
		(layer "In4.Cu")
		(net 152)
	)
	(arc
		(start 142.472503 151.517054)
		(mid 142.545726 151.340277)
		(end 142.472503 151.1635)
		(width 0.1)
		(layer "In4.Cu")
		(net 152)
	)
	(arc
		(start 143.07772 153.033169)
		(mid 142.900943 153.106392)
		(end 142.724166 153.033169)
		(width 0.1)
		(layer "In4.Cu")
		(net 152)
	)
	(arc
		(start 144.593836 153.284834)
		(mid 144.41706 153.21161)
		(end 144.240283 153.284833)
		(width 0.1)
		(layer "In4.Cu")
		(net 152)
	)
	(arc
		(start 143.179614 151.870612)
		(mid 143.002838 151.797388)
		(end 142.826061 151.870611)
		(width 0.1)
		(layer "In4.Cu")
		(net 152)
	)
	(arc
		(start 141.765392 150.45639)
		(mid 141.588616 150.383166)
		(end 141.411839 150.456389)
		(width 0.1)
		(layer "In4.Cu")
		(net 152)
	)
	(segment
		(start 136.650001 138.8025)
		(end 136.650001 139.8775)
		(width 0.201)
		(layer "F.Cu")
		(net 153)
	)
	(segment
		(start 144.375501 167.302)
		(end 144.875001 166.8025)
		(width 0.256)
		(layer "F.Cu")
		(net 153)
	)
	(via
		(at 136.650001 139.8775)
		(size 0.45)
		(drill 0.1)
		(layers "F.Cu" "B.Cu")
		(net 153)
	)
	(via
		(at 144.875001 166.8025)
		(size 0.45)
		(drill 0.1)
		(layers "F.Cu" "B.Cu")
		(net 153)
	)
	(segment
		(start 146.4 154.5)
		(end 146.4 161.976501)
		(width 0.1)
		(layer "In4.Cu")
		(net 153)
	)
	(segment
		(start 145.500501 162.576)
		(end 145.500501 166.177)
		(width 0.1)
		(layer "In4.Cu")
		(net 153)
	)
	(segment
		(start 138.075 141.525)
		(end 138.082667 141.525)
		(width 0.1)
		(layer "In4.Cu")
		(net 153)
	)
	(segment
		(start 137.5 146.95)
		(end 137.5 147.75)
		(width 0.1)
		(layer "In4.Cu")
		(net 153)
	)
	(segment
		(start 136.650001 139.8775)
		(end 136.650001 139.900001)
		(width 0.1)
		(layer "In4.Cu")
		(net 153)
	)
	(segment
		(start 146.4 161.976501)
		(end 146.090501 162.286)
		(width 0.1)
		(layer "In4.Cu")
		(net 153)
	)
	(segment
		(start 138.082667 142.025)
		(end 138.075 142.025)
		(width 0.1)
		(layer "In4.Cu")
		(net 153)
	)
	(segment
		(start 138.075 142.025)
		(end 137.567333 142.025)
		(width 0.1)
		(layer "In4.Cu")
		(net 153)
	)
	(segment
		(start 145.500501 166.177)
		(end 144.875001 166.8025)
		(width 0.1)
		(layer "In4.Cu")
		(net 153)
	)
	(segment
		(start 138.082667 143.025)
		(end 138.075 143.025)
		(width 0.1)
		(layer "In4.Cu")
		(net 153)
	)
	(segment
		(start 145.790501 162.286)
		(end 145.500501 162.576)
		(width 0.1)
		(layer "In4.Cu")
		(net 153)
	)
	(segment
		(start 137.825 144.155331)
		(end 136.925001 145.05533)
		(width 0.1)
		(layer "In4.Cu")
		(net 153)
	)
	(segment
		(start 137.5 147.75)
		(end 139.25 149.5)
		(width 0.1)
		(layer "In4.Cu")
		(net 153)
	)
	(segment
		(start 137.825 143.275)
		(end 137.825 144.155331)
		(width 0.1)
		(layer "In4.Cu")
		(net 153)
	)
	(segment
		(start 137.567333 142.525)
		(end 138.082667 142.525)
		(width 0.1)
		(layer "In4.Cu")
		(net 153)
	)
	(segment
		(start 146.090501 162.286)
		(end 145.790501 162.286)
		(width 0.1)
		(layer "In4.Cu")
		(net 153)
	)
	(segment
		(start 136.650001 139.900001)
		(end 137.825 141.075)
		(width 0.1)
		(layer "In4.Cu")
		(net 153)
	)
	(segment
		(start 136.925001 146.375001)
		(end 137.5 146.95)
		(width 0.1)
		(layer "In4.Cu")
		(net 153)
	)
	(segment
		(start 141.4 149.5)
		(end 146.4 154.5)
		(width 0.1)
		(layer "In4.Cu")
		(net 153)
	)
	(segment
		(start 137.825 141.075)
		(end 137.825 141.275)
		(width 0.1)
		(layer "In4.Cu")
		(net 153)
	)
	(segment
		(start 136.925001 145.05533)
		(end 136.925001 146.375001)
		(width 0.1)
		(layer "In4.Cu")
		(net 153)
	)
	(segment
		(start 139.25 149.5)
		(end 141.4 149.5)
		(width 0.1)
		(layer "In4.Cu")
		(net 153)
	)
	(arc
		(start 137.567333 142.025)
		(mid 137.390556 142.098223)
		(end 137.317333 142.275)
		(width 0.1)
		(layer "In4.Cu")
		(net 153)
	)
	(arc
		(start 137.317333 142.275)
		(mid 137.390556 142.451777)
		(end 137.567333 142.525)
		(width 0.1)
		(layer "In4.Cu")
		(net 153)
	)
	(arc
		(start 138.332667 141.775)
		(mid 138.259444 141.951777)
		(end 138.082667 142.025)
		(width 0.1)
		(layer "In4.Cu")
		(net 153)
	)
	(arc
		(start 138.075 143.025)
		(mid 137.898223 143.098223)
		(end 137.825 143.275)
		(width 0.1)
		(layer "In4.Cu")
		(net 153)
	)
	(arc
		(start 138.082667 141.525)
		(mid 138.259444 141.598223)
		(end 138.332667 141.775)
		(width 0.1)
		(layer "In4.Cu")
		(net 153)
	)
	(arc
		(start 137.825 141.275)
		(mid 137.898223 141.451777)
		(end 138.075 141.525)
		(width 0.1)
		(layer "In4.Cu")
		(net 153)
	)
	(arc
		(start 138.332667 142.775)
		(mid 138.259444 142.951777)
		(end 138.082667 143.025)
		(width 0.1)
		(layer "In4.Cu")
		(net 153)
	)
	(arc
		(start 138.082667 142.525)
		(mid 138.259444 142.598223)
		(end 138.332667 142.775)
		(width 0.1)
		(layer "In4.Cu")
		(net 153)
	)
	(segment
		(start 145.375501 165.302)
		(end 145.875001 164.8025)
		(width 0.256)
		(layer "F.Cu")
		(net 154)
	)
	(segment
		(start 137.400001 146.2025)
		(end 137.400001 145.1275)
		(width 0.201)
		(layer "F.Cu")
		(net 154)
	)
	(via
		(at 137.400001 145.1275)
		(size 0.45)
		(drill 0.1)
		(layers "F.Cu" "B.Cu")
		(net 154)
	)
	(via
		(at 145.875001 164.8025)
		(size 0.45)
		(drill 0.1)
		(layers "F.Cu" "B.Cu")
		(net 154)
	)
	(segment
		(start 144.398425 151.498248)
		(end 144.398426 151.498247)
		(width 0.1)
		(layer "In4.Cu")
		(net 154)
	)
	(segment
		(start 145.812645 152.912468)
		(end 145.812646 152.912467)
		(width 0.1)
		(layer "In4.Cu")
		(net 154)
	)
	(segment
		(start 146.390501 162.621334)
		(end 146.725835 162.286)
		(width 0.1)
		(layer "In4.Cu")
		(net 154)
	)
	(segment
		(start 146.519758 153.973133)
		(end 146.519757 153.973132)
		(width 0.1)
		(layer "In4.Cu")
		(net 154)
	)
	(segment
		(start 145.812646 152.912467)
		(end 146.312467 152.412646)
		(width 0.1)
		(layer "In4.Cu")
		(net 154)
	)
	(segment
		(start 146.946446 153.9)
		(end 146.873311 153.973132)
		(width 0.1)
		(layer "In4.Cu")
		(net 154)
	)
	(segment
		(start 144.544694 150.644871)
		(end 144.544693 150.644872)
		(width 0.1)
		(layer "In4.Cu")
		(net 154)
	)
	(segment
		(start 146.946447 153.899999)
		(end 146.946446 153.9)
		(width 0.1)
		(layer "In4.Cu")
		(net 154)
	)
	(segment
		(start 145.105535 152.205358)
		(end 145.105536 152.205357)
		(width 0.1)
		(layer "In4.Cu")
		(net 154)
	)
	(segment
		(start 146.666024 152.766201)
		(end 146.666023 152.766202)
		(width 0.1)
		(layer "In4.Cu")
		(net 154)
	)
	(segment
		(start 147.390501 161.986)
		(end 147.390501 153.990501)
		(width 0.1)
		(layer "In4.Cu")
		(net 154)
	)
	(segment
		(start 143.76445 150.36445)
		(end 142.4 149)
		(width 0.1)
		(layer "In4.Cu")
		(net 154)
	)
	(segment
		(start 145.251804 151.351981)
		(end 145.251803 151.351982)
		(width 0.1)
		(layer "In4.Cu")
		(net 154)
	)
	(segment
		(start 144.398426 151.498247)
		(end 144.898247 150.998426)
		(width 0.1)
		(layer "In4.Cu")
		(net 154)
	)
	(segment
		(start 146.666023 152.766202)
		(end 146.1662 153.266021)
		(width 0.1)
		(layer "In4.Cu")
		(net 154)
	)
	(segment
		(start 146.725835 162.286)
		(end 147.090501 162.286)
		(width 0.1)
		(layer "In4.Cu")
		(net 154)
	)
	(segment
		(start 143.691316 150.791137)
		(end 143.76445 150.718004)
		(width 0.1)
		(layer "In4.Cu")
		(net 154)
	)
	(segment
		(start 145.958914 152.059091)
		(end 145.958913 152.059092)
		(width 0.1)
		(layer "In4.Cu")
		(net 154)
	)
	(segment
		(start 147.090501 162.286)
		(end 147.390501 161.986)
		(width 0.1)
		(layer "In4.Cu")
		(net 154)
	)
	(segment
		(start 145.251803 151.351982)
		(end 144.75198 151.851801)
		(width 0.1)
		(layer "In4.Cu")
		(net 154)
	)
	(segment
		(start 146.519756 153.619579)
		(end 146.519757 153.619578)
		(width 0.1)
		(layer "In4.Cu")
		(net 154)
	)
	(segment
		(start 143.764451 150.364451)
		(end 143.76445 150.36445)
		(width 0.1)
		(layer "In4.Cu")
		(net 154)
	)
	(segment
		(start 142.4 149)
		(end 139.75 149)
		(width 0.1)
		(layer "In4.Cu")
		(net 154)
	)
	(segment
		(start 137.9 147.15)
		(end 137.9 145.627499)
		(width 0.1)
		(layer "In4.Cu")
		(net 154)
	)
	(segment
		(start 145.105536 152.205357)
		(end 145.605357 151.705536)
		(width 0.1)
		(layer "In4.Cu")
		(net 154)
	)
	(segment
		(start 137.9 145.627499)
		(end 137.400001 145.1275)
		(width 0.1)
		(layer "In4.Cu")
		(net 154)
	)
	(segment
		(start 144.544693 150.644872)
		(end 144.04487 151.144691)
		(width 0.1)
		(layer "In4.Cu")
		(net 154)
	)
	(segment
		(start 143.691315 150.791138)
		(end 143.691316 150.791137)
		(width 0.1)
		(layer "In4.Cu")
		(net 154)
	)
	(segment
		(start 145.958913 152.059092)
		(end 145.45909 152.558911)
		(width 0.1)
		(layer "In4.Cu")
		(net 154)
	)
	(segment
		(start 146.390501 164.287)
		(end 146.390501 162.621334)
		(width 0.1)
		(layer "In4.Cu")
		(net 154)
	)
	(segment
		(start 139.75 149)
		(end 137.9 147.15)
		(width 0.1)
		(layer "In4.Cu")
		(net 154)
	)
	(segment
		(start 146.519757 153.619578)
		(end 147.019577 153.119756)
		(width 0.1)
		(layer "In4.Cu")
		(net 154)
	)
	(segment
		(start 147.390501 153.990501)
		(end 147.3 153.9)
		(width 0.1)
		(layer "In4.Cu")
		(net 154)
	)
	(segment
		(start 145.875001 164.8025)
		(end 146.390501 164.287)
		(width 0.1)
		(layer "In4.Cu")
		(net 154)
	)
	(arc
		(start 147.019577 152.766202)
		(mid 146.842801 152.692978)
		(end 146.666024 152.766201)
		(width 0.1)
		(layer "In4.Cu")
		(net 154)
	)
	(arc
		(start 146.312467 152.059092)
		(mid 146.135691 151.985868)
		(end 145.958914 152.059091)
		(width 0.1)
		(layer "In4.Cu")
		(net 154)
	)
	(arc
		(start 146.1662 153.266021)
		(mid 145.989423 153.339244)
		(end 145.812646 153.266021)
		(width 0.1)
		(layer "In4.Cu")
		(net 154)
	)
	(arc
		(start 145.812646 153.266021)
		(mid 145.739422 153.089245)
		(end 145.812645 152.912468)
		(width 0.1)
		(layer "In4.Cu")
		(net 154)
	)
	(arc
		(start 147.019577 153.119756)
		(mid 147.0928 152.942979)
		(end 147.019577 152.766202)
		(width 0.1)
		(layer "In4.Cu")
		(net 154)
	)
	(arc
		(start 144.75198 151.851801)
		(mid 144.575203 151.925024)
		(end 144.398426 151.851801)
		(width 0.1)
		(layer "In4.Cu")
		(net 154)
	)
	(arc
		(start 146.519757 153.973132)
		(mid 146.446533 153.796356)
		(end 146.519756 153.619579)
		(width 0.1)
		(layer "In4.Cu")
		(net 154)
	)
	(arc
		(start 145.105536 152.558911)
		(mid 145.032312 152.382135)
		(end 145.105535 152.205358)
		(width 0.1)
		(layer "In4.Cu")
		(net 154)
	)
	(arc
		(start 143.76445 150.718004)
		(mid 143.837674 150.541228)
		(end 143.764451 150.364451)
		(width 0.1)
		(layer "In4.Cu")
		(net 154)
	)
	(arc
		(start 144.898247 150.998426)
		(mid 144.97147 150.821649)
		(end 144.898247 150.644872)
		(width 0.1)
		(layer "In4.Cu")
		(net 154)
	)
	(arc
		(start 143.691316 151.144691)
		(mid 143.618092 150.967915)
		(end 143.691315 150.791138)
		(width 0.1)
		(layer "In4.Cu")
		(net 154)
	)
	(arc
		(start 146.873311 153.973132)
		(mid 146.696535 154.046356)
		(end 146.519758 153.973133)
		(width 0.1)
		(layer "In4.Cu")
		(net 154)
	)
	(arc
		(start 146.312467 152.412646)
		(mid 146.38569 152.235869)
		(end 146.312467 152.059092)
		(width 0.1)
		(layer "In4.Cu")
		(net 154)
	)
	(arc
		(start 145.605357 151.351982)
		(mid 145.428581 151.278758)
		(end 145.251804 151.351981)
		(width 0.1)
		(layer "In4.Cu")
		(net 154)
	)
	(arc
		(start 145.605357 151.705536)
		(mid 145.67858 151.528759)
		(end 145.605357 151.351982)
		(width 0.1)
		(layer "In4.Cu")
		(net 154)
	)
	(arc
		(start 144.898247 150.644872)
		(mid 144.721471 150.571648)
		(end 144.544694 150.644871)
		(width 0.1)
		(layer "In4.Cu")
		(net 154)
	)
	(arc
		(start 144.398426 151.851801)
		(mid 144.325202 151.675025)
		(end 144.398425 151.498248)
		(width 0.1)
		(layer "In4.Cu")
		(net 154)
	)
	(arc
		(start 144.04487 151.144691)
		(mid 143.868093 151.217914)
		(end 143.691316 151.144691)
		(width 0.1)
		(layer "In4.Cu")
		(net 154)
	)
	(arc
		(start 145.45909 152.558911)
		(mid 145.282313 152.632134)
		(end 145.105536 152.558911)
		(width 0.1)
		(layer "In4.Cu")
		(net 154)
	)
	(arc
		(start 147.3 153.9)
		(mid 147.123224 153.826776)
		(end 146.946447 153.899999)
		(width 0.1)
		(layer "In4.Cu")
		(net 154)
	)
	(segment
		(start 145.375501 166.302)
		(end 145.875001 165.8025)
		(width 0.256)
		(layer "F.Cu")
		(net 155)
	)
	(segment
		(start 137.650001 138.8025)
		(end 137.650001 139.8775)
		(width 0.201)
		(layer "F.Cu")
		(net 155)
	)
	(via
		(at 137.650001 139.8775)
		(size 0.45)
		(drill 0.1)
		(layers "F.Cu" "B.Cu")
		(net 155)
	)
	(via
		(at 145.875001 165.8025)
		(size 0.45)
		(drill 0.1)
		(layers "F.Cu" "B.Cu")
		(net 155)
	)
	(segment
		(start 148.500001 161.2765)
		(end 148.500001 153.800001)
		(width 0.1)
		(layer "In4.Cu")
		(net 155)
	)
	(segment
		(start 139.044622 145)
		(end 139 145)
		(width 0.1)
		(layer "In4.Cu")
		(net 155)
	)
	(segment
		(start 147.090501 164.286)
		(end 147.390501 163.986)
		(width 0.1)
		(layer "In4.Cu")
		(net 155)
	)
	(segment
		(start 146.202876 165.273625)
		(end 146.390501 165.086)
		(width 0.1)
		(layer "In4.Cu")
		(net 155)
	)
	(segment
		(start 143.2 148.5)
		(end 139.904501 148.5)
		(width 0.1)
		(layer "In4.Cu")
		(net 155)
	)
	(segment
		(start 147.390501 162.586)
		(end 147.690501 162.286)
		(width 0.1)
		(layer "In4.Cu")
		(net 155)
	)
	(segment
		(start 139 145)
		(end 138.455378 145)
		(width 0.1)
		(layer "In4.Cu")
		(net 155)
	)
	(segment
		(start 146.390501 164.671334)
		(end 146.775835 164.286)
		(width 0.1)
		(layer "In4.Cu")
		(net 155)
	)
	(segment
		(start 148.090501 162.286)
		(end 148.390501 161.986)
		(width 0.1)
		(layer "In4.Cu")
		(net 155)
	)
	(segment
		(start 147.390501 163.986)
		(end 147.390501 162.586)
		(width 0.1)
		(layer "In4.Cu")
		(net 155)
	)
	(segment
		(start 139.044622 144)
		(end 139 144)
		(width 0.1)
		(layer "In4.Cu")
		(net 155)
	)
	(segment
		(start 145.978126 165.273625)
		(end 146.202876 165.273625)
		(width 0.1)
		(layer "In4.Cu")
		(net 155)
	)
	(segment
		(start 139 145.5)
		(end 139.044622 145.5)
		(width 0.1)
		(layer "In4.Cu")
		(net 155)
	)
	(segment
		(start 146.390501 165.086)
		(end 146.390501 164.671334)
		(width 0.1)
		(layer "In4.Cu")
		(net 155)
	)
	(segment
		(start 147.690501 162.286)
		(end 148.090501 162.286)
		(width 0.1)
		(layer "In4.Cu")
		(net 155)
	)
	(segment
		(start 145.875001 165.8025)
		(end 145.875001 165.37675)
		(width 0.1)
		(layer "In4.Cu")
		(net 155)
	)
	(segment
		(start 138.75 143.75)
		(end 138.75 140.977499)
		(width 0.1)
		(layer "In4.Cu")
		(net 155)
	)
	(segment
		(start 138.75 147.345499)
		(end 138.75 145.75)
		(width 0.1)
		(layer "In4.Cu")
		(net 155)
	)
	(segment
		(start 145.875001 165.37675)
		(end 145.978126 165.273625)
		(width 0.1)
		(layer "In4.Cu")
		(net 155)
	)
	(segment
		(start 146.775835 164.286)
		(end 147.090501 164.286)
		(width 0.1)
		(layer "In4.Cu")
		(net 155)
	)
	(segment
		(start 138.455378 144.5)
		(end 139.044622 144.5)
		(width 0.1)
		(layer "In4.Cu")
		(net 155)
	)
	(segment
		(start 148.390501 161.986)
		(end 148.390501 161.386)
		(width 0.1)
		(layer "In4.Cu")
		(net 155)
	)
	(segment
		(start 148.390501 161.386)
		(end 148.500001 161.2765)
		(width 0.1)
		(layer "In4.Cu")
		(net 155)
	)
	(segment
		(start 138.75 140.977499)
		(end 137.650001 139.8775)
		(width 0.1)
		(layer "In4.Cu")
		(net 155)
	)
	(segment
		(start 139.904501 148.5)
		(end 138.75 147.345499)
		(width 0.1)
		(layer "In4.Cu")
		(net 155)
	)
	(segment
		(start 148.500001 153.800001)
		(end 143.2 148.5)
		(width 0.1)
		(layer "In4.Cu")
		(net 155)
	)
	(arc
		(start 138.205378 144.75)
		(mid 138.278601 144.573223)
		(end 138.455378 144.5)
		(width 0.1)
		(layer "In4.Cu")
		(net 155)
	)
	(arc
		(start 138.75 145.75)
		(mid 138.823223 145.573223)
		(end 139 145.5)
		(width 0.1)
		(layer "In4.Cu")
		(net 155)
	)
	(arc
		(start 139 144)
		(mid 138.823223 143.926777)
		(end 138.75 143.75)
		(width 0.1)
		(layer "In4.Cu")
		(net 155)
	)
	(arc
		(start 139.044622 144.5)
		(mid 139.221399 144.426777)
		(end 139.294622 144.25)
		(width 0.1)
		(layer "In4.Cu")
		(net 155)
	)
	(arc
		(start 139.294622 145.25)
		(mid 139.221399 145.073223)
		(end 139.044622 145)
		(width 0.1)
		(layer "In4.Cu")
		(net 155)
	)
	(arc
		(start 139.044622 145.5)
		(mid 139.221399 145.426777)
		(end 139.294622 145.25)
		(width 0.1)
		(layer "In4.Cu")
		(net 155)
	)
	(arc
		(start 139.294622 144.25)
		(mid 139.221399 144.073223)
		(end 139.044622 144)
		(width 0.1)
		(layer "In4.Cu")
		(net 155)
	)
	(arc
		(start 138.455378 145)
		(mid 138.278601 144.926777)
		(end 138.205378 144.75)
		(width 0.1)
		(layer "In4.Cu")
		(net 155)
	)
	(segment
		(start 145.375501 167.302)
		(end 145.875001 166.8025)
		(width 0.256)
		(layer "F.Cu")
		(net 156)
	)
	(segment
		(start 139.400001 146.2025)
		(end 139.400001 147.277498)
		(width 0.201)
		(layer "F.Cu")
		(net 156)
	)
	(via
		(at 139.400001 147.2775)
		(size 0.45)
		(drill 0.1)
		(layers "F.Cu" "B.Cu")
		(net 156)
	)
	(via
		(at 145.875001 166.8025)
		(size 0.45)
		(drill 0.1)
		(layers "F.Cu" "B.Cu")
		(net 156)
	)
	(segment
		(start 147.390501 164.586)
		(end 147.390501 164.986)
		(width 0.1)
		(layer "In4.Cu")
		(net 156)
	)
	(segment
		(start 145.442809 149.024955)
		(end 145.233883 149.233882)
		(width 0.1)
		(layer "In4.Cu")
		(net 156)
	)
	(segment
		(start 146.390501 165.586)
		(end 146.390501 166.287)
		(width 0.1)
		(layer "In4.Cu")
		(net 156)
	)
	(segment
		(start 147.105167 165.271334)
		(end 146.705167 165.271334)
		(width 0.1)
		(layer "In4.Cu")
		(net 156)
	)
	(segment
		(start 146.439161 151.210568)
		(end 146.439162 151.210569)
		(width 0.1)
		(layer "In4.Cu")
		(net 156)
	)
	(segment
		(start 145.940985 149.940985)
		(end 145.732058 150.149911)
		(width 0.1)
		(layer "In4.Cu")
		(net 156)
	)
	(segment
		(start 149.090501 162.286)
		(end 148.790501 162.286)
		(width 0.1)
		(layer "In4.Cu")
		(net 156)
	)
	(segment
		(start 139.400001 147.2775)
		(end 140.098501 147.976)
		(width 0.1)
		(layer "In4.Cu")
		(net 156)
	)
	(segment
		(start 146.390501 166.287)
		(end 145.875001 166.8025)
		(width 0.1)
		(layer "In4.Cu")
		(net 156)
	)
	(segment
		(start 146.792715 151.210569)
		(end 147.210566 150.792713)
		(width 0.1)
		(layer "In4.Cu")
		(net 156)
	)
	(segment
		(start 146.792715 151.210568)
		(end 146.792715 151.210569)
		(width 0.1)
		(layer "In4.Cu")
		(net 156)
	)
	(segment
		(start 146.857017 150.08561)
		(end 146.857018 150.085611)
		(width 0.1)
		(layer "In4.Cu")
		(net 156)
	)
	(segment
		(start 145.442809 148.671402)
		(end 145.44281 148.671403)
		(width 0.1)
		(layer "In4.Cu")
		(net 156)
	)
	(segment
		(start 145.378507 149.796361)
		(end 145.796358 149.378505)
		(width 0.1)
		(layer "In4.Cu")
		(net 156)
	)
	(segment
		(start 149.390501 161.986)
		(end 149.090501 162.286)
		(width 0.1)
		(layer "In4.Cu")
		(net 156)
	)
	(segment
		(start 146.149913 149.378506)
		(end 146.149914 149.378507)
		(width 0.1)
		(layer "In4.Cu")
		(net 156)
	)
	(segment
		(start 147.564121 151.146267)
		(end 147.531971 151.178418)
		(width 0.1)
		(layer "In4.Cu")
		(net 156)
	)
	(segment
		(start 148.390501 164.086)
		(end 148.190501 164.286)
		(width 0.1)
		(layer "In4.Cu")
		(net 156)
	)
	(segment
		(start 145.732057 150.503464)
		(end 145.732058 150.503465)
		(width 0.1)
		(layer "In4.Cu")
		(net 156)
	)
	(segment
		(start 146.857017 150.439164)
		(end 146.857017 150.439163)
		(width 0.1)
		(layer "In4.Cu")
		(net 156)
	)
	(segment
		(start 147.564121 151.146268)
		(end 147.564121 151.146267)
		(width 0.1)
		(layer "In4.Cu")
		(net 156)
	)
	(segment
		(start 144.671402 149.089255)
		(end 144.671402 149.089256)
		(width 0.1)
		(layer "In4.Cu")
		(net 156)
	)
	(segment
		(start 145.378507 149.79636)
		(end 145.378507 149.796361)
		(width 0.1)
		(layer "In4.Cu")
		(net 156)
	)
	(segment
		(start 145.233881 149.233881)
		(end 145.024954 149.442807)
		(width 0.1)
		(layer "In4.Cu")
		(net 156)
	)
	(segment
		(start 146.149913 149.732059)
		(end 145.940987 149.940986)
		(width 0.1)
		(layer "In4.Cu")
		(net 156)
	)
	(segment
		(start 149.390501 153.390501)
		(end 149.390501 161.986)
		(width 0.1)
		(layer "In4.Cu")
		(net 156)
	)
	(segment
		(start 148.790501 162.286)
		(end 148.390501 162.686)
		(width 0.1)
		(layer "In4.Cu")
		(net 156)
	)
	(segment
		(start 148.190501 164.286)
		(end 147.690501 164.286)
		(width 0.1)
		(layer "In4.Cu")
		(net 156)
	)
	(segment
		(start 146.085611 150.503465)
		(end 146.503462 150.085609)
		(width 0.1)
		(layer "In4.Cu")
		(net 156)
	)
	(segment
		(start 145.233883 149.233882)
		(end 145.233881 149.233881)
		(width 0.1)
		(layer "In4.Cu")
		(net 156)
	)
	(segment
		(start 148.390501 162.686)
		(end 148.390501 164.086)
		(width 0.1)
		(layer "In4.Cu")
		(net 156)
	)
	(segment
		(start 145.024953 149.79636)
		(end 145.024954 149.796361)
		(width 0.1)
		(layer "In4.Cu")
		(net 156)
	)
	(segment
		(start 147.564121 150.792714)
		(end 147.564122 150.792715)
		(width 0.1)
		(layer "In4.Cu")
		(net 156)
	)
	(segment
		(start 147.53197 151.53197)
		(end 149.390501 153.390501)
		(width 0.1)
		(layer "In4.Cu")
		(net 156)
	)
	(segment
		(start 140.098501 147.976)
		(end 143.976 147.976)
		(width 0.1)
		(layer "In4.Cu")
		(net 156)
	)
	(segment
		(start 146.648091 150.64809)
		(end 146.648089 150.648089)
		(width 0.1)
		(layer "In4.Cu")
		(net 156)
	)
	(segment
		(start 146.705167 165.271334)
		(end 146.390501 165.586)
		(width 0.1)
		(layer "In4.Cu")
		(net 156)
	)
	(segment
		(start 143.976 147.976)
		(end 144.35 148.35)
		(width 0.1)
		(layer "In4.Cu")
		(net 156)
	)
	(segment
		(start 144.671402 149.089256)
		(end 145.089254 148.671401)
		(width 0.1)
		(layer "In4.Cu")
		(net 156)
	)
	(segment
		(start 144.349999 148.703553)
		(end 144.35 148.703553)
		(width 0.1)
		(layer "In4.Cu")
		(net 156)
	)
	(segment
		(start 147.690501 164.286)
		(end 147.390501 164.586)
		(width 0.1)
		(layer "In4.Cu")
		(net 156)
	)
	(segment
		(start 146.648089 150.648089)
		(end 146.439162 150.857015)
		(width 0.1)
		(layer "In4.Cu")
		(net 156)
	)
	(segment
		(start 146.085611 150.503464)
		(end 146.085611 150.503465)
		(width 0.1)
		(layer "In4.Cu")
		(net 156)
	)
	(segment
		(start 146.857017 150.439163)
		(end 146.648091 150.64809)
		(width 0.1)
		(layer "In4.Cu")
		(net 156)
	)
	(segment
		(start 144.31785 149.089256)
		(end 144.317849 149.089256)
		(width 0.1)
		(layer "In4.Cu")
		(net 156)
	)
	(segment
		(start 145.940987 149.940986)
		(end 145.940985 149.940985)
		(width 0.1)
		(layer "In4.Cu")
		(net 156)
	)
	(segment
		(start 146.149913 149.73206)
		(end 146.149913 149.732059)
		(width 0.1)
		(layer "In4.Cu")
		(net 156)
	)
	(segment
		(start 145.442809 149.024956)
		(end 145.442809 149.024955)
		(width 0.1)
		(layer "In4.Cu")
		(net 156)
	)
	(segment
		(start 147.531972 151.531971)
		(end 147.53197 151.53197)
		(width 0.1)
		(layer "In4.Cu")
		(net 156)
	)
	(segment
		(start 144.35 148.703553)
		(end 144.317849 148.735703)
		(width 0.1)
		(layer "In4.Cu")
		(net 156)
	)
	(segment
		(start 147.390501 164.986)
		(end 147.105167 165.271334)
		(width 0.1)
		(layer "In4.Cu")
		(net 156)
	)
	(arc
		(start 147.564122 150.792715)
		(mid 147.637345 150.969492)
		(end 147.564121 151.146268)
		(width 0.1)
		(layer "In4.Cu")
		(net 156)
	)
	(arc
		(start 145.732058 150.149911)
		(mid 145.658834 150.326687)
		(end 145.732057 150.503464)
		(width 0.1)
		(layer "In4.Cu")
		(net 156)
	)
	(arc
		(start 144.35 148.35)
		(mid 144.423223 148.526777)
		(end 144.349999 148.703553)
		(width 0.1)
		(layer "In4.Cu")
		(net 156)
	)
	(arc
		(start 146.149914 149.378507)
		(mid 146.223137 149.555284)
		(end 146.149913 149.73206)
		(width 0.1)
		(layer "In4.Cu")
		(net 156)
	)
	(arc
		(start 146.439162 151.210569)
		(mid 146.615939 151.283792)
		(end 146.792715 151.210568)
		(width 0.1)
		(layer "In4.Cu")
		(net 156)
	)
	(arc
		(start 147.531971 151.178418)
		(mid 147.458748 151.355195)
		(end 147.531972 151.531971)
		(width 0.1)
		(layer "In4.Cu")
		(net 156)
	)
	(arc
		(start 145.024954 149.442807)
		(mid 144.95173 149.619583)
		(end 145.024953 149.79636)
		(width 0.1)
		(layer "In4.Cu")
		(net 156)
	)
	(arc
		(start 146.503462 150.085609)
		(mid 146.68024 150.012387)
		(end 146.857017 150.08561)
		(width 0.1)
		(layer "In4.Cu")
		(net 156)
	)
	(arc
		(start 145.732058 150.503465)
		(mid 145.908835 150.576688)
		(end 146.085611 150.503464)
		(width 0.1)
		(layer "In4.Cu")
		(net 156)
	)
	(arc
		(start 145.024954 149.796361)
		(mid 145.201731 149.869584)
		(end 145.378507 149.79636)
		(width 0.1)
		(layer "In4.Cu")
		(net 156)
	)
	(arc
		(start 145.796358 149.378505)
		(mid 145.973136 149.305283)
		(end 146.149913 149.378506)
		(width 0.1)
		(layer "In4.Cu")
		(net 156)
	)
	(arc
		(start 146.439162 150.857015)
		(mid 146.365938 151.033791)
		(end 146.439161 151.210568)
		(width 0.1)
		(layer "In4.Cu")
		(net 156)
	)
	(arc
		(start 145.44281 148.671403)
		(mid 145.516033 148.84818)
		(end 145.442809 149.024956)
		(width 0.1)
		(layer "In4.Cu")
		(net 156)
	)
	(arc
		(start 145.089254 148.671401)
		(mid 145.266032 148.598179)
		(end 145.442809 148.671402)
		(width 0.1)
		(layer "In4.Cu")
		(net 156)
	)
	(arc
		(start 147.210566 150.792713)
		(mid 147.387344 150.719491)
		(end 147.564121 150.792714)
		(width 0.1)
		(layer "In4.Cu")
		(net 156)
	)
	(arc
		(start 146.857018 150.085611)
		(mid 146.930241 150.262388)
		(end 146.857017 150.439164)
		(width 0.1)
		(layer "In4.Cu")
		(net 156)
	)
	(arc
		(start 144.317849 148.735703)
		(mid 144.244626 148.91248)
		(end 144.31785 149.089256)
		(width 0.1)
		(layer "In4.Cu")
		(net 156)
	)
	(arc
		(start 144.317849 149.089256)
		(mid 144.494626 149.162479)
		(end 144.671402 149.089255)
		(width 0.1)
		(layer "In4.Cu")
		(net 156)
	)
	(segment
		(start 140.42 147.292427)
		(end 140.375001 147.337426)
		(width 0.26)
		(layer "F.Cu")
		(net 157)
	)
	(segment
		(start 141.375501 166.302)
		(end 141.875001 165.8025)
		(width 0.256)
		(layer "F.Cu")
		(net 157)
	)
	(segment
		(start 140.400001 146.8025)
		(end 140.420001 146.8225)
		(width 0.26)
		(layer "F.Cu")
		(net 157)
	)
	(segment
		(start 140.400001 146.2025)
		(end 140.400001 146.8025)
		(width 0.26)
		(layer "F.Cu")
		(net 157)
	)
	(segment
		(start 140.420001 146.8225)
		(end 140.42 147.292427)
		(width 0.26)
		(layer "F.Cu")
		(net 157)
	)
	(via
		(at 140.375001 147.337426)
		(size 0.45)
		(drill 0.1)
		(layers "F.Cu" "B.Cu")
		(net 157)
	)
	(via
		(at 141.875001 165.8025)
		(size 0.45)
		(drill 0.1)
		(layers "F.Cu" "B.Cu")
		(net 157)
	)
	(segment
		(start 140.550001 147.512426)
		(end 140.375001 147.337426)
		(width 0.1)
		(layer "In2.Cu")
		(net 157)
	)
	(segment
		(start 143.258 151.819)
		(end 143.258 151.176921)
		(width 0.1)
		(layer "In2.Cu")
		(net 157)
	)
	(segment
		(start 142.275001 158.641577)
		(end 143.258 157.658578)
		(width 0.1)
		(layer "In2.Cu")
		(net 157)
	)
	(segment
		(start 142.871367 153.469)
		(end 143.844633 153.469)
		(width 0.1)
		(layer "In2.Cu")
		(net 157)
	)
	(segment
		(start 141.275001 164.511078)
		(end 141.583579 164.2025)
		(width 0.1)
		(layer "In2.Cu")
		(net 157)
	)
	(segment
		(start 141.875001 165.8025)
		(end 141.875001 165.5045)
		(width 0.1)
		(layer "In2.Cu")
		(net 157)
	)
	(segment
		(start 141.583579 164.2025)
		(end 142.083579 164.2025)
		(width 0.1)
		(layer "In2.Cu")
		(net 157)
	)
	(segment
		(start 141.773001 165.4025)
		(end 141.560913 165.4025)
		(width 0.1)
		(layer "In2.Cu")
		(net 157)
	)
	(segment
		(start 141.275001 165.116588)
		(end 141.275001 164.511078)
		(width 0.1)
		(layer "In2.Cu")
		(net 157)
	)
	(segment
		(start 143.258 157.658578)
		(end 143.258 157.319)
		(width 0.1)
		(layer "In2.Cu")
		(net 157)
	)
	(segment
		(start 142.871367 154.469)
		(end 143.844633 154.469)
		(width 0.1)
		(layer "In2.Cu")
		(net 157)
	)
	(segment
		(start 142.871367 156.169)
		(end 143.844633 156.169)
		(width 0.1)
		(layer "In2.Cu")
		(net 157)
	)
	(segment
		(start 142.275001 164.011078)
		(end 142.275001 158.641577)
		(width 0.1)
		(layer "In2.Cu")
		(net 157)
	)
	(segment
		(start 142.871367 155.469)
		(end 143.844633 155.469)
		(width 0.1)
		(layer "In2.Cu")
		(net 157)
	)
	(segment
		(start 141.875001 165.5045)
		(end 141.773001 165.4025)
		(width 0.1)
		(layer "In2.Cu")
		(net 157)
	)
	(segment
		(start 142.871367 155.169)
		(end 143.844633 155.169)
		(width 0.1)
		(layer "In2.Cu")
		(net 157)
	)
	(segment
		(start 143.258 151.176921)
		(end 140.550001 148.468922)
		(width 0.1)
		(layer "In2.Cu")
		(net 157)
	)
	(segment
		(start 143.108 157.169)
		(end 142.871367 157.169)
		(width 0.1)
		(layer "In2.Cu")
		(net 157)
	)
	(segment
		(start 141.560913 165.4025)
		(end 141.275001 165.116588)
		(width 0.1)
		(layer "In2.Cu")
		(net 157)
	)
	(segment
		(start 140.550001 148.468922)
		(end 140.550001 147.512426)
		(width 0.1)
		(layer "In2.Cu")
		(net 157)
	)
	(segment
		(start 142.871367 154.169)
		(end 143.844633 154.169)
		(width 0.1)
		(layer "In2.Cu")
		(net 157)
	)
	(segment
		(start 143.844633 152.169)
		(end 143.608 152.169)
		(width 0.1)
		(layer "In2.Cu")
		(net 157)
	)
	(segment
		(start 142.871367 156.469)
		(end 143.844633 156.469)
		(width 0.1)
		(layer "In2.Cu")
		(net 157)
	)
	(segment
		(start 142.871367 153.169)
		(end 143.844633 153.169)
		(width 0.1)
		(layer "In2.Cu")
		(net 157)
	)
	(segment
		(start 142.083579 164.2025)
		(end 142.275001 164.011078)
		(width 0.1)
		(layer "In2.Cu")
		(net 157)
	)
	(segment
		(start 142.871367 152.469)
		(end 143.844633 152.469)
		(width 0.1)
		(layer "In2.Cu")
		(net 157)
	)
	(arc
		(start 142.521367 152.819)
		(mid 142.62388 152.571513)
		(end 142.871367 152.469)
		(width 0.1)
		(layer "In2.Cu")
		(net 157)
	)
	(arc
		(start 143.994633 153.319)
		(mid 143.950699 153.212934)
		(end 143.844633 153.169)
		(width 0.1)
		(layer "In2.Cu")
		(net 157)
	)
	(arc
		(start 143.844633 152.469)
		(mid 143.950699 152.425066)
		(end 143.994633 152.319)
		(width 0.1)
		(layer "In2.Cu")
		(net 157)
	)
	(arc
		(start 142.871367 154.169)
		(mid 142.62388 154.066487)
		(end 142.521367 153.819)
		(width 0.1)
		(layer "In2.Cu")
		(net 157)
	)
	(arc
		(start 142.871367 153.169)
		(mid 142.62388 153.066487)
		(end 142.521367 152.819)
		(width 0.1)
		(layer "In2.Cu")
		(net 157)
	)
	(arc
		(start 143.844633 155.469)
		(mid 143.950699 155.425066)
		(end 143.994633 155.319)
		(width 0.1)
		(layer "In2.Cu")
		(net 157)
	)
	(arc
		(start 143.608 152.169)
		(mid 143.360513 152.066487)
		(end 143.258 151.819)
		(width 0.1)
		(layer "In2.Cu")
		(net 157)
	)
	(arc
		(start 143.994633 156.319)
		(mid 143.950699 156.212934)
		(end 143.844633 156.169)
		(width 0.1)
		(layer "In2.Cu")
		(net 157)
	)
	(arc
		(start 143.844633 153.469)
		(mid 143.950699 153.425066)
		(end 143.994633 153.319)
		(width 0.1)
		(layer "In2.Cu")
		(net 157)
	)
	(arc
		(start 142.871367 157.169)
		(mid 142.62388 157.066487)
		(end 142.521367 156.819)
		(width 0.1)
		(layer "In2.Cu")
		(net 157)
	)
	(arc
		(start 143.994633 152.319)
		(mid 143.950699 152.212934)
		(end 143.844633 152.169)
		(width 0.1)
		(layer "In2.Cu")
		(net 157)
	)
	(arc
		(start 142.521367 153.819)
		(mid 142.62388 153.571513)
		(end 142.871367 153.469)
		(width 0.1)
		(layer "In2.Cu")
		(net 157)
	)
	(arc
		(start 142.521367 155.819)
		(mid 142.62388 155.571513)
		(end 142.871367 155.469)
		(width 0.1)
		(layer "In2.Cu")
		(net 157)
	)
	(arc
		(start 143.994633 154.319)
		(mid 143.950699 154.212934)
		(end 143.844633 154.169)
		(width 0.1)
		(layer "In2.Cu")
		(net 157)
	)
	(arc
		(start 143.994633 155.319)
		(mid 143.950699 155.212934)
		(end 143.844633 155.169)
		(width 0.1)
		(layer "In2.Cu")
		(net 157)
	)
	(arc
		(start 142.521367 154.819)
		(mid 142.62388 154.571513)
		(end 142.871367 154.469)
		(width 0.1)
		(layer "In2.Cu")
		(net 157)
	)
	(arc
		(start 142.871367 156.169)
		(mid 142.62388 156.066487)
		(end 142.521367 155.819)
		(width 0.1)
		(layer "In2.Cu")
		(net 157)
	)
	(arc
		(start 142.871367 155.169)
		(mid 142.62388 155.066487)
		(end 142.521367 154.819)
		(width 0.1)
		(layer "In2.Cu")
		(net 157)
	)
	(arc
		(start 143.258 157.319)
		(mid 143.214066 157.212934)
		(end 143.108 157.169)
		(width 0.1)
		(layer "In2.Cu")
		(net 157)
	)
	(arc
		(start 143.844633 154.469)
		(mid 143.950699 154.425066)
		(end 143.994633 154.319)
		(width 0.1)
		(layer "In2.Cu")
		(net 157)
	)
	(arc
		(start 143.844633 156.469)
		(mid 143.950699 156.425066)
		(end 143.994633 156.319)
		(width 0.1)
		(layer "In2.Cu")
		(net 157)
	)
	(arc
		(start 142.521367 156.819)
		(mid 142.62388 156.571513)
		(end 142.871367 156.469)
		(width 0.1)
		(layer "In2.Cu")
		(net 157)
	)
	(segment
		(start 140.670001 138.1825)
		(end 140.67 137.712573)
		(width 0.26)
		(layer "F.Cu")
		(net 158)
	)
	(segment
		(start 140.650002 138.2025)
		(end 140.670001 138.1825)
		(width 0.26)
		(layer "F.Cu")
		(net 158)
	)
	(segment
		(start 140.650002 138.8025)
		(end 140.650002 138.2025)
		(width 0.26)
		(layer "F.Cu")
		(net 158)
	)
	(segment
		(start 140.67 137.712573)
		(end 140.625001 137.667574)
		(width 0.26)
		(layer "F.Cu")
		(net 158)
	)
	(segment
		(start 140.375501 163.302)
		(end 140.875001 162.8025)
		(width 0.256)
		(layer "F.Cu")
		(net 158)
	)
	(via
		(at 140.875001 162.8025)
		(size 0.45)
		(drill 0.1)
		(layers "F.Cu" "B.Cu")
		(net 158)
	)
	(via
		(at 140.625001 137.667574)
		(size 0.45)
		(drill 0.1)
		(layers "F.Cu" "B.Cu")
		(net 158)
	)
	(segment
		(start 140.093578 149.7345)
		(end 139.3345 150.493578)
		(width 0.1)
		(layer "In2.Cu")
		(net 158)
	)
	(segment
		(start 140.459079 136.676)
		(end 139.542923 136.676)
		(width 0.1)
		(layer "In2.Cu")
		(net 158)
	)
	(segment
		(start 140.244368 150.502947)
		(end 141.475001 151.733579)
		(width 0.1)
		(layer "In2.Cu")
		(net 158)
	)
	(segment
		(start 140.800001 137.492574)
		(end 140.800001 137.016922)
		(width 0.1)
		(layer "In2.Cu")
		(net 158)
	)
	(segment
		(start 141.475001 162.093922)
		(end 141.166423 162.4025)
		(width 0.1)
		(layer "In2.Cu")
		(net 158)
	)
	(segment
		(start 140.625001 137.667574)
		(end 140.800001 137.492574)
		(width 0.1)
		(layer "In2.Cu")
		(net 158)
	)
	(segment
		(start 141.166423 162.4025)
		(end 140.973001 162.4025)
		(width 0.1)
		(layer "In2.Cu")
		(net 158)
	)
	(segment
		(start 140.244369 150.502948)
		(end 140.244368 150.502947)
		(width 0.1)
		(layer "In2.Cu")
		(net 158)
	)
	(segment
		(start 139.175001 146.293922)
		(end 138.825001 146.643922)
		(width 0.1)
		(layer "In2.Cu")
		(net 158)
	)
	(segment
		(start 139.546633 150.705709)
		(end 139.546632 150.70571)
		(width 0.1)
		(layer "In2.Cu")
		(net 158)
	)
	(segment
		(start 140.875001 162.5005)
		(end 140.875001 162.8025)
		(width 0.1)
		(layer "In2.Cu")
		(net 158)
	)
	(segment
		(start 139.542923 136.676)
		(end 139.175001 137.043922)
		(width 0.1)
		(layer "In2.Cu")
		(net 158)
	)
	(segment
		(start 140.800001 137.016922)
		(end 140.459079 136.676)
		(width 0.1)
		(layer "In2.Cu")
		(net 158)
	)
	(segment
		(start 139.175001 137.043922)
		(end 139.175001 146.293922)
		(width 0.1)
		(layer "In2.Cu")
		(net 158)
	)
	(segment
		(start 141.475001 151.733579)
		(end 141.475001 162.093922)
		(width 0.1)
		(layer "In2.Cu")
		(net 158)
	)
	(segment
		(start 140.093577 149.734501)
		(end 140.093578 149.7345)
		(width 0.1)
		(layer "In2.Cu")
		(net 158)
	)
	(segment
		(start 140.093579 149.239527)
		(end 140.093578 149.239526)
		(width 0.1)
		(layer "In2.Cu")
		(net 158)
	)
	(segment
		(start 139.395843 149.44229)
		(end 139.598604 149.239526)
		(width 0.1)
		(layer "In2.Cu")
		(net 158)
	)
	(segment
		(start 139.546632 150.70571)
		(end 139.749394 150.502947)
		(width 0.1)
		(layer "In2.Cu")
		(net 158)
	)
	(segment
		(start 140.973001 162.4025)
		(end 140.875001 162.5005)
		(width 0.1)
		(layer "In2.Cu")
		(net 158)
	)
	(segment
		(start 138.825001 146.643922)
		(end 138.825001 149.083579)
		(width 0.1)
		(layer "In2.Cu")
		(net 158)
	)
	(segment
		(start 138.825001 149.083579)
		(end 139.183709 149.442288)
		(width 0.1)
		(layer "In2.Cu")
		(net 158)
	)
	(arc
		(start 139.749394 150.502947)
		(mid 139.996882 150.400435)
		(end 140.244369 150.502948)
		(width 0.1)
		(layer "In2.Cu")
		(net 158)
	)
	(arc
		(start 139.3345 150.493578)
		(mid 139.290566 150.599644)
		(end 139.3345 150.70571)
		(width 0.1)
		(layer "In2.Cu")
		(net 158)
	)
	(arc
		(start 140.093578 149.239526)
		(mid 140.19609 149.487014)
		(end 140.093577 149.734501)
		(width 0.1)
		(layer "In2.Cu")
		(net 158)
	)
	(arc
		(start 139.598604 149.239526)
		(mid 139.846092 149.137014)
		(end 140.093579 149.239527)
		(width 0.1)
		(layer "In2.Cu")
		(net 158)
	)
	(arc
		(start 139.183709 149.442288)
		(mid 139.289777 149.486224)
		(end 139.395843 149.44229)
		(width 0.1)
		(layer "In2.Cu")
		(net 158)
	)
	(arc
		(start 139.3345 150.70571)
		(mid 139.440567 150.749644)
		(end 139.546633 150.705709)
		(width 0.1)
		(layer "In2.Cu")
		(net 158)
	)
	(segment
		(start 140.900001 146.2025)
		(end 140.900001 146.8025)
		(width 0.26)
		(layer "F.Cu")
		(net 159)
	)
	(segment
		(start 141.375501 165.302)
		(end 141.875001 164.8025)
		(width 0.256)
		(layer "F.Cu")
		(net 159)
	)
	(segment
		(start 140.880001 146.8225)
		(end 140.880002 147.292427)
		(width 0.26)
		(layer "F.Cu")
		(net 159)
	)
	(segment
		(start 140.880002 147.292427)
		(end 140.925001 147.337426)
		(width 0.26)
		(layer "F.Cu")
		(net 159)
	)
	(segment
		(start 140.900001 146.8025)
		(end 140.880001 146.8225)
		(width 0.26)
		(layer "F.Cu")
		(net 159)
	)
	(via
		(at 140.925001 147.337426)
		(size 0.45)
		(drill 0.1)
		(layers "F.Cu" "B.Cu")
		(net 159)
	)
	(via
		(at 141.875001 164.8025)
		(size 0.45)
		(drill 0.1)
		(layers "F.Cu" "B.Cu")
		(net 159)
	)
	(segment
		(start 142.475001 158.724421)
		(end 142.596211 158.603211)
		(width 0.1)
		(layer "In2.Cu")
		(net 159)
	)
	(segment
		(start 141.875001 165.104499)
		(end 141.777001 165.202499)
		(width 0.1)
		(layer "In2.Cu")
		(net 159)
	)
	(segment
		(start 142.879053 158.603211)
		(end 142.962961 158.687119)
		(width 0.1)
		(layer "In2.Cu")
		(net 159)
	)
	(segment
		(start 143.161895 158.037524)
		(end 143.458 157.741422)
		(width 0.1)
		(layer "In2.Cu")
		(net 159)
	)
	(segment
		(start 143.161894 158.037524)
		(end 143.161895 158.037524)
		(width 0.1)
		(layer "In2.Cu")
		(net 159)
	)
	(segment
		(start 143.245804 158.68712)
		(end 143.245804 158.687119)
		(width 0.1)
		(layer "In2.Cu")
		(net 159)
	)
	(segment
		(start 143.108 156.969)
		(end 142.871367 156.969)
		(width 0.1)
		(layer "In2.Cu")
		(net 159)
	)
	(segment
		(start 141.777001 165.202499)
		(end 141.643756 165.202499)
		(width 0.1)
		(layer "In2.Cu")
		(net 159)
	)
	(segment
		(start 142.871367 152.669)
		(end 143.844633 152.669)
		(width 0.1)
		(layer "In2.Cu")
		(net 159)
	)
	(segment
		(start 142.475001 164.093922)
		(end 142.475001 158.724421)
		(width 0.1)
		(layer "In2.Cu")
		(net 159)
	)
	(segment
		(start 140.750001 148.386078)
		(end 140.750001 147.512426)
		(width 0.1)
		(layer "In2.Cu")
		(net 159)
	)
	(segment
		(start 143.844633 151.969)
		(end 143.608 151.969)
		(width 0.1)
		(layer "In2.Cu")
		(net 159)
	)
	(segment
		(start 142.871367 154.969)
		(end 143.844633 154.969)
		(width 0.1)
		(layer "In2.Cu")
		(net 159)
	)
	(segment
		(start 141.666423 164.4025)
		(end 142.166423 164.4025)
		(width 0.1)
		(layer "In2.Cu")
		(net 159)
	)
	(segment
		(start 141.875001 164.8025)
		(end 141.875001 165.104499)
		(width 0.1)
		(layer "In2.Cu")
		(net 159)
	)
	(segment
		(start 143.245804 158.404276)
		(end 143.161895 158.320367)
		(width 0.1)
		(layer "In2.Cu")
		(net 159)
	)
	(segment
		(start 142.871367 155.669)
		(end 143.844633 155.669)
		(width 0.1)
		(layer "In2.Cu")
		(net 159)
	)
	(segment
		(start 142.871367 153.669)
		(end 143.844633 153.669)
		(width 0.1)
		(layer "In2.Cu")
		(net 159)
	)
	(segment
		(start 141.475001 165.033744)
		(end 141.475001 164.593922)
		(width 0.1)
		(layer "In2.Cu")
		(net 159)
	)
	(segment
		(start 142.871367 154.669)
		(end 143.844633 154.669)
		(width 0.1)
		(layer "In2.Cu")
		(net 159)
	)
	(segment
		(start 143.458 157.741422)
		(end 143.458 157.319)
		(width 0.1)
		(layer "In2.Cu")
		(net 159)
	)
	(segment
		(start 141.643756 165.202499)
		(end 141.475001 165.033744)
		(width 0.1)
		(layer "In2.Cu")
		(net 159)
	)
	(segment
		(start 143.458 151.819)
		(end 143.458 151.094077)
		(width 0.1)
		(layer "In2.Cu")
		(net 159)
	)
	(segment
		(start 143.245804 158.404275)
		(end 143.245804 158.404276)
		(width 0.1)
		(layer "In2.Cu")
		(net 159)
	)
	(segment
		(start 142.871367 156.669)
		(end 143.844633 156.669)
		(width 0.1)
		(layer "In2.Cu")
		(net 159)
	)
	(segment
		(start 142.166423 164.4025)
		(end 142.475001 164.093922)
		(width 0.1)
		(layer "In2.Cu")
		(net 159)
	)
	(segment
		(start 142.871367 152.969)
		(end 143.844633 152.969)
		(width 0.1)
		(layer "In2.Cu")
		(net 159)
	)
	(segment
		(start 142.871367 155.969)
		(end 143.844633 155.969)
		(width 0.1)
		(layer "In2.Cu")
		(net 159)
	)
	(segment
		(start 143.458 151.094077)
		(end 140.750001 148.386078)
		(width 0.1)
		(layer "In2.Cu")
		(net 159)
	)
	(segment
		(start 141.475001 164.593922)
		(end 141.666423 164.4025)
		(width 0.1)
		(layer "In2.Cu")
		(net 159)
	)
	(segment
		(start 142.871367 153.969)
		(end 143.844633 153.969)
		(width 0.1)
		(layer "In2.Cu")
		(net 159)
	)
	(segment
		(start 140.750001 147.512426)
		(end 140.925001 147.337426)
		(width 0.1)
		(layer "In2.Cu")
		(net 159)
	)
	(arc
		(start 142.871367 155.969)
		(mid 142.765301 155.925066)
		(end 142.721367 155.819)
		(width 0.1)
		(layer "In2.Cu")
		(net 159)
	)
	(arc
		(start 142.962961 158.687119)
		(mid 143.104382 158.745698)
		(end 143.245804 158.68712)
		(width 0.1)
		(layer "In2.Cu")
		(net 159)
	)
	(arc
		(start 143.844633 156.669)
		(mid 144.09212 156.566487)
		(end 144.194633 156.319)
		(width 0.1)
		(layer "In2.Cu")
		(net 159)
	)
	(arc
		(start 143.245804 158.687119)
		(mid 143.304383 158.545697)
		(end 143.245804 158.404275)
		(width 0.1)
		(layer "In2.Cu")
		(net 159)
	)
	(arc
		(start 144.194633 153.319)
		(mid 144.09212 153.071513)
		(end 143.844633 152.969)
		(width 0.1)
		(layer "In2.Cu")
		(net 159)
	)
	(arc
		(start 144.194633 156.319)
		(mid 144.09212 156.071513)
		(end 143.844633 155.969)
		(width 0.1)
		(layer "In2.Cu")
		(net 159)
	)
	(arc
		(start 144.194633 154.319)
		(mid 144.09212 154.071513)
		(end 143.844633 153.969)
		(width 0.1)
		(layer "In2.Cu")
		(net 159)
	)
	(arc
		(start 142.721367 154.819)
		(mid 142.765301 154.712934)
		(end 142.871367 154.669)
		(width 0.1)
		(layer "In2.Cu")
		(net 159)
	)
	(arc
		(start 142.721367 153.819)
		(mid 142.765301 153.712934)
		(end 142.871367 153.669)
		(width 0.1)
		(layer "In2.Cu")
		(net 159)
	)
	(arc
		(start 142.596211 158.603211)
		(mid 142.737632 158.544633)
		(end 142.879053 158.603211)
		(width 0.1)
		(layer "In2.Cu")
		(net 159)
	)
	(arc
		(start 142.721367 156.819)
		(mid 142.765301 156.712934)
		(end 142.871367 156.669)
		(width 0.1)
		(layer "In2.Cu")
		(net 159)
	)
	(arc
		(start 142.721367 155.819)
		(mid 142.765301 155.712934)
		(end 142.871367 155.669)
		(width 0.1)
		(layer "In2.Cu")
		(net 159)
	)
	(arc
		(start 142.721367 152.819)
		(mid 142.765301 152.712934)
		(end 142.871367 152.669)
		(width 0.1)
		(layer "In2.Cu")
		(net 159)
	)
	(arc
		(start 143.608 151.969)
		(mid 143.501934 151.925066)
		(end 143.458 151.819)
		(width 0.1)
		(layer "In2.Cu")
		(net 159)
	)
	(arc
		(start 142.871367 153.969)
		(mid 142.765301 153.925066)
		(end 142.721367 153.819)
		(width 0.1)
		(layer "In2.Cu")
		(net 159)
	)
	(arc
		(start 142.871367 152.969)
		(mid 142.765301 152.925066)
		(end 142.721367 152.819)
		(width 0.1)
		(layer "In2.Cu")
		(net 159)
	)
	(arc
		(start 143.844633 155.669)
		(mid 144.09212 155.566487)
		(end 144.194633 155.319)
		(width 0.1)
		(layer "In2.Cu")
		(net 159)
	)
	(arc
		(start 143.844633 153.669)
		(mid 144.09212 153.566487)
		(end 144.194633 153.319)
		(width 0.1)
		(layer "In2.Cu")
		(net 159)
	)
	(arc
		(start 143.161895 158.320367)
		(mid 143.103316 158.178946)
		(end 143.161894 158.037524)
		(width 0.1)
		(layer "In2.Cu")
		(net 159)
	)
	(arc
		(start 143.458 157.319)
		(mid 143.355487 157.071513)
		(end 143.108 156.969)
		(width 0.1)
		(layer "In2.Cu")
		(net 159)
	)
	(arc
		(start 143.844633 154.669)
		(mid 144.09212 154.566487)
		(end 144.194633 154.319)
		(width 0.1)
		(layer "In2.Cu")
		(net 159)
	)
	(arc
		(start 142.871367 156.969)
		(mid 142.765301 156.925066)
		(end 142.721367 156.819)
		(width 0.1)
		(layer "In2.Cu")
		(net 159)
	)
	(arc
		(start 143.844633 152.669)
		(mid 144.09212 152.566487)
		(end 144.194633 152.319)
		(width 0.1)
		(layer "In2.Cu")
		(net 159)
	)
	(arc
		(start 144.194633 152.319)
		(mid 144.09212 152.071513)
		(end 143.844633 151.969)
		(width 0.1)
		(layer "In2.Cu")
		(net 159)
	)
	(arc
		(start 142.871367 154.969)
		(mid 142.765301 154.925066)
		(end 142.721367 154.819)
		(width 0.1)
		(layer "In2.Cu")
		(net 159)
	)
	(arc
		(start 144.194633 155.319)
		(mid 144.09212 155.071513)
		(end 143.844633 154.969)
		(width 0.1)
		(layer "In2.Cu")
		(net 159)
	)
	(segment
		(start 140.375501 162.302)
		(end 140.875001 161.8025)
		(width 0.256)
		(layer "F.Cu")
		(net 160)
	)
	(segment
		(start 141.150001 138.8025)
		(end 141.150001 138.2025)
		(width 0.26)
		(layer "F.Cu")
		(net 160)
	)
	(segment
		(start 141.130001 138.1825)
		(end 141.130002 137.712573)
		(width 0.26)
		(layer "F.Cu")
		(net 160)
	)
	(segment
		(start 141.130002 137.712573)
		(end 141.175001 137.667574)
		(width 0.26)
		(layer "F.Cu")
		(net 160)
	)
	(segment
		(start 141.150001 138.2025)
		(end 141.130001 138.1825)
		(width 0.26)
		(layer "F.Cu")
		(net 160)
	)
	(via
		(at 140.875001 161.8025)
		(size 0.45)
		(drill 0.1)
		(layers "F.Cu" "B.Cu")
		(net 160)
	)
	(via
		(at 141.175001 137.667574)
		(size 0.45)
		(drill 0.1)
		(layers "F.Cu" "B.Cu")
		(net 160)
	)
	(segment
		(start 141.104574 137.667574)
		(end 141.000001 137.563001)
		(width 0.1)
		(layer "In2.Cu")
		(net 160)
	)
	(segment
		(start 139.952158 149.593081)
		(end 139.952159 149.59308)
		(width 0.1)
		(layer "In2.Cu")
		(net 160)
	)
	(segment
		(start 140.977001 162.2025)
		(end 140.875001 162.1005)
		(width 0.1)
		(layer "In2.Cu")
		(net 160)
	)
	(segment
		(start 140.541921 136.476)
		(end 139.460079 136.476)
		(width 0.1)
		(layer "In2.Cu")
		(net 160)
	)
	(segment
		(start 138.975001 136.961078)
		(end 138.975001 146.211078)
		(width 0.1)
		(layer "In2.Cu")
		(net 160)
	)
	(segment
		(start 139.537264 149.583711)
		(end 139.537264 149.58371)
		(width 0.1)
		(layer "In2.Cu")
		(net 160)
	)
	(segment
		(start 141.175001 137.667574)
		(end 141.104574 137.667574)
		(width 0.1)
		(layer "In2.Cu")
		(net 160)
	)
	(segment
		(start 141.000001 137.563001)
		(end 141.000001 136.93408)
		(width 0.1)
		(layer "In2.Cu")
		(net 160)
	)
	(segment
		(start 140.102947 150.644368)
		(end 141.275001 151.816423)
		(width 0.1)
		(layer "In2.Cu")
		(net 160)
	)
	(segment
		(start 139.460079 136.476)
		(end 138.975001 136.961078)
		(width 0.1)
		(layer "In2.Cu")
		(net 160)
	)
	(segment
		(start 138.625001 146.561078)
		(end 138.625001 149.166423)
		(width 0.1)
		(layer "In2.Cu")
		(net 160)
	)
	(segment
		(start 139.952159 149.59308)
		(end 139.193079 150.352157)
		(width 0.1)
		(layer "In2.Cu")
		(net 160)
	)
	(segment
		(start 139.537264 149.58371)
		(end 139.740027 149.380948)
		(width 0.1)
		(layer "In2.Cu")
		(net 160)
	)
	(segment
		(start 139.688054 150.84713)
		(end 139.688053 150.847131)
		(width 0.1)
		(layer "In2.Cu")
		(net 160)
	)
	(segment
		(start 141.000001 136.93408)
		(end 140.541921 136.476)
		(width 0.1)
		(layer "In2.Cu")
		(net 160)
	)
	(segment
		(start 140.875001 162.1005)
		(end 140.875001 161.8025)
		(width 0.1)
		(layer "In2.Cu")
		(net 160)
	)
	(segment
		(start 138.975001 146.211078)
		(end 138.625001 146.561078)
		(width 0.1)
		(layer "In2.Cu")
		(net 160)
	)
	(segment
		(start 139.688053 150.847131)
		(end 139.890815 150.644368)
		(width 0.1)
		(layer "In2.Cu")
		(net 160)
	)
	(segment
		(start 141.275001 151.816423)
		(end 141.275001 162.011078)
		(width 0.1)
		(layer "In2.Cu")
		(net 160)
	)
	(segment
		(start 138.625001 149.166423)
		(end 139.042288 149.583709)
		(width 0.1)
		(layer "In2.Cu")
		(net 160)
	)
	(segment
		(start 141.275001 162.011078)
		(end 141.083579 162.2025)
		(width 0.1)
		(layer "In2.Cu")
		(net 160)
	)
	(segment
		(start 141.083579 162.2025)
		(end 140.977001 162.2025)
		(width 0.1)
		(layer "In2.Cu")
		(net 160)
	)
	(arc
		(start 139.952159 149.380948)
		(mid 139.996092 149.487014)
		(end 139.952158 149.593081)
		(width 0.1)
		(layer "In2.Cu")
		(net 160)
	)
	(arc
		(start 139.193079 150.847131)
		(mid 139.440567 150.949643)
		(end 139.688054 150.84713)
		(width 0.1)
		(layer "In2.Cu")
		(net 160)
	)
	(arc
		(start 139.193079 150.352157)
		(mid 139.090567 150.599644)
		(end 139.193079 150.847131)
		(width 0.1)
		(layer "In2.Cu")
		(net 160)
	)
	(arc
		(start 139.740027 149.380948)
		(mid 139.846093 149.337014)
		(end 139.952159 149.380948)
		(width 0.1)
		(layer "In2.Cu")
		(net 160)
	)
	(arc
		(start 139.042288 149.583709)
		(mid 139.289776 149.686222)
		(end 139.537264 149.583711)
		(width 0.1)
		(layer "In2.Cu")
		(net 160)
	)
	(arc
		(start 139.890815 150.644368)
		(mid 139.996881 150.600434)
		(end 140.102947 150.644368)
		(width 0.1)
		(layer "In2.Cu")
		(net 160)
	)
	(segment
		(start 141.900001 146.2025)
		(end 141.900001 146.8025)
		(width 0.26)
		(layer "F.Cu")
		(net 161)
	)
	(segment
		(start 142.375501 167.301999)
		(end 142.875001 166.8025)
		(width 0.256)
		(layer "F.Cu")
		(net 161)
	)
	(segment
		(start 141.900001 146.8025)
		(end 141.920001 146.8225)
		(width 0.26)
		(layer "F.Cu")
		(net 161)
	)
	(segment
		(start 141.920001 146.8225)
		(end 141.92 147.292427)
		(width 0.26)
		(layer "F.Cu")
		(net 161)
	)
	(segment
		(start 141.92 147.292427)
		(end 141.875001 147.337426)
		(width 0.26)
		(layer "F.Cu")
		(net 161)
	)
	(via
		(at 142.875001 166.8025)
		(size 0.45)
		(drill 0.1)
		(layers "F.Cu" "B.Cu")
		(net 161)
	)
	(via
		(at 141.875001 147.337426)
		(size 0.45)
		(drill 0.1)
		(layers "F.Cu" "B.Cu")
		(net 161)
	)
	(segment
		(start 142.688578 148.74)
		(end 142.050001 148.101423)
		(width 0.1)
		(layer "In2.Cu")
		(net 161)
	)
	(segment
		(start 146.165337 150.3)
		(end 146.52 150.3)
		(width 0.1)
		(layer "In2.Cu")
		(net 161)
	)
	(segment
		(start 147.374663 155)
		(end 146.165337 155)
		(width 0.1)
		(layer "In2.Cu")
		(net 161)
	)
	(segment
		(start 146.165337 154.3)
		(end 147.374663 154.3)
		(width 0.1)
		(layer "In2.Cu")
		(net 161)
	)
	(segment
		(start 147.374663 151)
		(end 146.165337 151)
		(width 0.1)
		(layer "In2.Cu")
		(net 161)
	)
	(segment
		(start 142.583579 165.2025)
		(end 143.083579 165.2025)
		(width 0.1)
		(layer "In2.Cu")
		(net 161)
	)
	(segment
		(start 142.875001 166.5045)
		(end 142.773001 166.4025)
		(width 0.1)
		(layer "In2.Cu")
		(net 161)
	)
	(segment
		(start 142.773001 166.4025)
		(end 142.560915 166.4025)
		(width 0.1)
		(layer "In2.Cu")
		(net 161)
	)
	(segment
		(start 143.275001 161.375001)
		(end 143.12 161.22)
		(width 0.1)
		(layer "In2.Cu")
		(net 161)
	)
	(segment
		(start 143.12 161.22)
		(end 143.12 161.030002)
		(width 0.1)
		(layer "In2.Cu")
		(net 161)
	)
	(segment
		(start 147.374663 154)
		(end 146.165337 154)
		(width 0.1)
		(layer "In2.Cu")
		(net 161)
	)
	(segment
		(start 146.67 156.518578)
		(end 146.67 155.65)
		(width 0.1)
		(layer "In2.Cu")
		(net 161)
	)
	(segment
		(start 146.67 149.912422)
		(end 145.497578 148.74)
		(width 0.1)
		(layer "In2.Cu")
		(net 161)
	)
	(segment
		(start 142.875001 166.8025)
		(end 142.875001 166.5045)
		(width 0.1)
		(layer "In2.Cu")
		(net 161)
	)
	(segment
		(start 146.67 150.15)
		(end 146.67 149.912422)
		(width 0.1)
		(layer "In2.Cu")
		(net 161)
	)
	(segment
		(start 146.165337 151.3)
		(end 147.374663 151.3)
		(width 0.1)
		(layer "In2.Cu")
		(net 161)
	)
	(segment
		(start 142.050001 148.101423)
		(end 142.050001 147.512426)
		(width 0.1)
		(layer "In2.Cu")
		(net 161)
	)
	(segment
		(start 143.083579 165.2025)
		(end 143.275001 165.011078)
		(width 0.1)
		(layer "In2.Cu")
		(net 161)
	)
	(segment
		(start 147.374663 153)
		(end 146.165337 153)
		(width 0.1)
		(layer "In2.Cu")
		(net 161)
	)
	(segment
		(start 143.12 161.030002)
		(end 143.275001 160.875001)
		(width 0.1)
		(layer "In2.Cu")
		(net 161)
	)
	(segment
		(start 143.275001 160.875001)
		(end 143.275001 159.913577)
		(width 0.1)
		(layer "In2.Cu")
		(net 161)
	)
	(segment
		(start 142.050001 147.512426)
		(end 141.875001 147.337426)
		(width 0.1)
		(layer "In2.Cu")
		(net 161)
	)
	(segment
		(start 145.497578 148.74)
		(end 142.688578 148.74)
		(width 0.1)
		(layer "In2.Cu")
		(net 161)
	)
	(segment
		(start 142.275001 166.116586)
		(end 142.275001 165.511078)
		(width 0.1)
		(layer "In2.Cu")
		(net 161)
	)
	(segment
		(start 143.275001 159.913577)
		(end 146.67 156.518578)
		(width 0.1)
		(layer "In2.Cu")
		(net 161)
	)
	(segment
		(start 142.275001 165.511078)
		(end 142.583579 165.2025)
		(width 0.1)
		(layer "In2.Cu")
		(net 161)
	)
	(segment
		(start 147.02 155.3)
		(end 147.374663 155.3)
		(width 0.1)
		(layer "In2.Cu")
		(net 161)
	)
	(segment
		(start 146.165337 153.3)
		(end 147.374663 153.3)
		(width 0.1)
		(layer "In2.Cu")
		(net 161)
	)
	(segment
		(start 142.560915 166.4025)
		(end 142.275001 166.116586)
		(width 0.1)
		(layer "In2.Cu")
		(net 161)
	)
	(segment
		(start 143.275001 165.011078)
		(end 143.275001 161.375001)
		(width 0.1)
		(layer "In2.Cu")
		(net 161)
	)
	(segment
		(start 147.374663 152)
		(end 146.165337 152)
		(width 0.1)
		(layer "In2.Cu")
		(net 161)
	)
	(segment
		(start 146.165337 152.3)
		(end 147.374663 152.3)
		(width 0.1)
		(layer "In2.Cu")
		(net 161)
	)
	(arc
		(start 146.165337 154)
		(mid 145.91785 153.897487)
		(end 145.815337 153.65)
		(width 0.1)
		(layer "In2.Cu")
		(net 161)
	)
	(arc
		(start 147.524663 155.15)
		(mid 147.480729 155.043934)
		(end 147.374663 155)
		(width 0.1)
		(layer "In2.Cu")
		(net 161)
	)
	(arc
		(start 147.524663 151.15)
		(mid 147.480729 151.043934)
		(end 147.374663 151)
		(width 0.1)
		(layer "In2.Cu")
		(net 161)
	)
	(arc
		(start 146.165337 153)
		(mid 145.91785 152.897487)
		(end 145.815337 152.65)
		(width 0.1)
		(layer "In2.Cu")
		(net 161)
	)
	(arc
		(start 147.374663 154.3)
		(mid 147.480729 154.256066)
		(end 147.524663 154.15)
		(width 0.1)
		(layer "In2.Cu")
		(net 161)
	)
	(arc
		(start 146.165337 151)
		(mid 145.91785 150.897487)
		(end 145.815337 150.65)
		(width 0.1)
		(layer "In2.Cu")
		(net 161)
	)
	(arc
		(start 147.374663 152.3)
		(mid 147.480729 152.256066)
		(end 147.524663 152.15)
		(width 0.1)
		(layer "In2.Cu")
		(net 161)
	)
	(arc
		(start 147.524663 152.15)
		(mid 147.480729 152.043934)
		(end 147.374663 152)
		(width 0.1)
		(layer "In2.Cu")
		(net 161)
	)
	(arc
		(start 146.165337 155)
		(mid 145.91785 154.897487)
		(end 145.815337 154.65)
		(width 0.1)
		(layer "In2.Cu")
		(net 161)
	)
	(arc
		(start 145.815337 153.65)
		(mid 145.91785 153.402513)
		(end 146.165337 153.3)
		(width 0.1)
		(layer "In2.Cu")
		(net 161)
	)
	(arc
		(start 145.815337 154.65)
		(mid 145.91785 154.402513)
		(end 146.165337 154.3)
		(width 0.1)
		(layer "In2.Cu")
		(net 161)
	)
	(arc
		(start 146.67 155.65)
		(mid 146.772513 155.402513)
		(end 147.02 155.3)
		(width 0.1)
		(layer "In2.Cu")
		(net 161)
	)
	(arc
		(start 147.374663 155.3)
		(mid 147.480729 155.256066)
		(end 147.524663 155.15)
		(width 0.1)
		(layer "In2.Cu")
		(net 161)
	)
	(arc
		(start 147.524663 154.15)
		(mid 147.480729 154.043934)
		(end 147.374663 154)
		(width 0.1)
		(layer "In2.Cu")
		(net 161)
	)
	(arc
		(start 147.524663 153.15)
		(mid 147.480729 153.043934)
		(end 147.374663 153)
		(width 0.1)
		(layer "In2.Cu")
		(net 161)
	)
	(arc
		(start 145.815337 152.65)
		(mid 145.91785 152.402513)
		(end 146.165337 152.3)
		(width 0.1)
		(layer "In2.Cu")
		(net 161)
	)
	(arc
		(start 147.374663 153.3)
		(mid 147.480729 153.256066)
		(end 147.524663 153.15)
		(width 0.1)
		(layer "In2.Cu")
		(net 161)
	)
	(arc
		(start 145.815337 150.65)
		(mid 145.91785 150.402513)
		(end 146.165337 150.3)
		(width 0.1)
		(layer "In2.Cu")
		(net 161)
	)
	(arc
		(start 146.165337 152)
		(mid 145.91785 151.897487)
		(end 145.815337 151.65)
		(width 0.1)
		(layer "In2.Cu")
		(net 161)
	)
	(arc
		(start 145.815337 151.65)
		(mid 145.91785 151.402513)
		(end 146.165337 151.3)
		(width 0.1)
		(layer "In2.Cu")
		(net 161)
	)
	(arc
		(start 147.374663 151.3)
		(mid 147.480729 151.256066)
		(end 147.524663 151.15)
		(width 0.1)
		(layer "In2.Cu")
		(net 161)
	)
	(arc
		(start 146.52 150.3)
		(mid 146.626066 150.256066)
		(end 146.67 150.15)
		(width 0.1)
		(layer "In2.Cu")
		(net 161)
	)
	(segment
		(start 142.150002 138.8025)
		(end 142.150002 138.2025)
		(width 0.26)
		(layer "F.Cu")
		(net 162)
	)
	(segment
		(start 142.150002 138.2025)
		(end 142.170001 138.1825)
		(width 0.26)
		(layer "F.Cu")
		(net 162)
	)
	(segment
		(start 142.17 137.712573)
		(end 142.125001 137.667574)
		(width 0.26)
		(layer "F.Cu")
		(net 162)
	)
	(segment
		(start 139.375501 163.302)
		(end 139.875001 162.8025)
		(width 0.256)
		(layer "F.Cu")
		(net 162)
	)
	(segment
		(start 142.170001 138.1825)
		(end 142.17 137.712573)
		(width 0.26)
		(layer "F.Cu")
		(net 162)
	)
	(via
		(at 142.125001 137.667574)
		(size 0.45)
		(drill 0.1)
		(layers "F.Cu" "B.Cu")
		(net 162)
	)
	(via
		(at 139.875001 162.8025)
		(size 0.45)
		(drill 0.1)
		(layers "F.Cu" "B.Cu")
		(net 162)
	)
	(segment
		(start 140.7775 135.504979)
		(end 140.7775 135.4775)
		(width 0.1)
		(layer "In2.Cu")
		(net 162)
	)
	(segment
		(start 142.300001 136.068922)
		(end 141.533579 135.3025)
		(width 0.1)
		(layer "In2.Cu")
		(net 162)
	)
	(segment
		(start 139.875001 162.5005)
		(end 139.875001 162.8025)
		(width 0.1)
		(layer "In2.Cu")
		(net 162)
	)
	(segment
		(start 142.300001 137.492574)
		(end 142.300001 136.068922)
		(width 0.1)
		(layer "In2.Cu")
		(net 162)
	)
	(segment
		(start 139.8525 135.3025)
		(end 139.316423 135.3025)
		(width 0.1)
		(layer "In2.Cu")
		(net 162)
	)
	(segment
		(start 141.533579 135.3025)
		(end 141.3025 135.3025)
		(width 0.1)
		(layer "In2.Cu")
		(net 162)
	)
	(segment
		(start 140.0775 135.504979)
		(end 140.0775 135.4775)
		(width 0.1)
		(layer "In2.Cu")
		(net 162)
	)
	(segment
		(start 140.216423 162.4025)
		(end 139.973001 162.4025)
		(width 0.1)
		(layer "In2.Cu")
		(net 162)
	)
	(segment
		(start 139.316423 135.3025)
		(end 138.225001 136.393922)
		(width 0.1)
		(layer "In2.Cu")
		(net 162)
	)
	(segment
		(start 139.973001 162.4025)
		(end 139.875001 162.5005)
		(width 0.1)
		(layer "In2.Cu")
		(net 162)
	)
	(segment
		(start 138.225001 136.393922)
		(end 138.225001 151.511078)
		(width 0.1)
		(layer "In2.Cu")
		(net 162)
	)
	(segment
		(start 138.225001 151.511078)
		(end 140.475001 153.761078)
		(width 0.1)
		(layer "In2.Cu")
		(net 162)
	)
	(segment
		(start 141.1275 135.4775)
		(end 141.1275 135.504979)
		(width 0.1)
		(layer "In2.Cu")
		(net 162)
	)
	(segment
		(start 140.4275 135.4775)
		(end 140.4275 135.504979)
		(width 0.1)
		(layer "In2.Cu")
		(net 162)
	)
	(segment
		(start 140.475001 162.143922)
		(end 140.216423 162.4025)
		(width 0.1)
		(layer "In2.Cu")
		(net 162)
	)
	(segment
		(start 142.125001 137.667574)
		(end 142.300001 137.492574)
		(width 0.1)
		(layer "In2.Cu")
		(net 162)
	)
	(segment
		(start 140.475001 153.761078)
		(end 140.475001 162.143922)
		(width 0.1)
		(layer "In2.Cu")
		(net 162)
	)
	(segment
		(start 139.9025 135.3025)
		(end 139.8525 135.3025)
		(width 0.1)
		(layer "In2.Cu")
		(net 162)
	)
	(arc
		(start 140.7775 135.4775)
		(mid 140.726244 135.353756)
		(end 140.6025 135.3025)
		(width 0.1)
		(layer "In2.Cu")
		(net 162)
	)
	(arc
		(start 141.3025 135.3025)
		(mid 141.178756 135.353756)
		(end 141.1275 135.4775)
		(width 0.1)
		(layer "In2.Cu")
		(net 162)
	)
	(arc
		(start 140.0775 135.4775)
		(mid 140.026244 135.353756)
		(end 139.9025 135.3025)
		(width 0.1)
		(layer "In2.Cu")
		(net 162)
	)
	(arc
		(start 140.4275 135.504979)
		(mid 140.376244 135.628723)
		(end 140.2525 135.679979)
		(width 0.1)
		(layer "In2.Cu")
		(net 162)
	)
	(arc
		(start 141.1275 135.504979)
		(mid 141.076244 135.628723)
		(end 140.9525 135.679979)
		(width 0.1)
		(layer "In2.Cu")
		(net 162)
	)
	(arc
		(start 140.6025 135.3025)
		(mid 140.478756 135.353756)
		(end 140.4275 135.4775)
		(width 0.1)
		(layer "In2.Cu")
		(net 162)
	)
	(arc
		(start 140.2525 135.679979)
		(mid 140.128756 135.628723)
		(end 140.0775 135.504979)
		(width 0.1)
		(layer "In2.Cu")
		(net 162)
	)
	(arc
		(start 140.9525 135.679979)
		(mid 140.828756 135.628723)
		(end 140.7775 135.504979)
		(width 0.1)
		(layer "In2.Cu")
		(net 162)
	)
	(segment
		(start 142.380002 147.292427)
		(end 142.425001 147.337426)
		(width 0.26)
		(layer "F.Cu")
		(net 163)
	)
	(segment
		(start 142.375501 166.302)
		(end 142.875001 165.8025)
		(width 0.256)
		(layer "F.Cu")
		(net 163)
	)
	(segment
		(start 142.400001 146.2025)
		(end 142.400001 146.8025)
		(width 0.26)
		(layer "F.Cu")
		(net 163)
	)
	(segment
		(start 142.380001 146.8225)
		(end 142.380002 147.292427)
		(width 0.26)
		(layer "F.Cu")
		(net 163)
	)
	(segment
		(start 142.400001 146.8025)
		(end 142.380001 146.8225)
		(width 0.26)
		(layer "F.Cu")
		(net 163)
	)
	(via
		(at 142.875001 165.8025)
		(size 0.45)
		(drill 0.1)
		(layers "F.Cu" "B.Cu")
		(net 163)
	)
	(via
		(at 142.425001 147.337426)
		(size 0.45)
		(drill 0.1)
		(layers "F.Cu" "B.Cu")
		(net 163)
	)
	(segment
		(start 143.475001 159.996421)
		(end 143.475001 165.093922)
		(width 0.1)
		(layer "In2.Cu")
		(net 163)
	)
	(segment
		(start 142.666423 165.4025)
		(end 142.475001 165.593922)
		(width 0.1)
		(layer "In2.Cu")
		(net 163)
	)
	(segment
		(start 146.87 149.829578)
		(end 146.87 150.15)
		(width 0.1)
		(layer "In2.Cu")
		(net 163)
	)
	(segment
		(start 145.580422 148.54)
		(end 146.87 149.829578)
		(width 0.1)
		(layer "In2.Cu")
		(net 163)
	)
	(segment
		(start 142.643756 166.202499)
		(end 142.777001 166.202499)
		(width 0.1)
		(layer "In2.Cu")
		(net 163)
	)
	(segment
		(start 143.166423 165.4025)
		(end 142.666423 165.4025)
		(width 0.1)
		(layer "In2.Cu")
		(net 163)
	)
	(segment
		(start 146.52 150.5)
		(end 146.165337 150.5)
		(width 0.1)
		(layer "In2.Cu")
		(net 163)
	)
	(segment
		(start 146.165337 153.5)
		(end 147.374663 153.5)
		(width 0.1)
		(layer "In2.Cu")
		(net 163)
	)
	(segment
		(start 142.425001 147.337426)
		(end 142.250001 147.512426)
		(width 0.1)
		(layer "In2.Cu")
		(net 163)
	)
	(segment
		(start 142.250001 147.512426)
		(end 142.250001 148.018579)
		(width 0.1)
		(layer "In2.Cu")
		(net 163)
	)
	(segment
		(start 142.250001 148.018579)
		(end 142.771422 148.54)
		(width 0.1)
		(layer "In2.Cu")
		(net 163)
	)
	(segment
		(start 146.165337 153.8)
		(end 147.374663 153.8)
		(width 0.1)
		(layer "In2.Cu")
		(net 163)
	)
	(segment
		(start 146.165337 151.5)
		(end 147.374663 151.5)
		(width 0.1)
		(layer "In2.Cu")
		(net 163)
	)
	(segment
		(start 146.165337 151.8)
		(end 147.374663 151.8)
		(width 0.1)
		(layer "In2.Cu")
		(net 163)
	)
	(segment
		(start 147.374663 155.5)
		(end 147.02 155.5)
		(width 0.1)
		(layer "In2.Cu")
		(net 163)
	)
	(segment
		(start 146.165337 154.8)
		(end 147.374663 154.8)
		(width 0.1)
		(layer "In2.Cu")
		(net 163)
	)
	(segment
		(start 142.771422 148.54)
		(end 145.580422 148.54)
		(width 0.1)
		(layer "In2.Cu")
		(net 163)
	)
	(segment
		(start 142.475001 166.033744)
		(end 142.643756 166.202499)
		(width 0.1)
		(layer "In2.Cu")
		(net 163)
	)
	(segment
		(start 146.87 155.65)
		(end 146.87 156.601422)
		(width 0.1)
		(layer "In2.Cu")
		(net 163)
	)
	(segment
		(start 142.875001 166.104499)
		(end 142.875001 165.8025)
		(width 0.1)
		(layer "In2.Cu")
		(net 163)
	)
	(segment
		(start 146.165337 150.8)
		(end 147.374663 150.8)
		(width 0.1)
		(layer "In2.Cu")
		(net 163)
	)
	(segment
		(start 142.475001 165.593922)
		(end 142.475001 166.033744)
		(width 0.1)
		(layer "In2.Cu")
		(net 163)
	)
	(segment
		(start 146.165337 152.5)
		(end 147.374663 152.5)
		(width 0.1)
		(layer "In2.Cu")
		(net 163)
	)
	(segment
		(start 146.87 156.601422)
		(end 143.475001 159.996421)
		(width 0.1)
		(layer "In2.Cu")
		(net 163)
	)
	(segment
		(start 146.165337 152.8)
		(end 147.374663 152.8)
		(width 0.1)
		(layer "In2.Cu")
		(net 163)
	)
	(segment
		(start 142.777001 166.202499)
		(end 142.875001 166.104499)
		(width 0.1)
		(layer "In2.Cu")
		(net 163)
	)
	(segment
		(start 146.165337 154.5)
		(end 147.374663 154.5)
		(width 0.1)
		(layer "In2.Cu")
		(net 163)
	)
	(segment
		(start 143.475001 165.093922)
		(end 143.166423 165.4025)
		(width 0.1)
		(layer "In2.Cu")
		(net 163)
	)
	(arc
		(start 147.374663 150.8)
		(mid 147.62215 150.902513)
		(end 147.724663 151.15)
		(width 0.1)
		(layer "In2.Cu")
		(net 163)
	)
	(arc
		(start 146.015337 150.65)
		(mid 146.059271 150.756066)
		(end 146.165337 150.8)
		(width 0.1)
		(layer "In2.Cu")
		(net 163)
	)
	(arc
		(start 146.015337 154.65)
		(mid 146.059271 154.756066)
		(end 146.165337 154.8)
		(width 0.1)
		(layer "In2.Cu")
		(net 163)
	)
	(arc
		(start 147.374663 152.8)
		(mid 147.62215 152.902513)
		(end 147.724663 153.15)
		(width 0.1)
		(layer "In2.Cu")
		(net 163)
	)
	(arc
		(start 146.165337 150.5)
		(mid 146.059271 150.543934)
		(end 146.015337 150.65)
		(width 0.1)
		(layer "In2.Cu")
		(net 163)
	)
	(arc
		(start 146.015337 151.65)
		(mid 146.059271 151.756066)
		(end 146.165337 151.8)
		(width 0.1)
		(layer "In2.Cu")
		(net 163)
	)
	(arc
		(start 146.165337 152.5)
		(mid 146.059271 152.543934)
		(end 146.015337 152.65)
		(width 0.1)
		(layer "In2.Cu")
		(net 163)
	)
	(arc
		(start 147.374663 153.8)
		(mid 147.62215 153.902513)
		(end 147.724663 154.15)
		(width 0.1)
		(layer "In2.Cu")
		(net 163)
	)
	(arc
		(start 146.165337 153.5)
		(mid 146.059271 153.543934)
		(end 146.015337 153.65)
		(width 0.1)
		(layer "In2.Cu")
		(net 163)
	)
	(arc
		(start 147.724663 154.15)
		(mid 147.62215 154.397487)
		(end 147.374663 154.5)
		(width 0.1)
		(layer "In2.Cu")
		(net 163)
	)
	(arc
		(start 147.724663 151.15)
		(mid 147.62215 151.397487)
		(end 147.374663 151.5)
		(width 0.1)
		(layer "In2.Cu")
		(net 163)
	)
	(arc
		(start 147.374663 151.8)
		(mid 147.62215 151.902513)
		(end 147.724663 152.15)
		(width 0.1)
		(layer "In2.Cu")
		(net 163)
	)
	(arc
		(start 146.165337 154.5)
		(mid 146.059271 154.543934)
		(end 146.015337 154.65)
		(width 0.1)
		(layer "In2.Cu")
		(net 163)
	)
	(arc
		(start 146.015337 152.65)
		(mid 146.059271 152.756066)
		(end 146.165337 152.8)
		(width 0.1)
		(layer "In2.Cu")
		(net 163)
	)
	(arc
		(start 147.02 155.5)
		(mid 146.913934 155.543934)
		(end 146.87 155.65)
		(width 0.1)
		(layer "In2.Cu")
		(net 163)
	)
	(arc
		(start 147.724663 155.15)
		(mid 147.62215 155.397487)
		(end 147.374663 155.5)
		(width 0.1)
		(layer "In2.Cu")
		(net 163)
	)
	(arc
		(start 146.165337 151.5)
		(mid 146.059271 151.543934)
		(end 146.015337 151.65)
		(width 0.1)
		(layer "In2.Cu")
		(net 163)
	)
	(arc
		(start 146.015337 153.65)
		(mid 146.059271 153.756066)
		(end 146.165337 153.8)
		(width 0.1)
		(layer "In2.Cu")
		(net 163)
	)
	(arc
		(start 147.724663 153.15)
		(mid 147.62215 153.397487)
		(end 147.374663 153.5)
		(width 0.1)
		(layer "In2.Cu")
		(net 163)
	)
	(arc
		(start 147.374663 154.8)
		(mid 147.62215 154.902513)
		(end 147.724663 155.15)
		(width 0.1)
		(layer "In2.Cu")
		(net 163)
	)
	(arc
		(start 147.724663 152.15)
		(mid 147.62215 152.397487)
		(end 147.374663 152.5)
		(width 0.1)
		(layer "In2.Cu")
		(net 163)
	)
	(arc
		(start 146.87 150.15)
		(mid 146.767487 150.397487)
		(end 146.52 150.5)
		(width 0.1)
		(layer "In2.Cu")
		(net 163)
	)
	(segment
		(start 142.625 138.1825)
		(end 142.625001 137.712573)
		(width 0.26)
		(layer "F.Cu")
		(net 164)
	)
	(segment
		(start 142.625001 137.712573)
		(end 142.67 137.667574)
		(width 0.26)
		(layer "F.Cu")
		(net 164)
	)
	(segment
		(start 139.375501 162.302)
		(end 139.875001 161.8025)
		(width 0.256)
		(layer "F.Cu")
		(net 164)
	)
	(segment
		(start 142.644999 138.2025)
		(end 142.625 138.1825)
		(width 0.26)
		(layer "F.Cu")
		(net 164)
	)
	(segment
		(start 142.644999 138.8025)
		(end 142.644999 138.2025)
		(width 0.26)
		(layer "F.Cu")
		(net 164)
	)
	(via
		(at 139.875001 161.8025)
		(size 0.45)
		(drill 0.1)
		(layers "F.Cu" "B.Cu")
		(net 164)
	)
	(via
		(at 142.675001 137.667574)
		(size 0.45)
		(drill 0.1)
		(layers "F.Cu" "B.Cu")
		(net 164)
	)
	(segment
		(start 141.616423 135.1025)
		(end 139.233579 135.1025)
		(width 0.1)
		(layer "In2.Cu")
		(net 164)
	)
	(segment
		(start 142.500001 135.986078)
		(end 142.500001 137.492574)
		(width 0.1)
		(layer "In2.Cu")
		(net 164)
	)
	(segment
		(start 140.275001 153.843922)
		(end 140.275001 162.061078)
		(width 0.1)
		(layer "In2.Cu")
		(net 164)
	)
	(segment
		(start 138.025001 136.311078)
		(end 138.025001 151.593922)
		(width 0.1)
		(layer "In2.Cu")
		(net 164)
	)
	(segment
		(start 142.500001 137.492574)
		(end 142.675001 137.667574)
		(width 0.1)
		(layer "In2.Cu")
		(net 164)
	)
	(segment
		(start 140.275001 162.061078)
		(end 140.133579 162.2025)
		(width 0.1)
		(layer "In2.Cu")
		(net 164)
	)
	(segment
		(start 138.025001 151.593922)
		(end 140.275001 153.843922)
		(width 0.1)
		(layer "In2.Cu")
		(net 164)
	)
	(segment
		(start 139.875001 162.1005)
		(end 139.875001 161.8025)
		(width 0.1)
		(layer "In2.Cu")
		(net 164)
	)
	(segment
		(start 141.616423 135.1025)
		(end 142.500001 135.986078)
		(width 0.1)
		(layer "In2.Cu")
		(net 164)
	)
	(segment
		(start 140.133579 162.2025)
		(end 139.977001 162.2025)
		(width 0.1)
		(layer "In2.Cu")
		(net 164)
	)
	(segment
		(start 139.233579 135.1025)
		(end 138.025001 136.311078)
		(width 0.1)
		(layer "In2.Cu")
		(net 164)
	)
	(segment
		(start 139.977001 162.2025)
		(end 139.875001 162.1005)
		(width 0.1)
		(layer "In2.Cu")
		(net 164)
	)
	(segment
		(start 141.375501 169.302)
		(end 141.875001 168.8025)
		(width 0.256)
		(layer "F.Cu")
		(net 165)
	)
	(segment
		(start 143.650001 138.8025)
		(end 143.650001 137.7275)
		(width 0.201)
		(layer "F.Cu")
		(net 165)
	)
	(via
		(at 143.650001 137.7275)
		(size 0.45)
		(drill 0.1)
		(layers "F.Cu" "B.Cu")
		(net 165)
	)
	(via
		(at 141.875001 168.8025)
		(size 0.45)
		(drill 0.1)
		(layers "F.Cu" "B.Cu")
		(net 165)
	)
	(segment
		(start 137.452001 163.44717)
		(end 137.721671 163.1775)
		(width 0.1)
		(layer "In6.Cu")
		(net 165)
	)
	(segment
		(start 138.477001 168.3025)
		(end 138.277001 168.1025)
		(width 0.1)
		(layer "In6.Cu")
		(net 165)
	)
	(segment
		(start 141.401501 169.276)
		(end 139.650501 169.276)
		(width 0.1)
		(layer "In6.Cu")
		(net 165)
	)
	(segment
		(start 143.1 141.83825)
		(end 144.600501 140.337749)
		(width 0.1)
		(layer "In6.Cu")
		(net 165)
	)
	(segment
		(start 138.452001 161.0275)
		(end 137.7 160.275499)
		(width 0.1)
		(layer "In6.Cu")
		(net 165)
	)
	(segment
		(start 135.3 153.55)
		(end 135.3 153)
		(width 0.1)
		(layer "In6.Cu")
		(net 165)
	)
	(segment
		(start 135.3 146.7)
		(end 135.98 146.02)
		(width 0.1)
		(layer "In6.Cu")
		(net 165)
	)
	(segment
		(start 135.558376 152.4)
		(end 135.5 152.4)
		(width 0.1)
		(layer "In6.Cu")
		(net 165)
	)
	(segment
		(start 138.277001 168.1025)
		(end 138.277001 167.5025)
		(width 0.1)
		(layer "In6.Cu")
		(net 165)
	)
	(segment
		(start 138.050501 167.276)
		(end 137.81817 167.276)
		(width 0.1)
		(layer "In6.Cu")
		(net 165)
	)
	(segment
		(start 137.452001 164.040674)
		(end 137.452001 163.44717)
		(width 0.1)
		(layer "In6.Cu")
		(net 165)
	)
	(segment
		(start 138.277001 167.5025)
		(end 138.050501 167.276)
		(width 0.1)
		(layer "In6.Cu")
		(net 165)
	)
	(segment
		(start 144.600501 140.337749)
		(end 144.600501 138.678)
		(width 0.1)
		(layer "In6.Cu")
		(net 165)
	)
	(segment
		(start 137.7 155.95)
		(end 135.3 153.55)
		(width 0.1)
		(layer "In6.Cu")
		(net 165)
	)
	(segment
		(start 139.650501 169.276)
		(end 138.677001 168.3025)
		(width 0.1)
		(layer "In6.Cu")
		(net 165)
	)
	(segment
		(start 138.677001 168.3025)
		(end 138.477001 168.3025)
		(width 0.1)
		(layer "In6.Cu")
		(net 165)
	)
	(segment
		(start 138.032333 163.1775)
		(end 138.452001 162.757832)
		(width 0.1)
		(layer "In6.Cu")
		(net 165)
	)
	(segment
		(start 143.1 143)
		(end 143.1 141.83825)
		(width 0.1)
		(layer "In6.Cu")
		(net 165)
	)
	(segment
		(start 141.875001 168.8025)
		(end 141.401501 169.276)
		(width 0.1)
		(layer "In6.Cu")
		(net 165)
	)
	(segment
		(start 137.721671 163.1775)
		(end 138.032333 163.1775)
		(width 0.1)
		(layer "In6.Cu")
		(net 165)
	)
	(segment
		(start 142.4 143.7)
		(end 143.1 143)
		(width 0.1)
		(layer "In6.Cu")
		(net 165)
	)
	(segment
		(start 137.81817 167.276)
		(end 137.400501 166.858331)
		(width 0.1)
		(layer "In6.Cu")
		(net 165)
	)
	(segment
		(start 135.5 152.8)
		(end 135.558376 152.8)
		(width 0.1)
		(layer "In6.Cu")
		(net 165)
	)
	(segment
		(start 137.7 160.275499)
		(end 137.7 155.95)
		(width 0.1)
		(layer "In6.Cu")
		(net 165)
	)
	(segment
		(start 138.452001 162.757832)
		(end 138.452001 161.0275)
		(width 0.1)
		(layer "In6.Cu")
		(net 165)
	)
	(segment
		(start 137.400501 166.858331)
		(end 137.400501 164.092174)
		(width 0.1)
		(layer "In6.Cu")
		(net 165)
	)
	(segment
		(start 135.3 152.15)
		(end 135.3 146.7)
		(width 0.1)
		(layer "In6.Cu")
		(net 165)
	)
	(segment
		(start 137.400501 164.092174)
		(end 137.452001 164.040674)
		(width 0.1)
		(layer "In6.Cu")
		(net 165)
	)
	(segment
		(start 137.18 146.02)
		(end 139.5 143.7)
		(width 0.1)
		(layer "In6.Cu")
		(net 165)
	)
	(segment
		(start 139.5 143.7)
		(end 142.4 143.7)
		(width 0.1)
		(layer "In6.Cu")
		(net 165)
	)
	(segment
		(start 135.3 152.2)
		(end 135.3 152.15)
		(width 0.1)
		(layer "In6.Cu")
		(net 165)
	)
	(segment
		(start 135.98 146.02)
		(end 137.18 146.02)
		(width 0.1)
		(layer "In6.Cu")
		(net 165)
	)
	(segment
		(start 144.600501 138.678)
		(end 143.650001 137.7275)
		(width 0.1)
		(layer "In6.Cu")
		(net 165)
	)
	(arc
		(start 135.3 153)
		(mid 135.358579 152.858579)
		(end 135.5 152.8)
		(width 0.1)
		(layer "In6.Cu")
		(net 165)
	)
	(arc
		(start 135.5 152.4)
		(mid 135.358579 152.341421)
		(end 135.3 152.2)
		(width 0.1)
		(layer "In6.Cu")
		(net 165)
	)
	(arc
		(start 135.558376 152.8)
		(mid 135.699797 152.741421)
		(end 135.758376 152.6)
		(width 0.1)
		(layer "In6.Cu")
		(net 165)
	)
	(arc
		(start 135.758376 152.6)
		(mid 135.699797 152.458579)
		(end 135.558376 152.4)
		(width 0.1)
		(layer "In6.Cu")
		(net 165)
	)
	(segment
		(start 143.9 146.2025)
		(end 143.900001 145.1275)
		(width 0.201)
		(layer "F.Cu")
		(net 166)
	)
	(segment
		(start 142.375501 169.302)
		(end 142.875001 168.8025)
		(width 0.256)
		(layer "F.Cu")
		(net 166)
	)
	(via
		(at 142.875001 168.8025)
		(size 0.45)
		(drill 0.1)
		(layers "F.Cu" "B.Cu")
		(net 166)
	)
	(via
		(at 143.900001 145.1275)
		(size 0.45)
		(drill 0.1)
		(layers "F.Cu" "B.Cu")
		(net 166)
	)
	(segment
		(start 139.377001 167.7025)
		(end 139.377001 168.1025)
		(width 0.1)
		(layer "In6.Cu")
		(net 166)
	)
	(segment
		(start 136.66 148.36)
		(end 136.162063 148.36)
		(width 0.1)
		(layer "In6.Cu")
		(net 166)
	)
	(segment
		(start 138.652001 160.9035)
		(end 138.652001 162.840674)
		(width 0.1)
		(layer "In6.Cu")
		(net 166)
	)
	(segment
		(start 138.677001 167.3025)
		(end 138.977001 167.3025)
		(width 0.1)
		(layer "In6.Cu")
		(net 166)
	)
	(segment
		(start 136.66 147.96)
		(end 136.757937 147.96)
		(width 0.1)
		(layer "In6.Cu")
		(net 166)
	)
	(segment
		(start 136.162063 150.36)
		(end 136.757937 150.36)
		(width 0.1)
		(layer "In6.Cu")
		(net 166)
	)
	(segment
		(start 143.900001 145.1275)
		(end 143.348501 144.576)
		(width 0.1)
		(layer "In6.Cu")
		(net 166)
	)
	(segment
		(start 136.162063 148.76)
		(end 136.757937 148.76)
		(width 0.1)
		(layer "In6.Cu")
		(net 166)
	)
	(segment
		(start 138.652001 162.840674)
		(end 138.300501 163.192174)
		(width 0.1)
		(layer "In6.Cu")
		(net 166)
	)
	(segment
		(start 138.125001 155.375001)
		(end 138.125001 160.3765)
		(width 0.1)
		(layer "In6.Cu")
		(net 166)
	)
	(segment
		(start 136.162063 149.96)
		(end 136.757937 149.96)
		(width 0.1)
		(layer "In6.Cu")
		(net 166)
	)
	(segment
		(start 136.162063 149.56)
		(end 136.757937 149.56)
		(width 0.1)
		(layer "In6.Cu")
		(net 166)
	)
	(segment
		(start 138.300501 163.192174)
		(end 138.300501 166.926)
		(width 0.1)
		(layer "In6.Cu")
		(net 166)
	)
	(segment
		(start 136.162063 151.16)
		(end 136.26 151.16)
		(width 0.1)
		(layer "In6.Cu")
		(net 166)
	)
	(segment
		(start 143.348501 144.576)
		(end 139.424 144.576)
		(width 0.1)
		(layer "In6.Cu")
		(net 166)
	)
	(segment
		(start 136.46 146.91)
		(end 136.46 147.76)
		(width 0.1)
		(layer "In6.Cu")
		(net 166)
	)
	(segment
		(start 139.677001 168.4025)
		(end 142.475001 168.4025)
		(width 0.1)
		(layer "In6.Cu")
		(net 166)
	)
	(segment
		(start 136.162063 149.16)
		(end 136.757937 149.16)
		(width 0.1)
		(layer "In6.Cu")
		(net 166)
	)
	(segment
		(start 136.757937 148.36)
		(end 136.66 148.36)
		(width 0.1)
		(layer "In6.Cu")
		(net 166)
	)
	(segment
		(start 142.475001 168.4025)
		(end 142.875001 168.8025)
		(width 0.1)
		(layer "In6.Cu")
		(net 166)
	)
	(segment
		(start 138.125001 160.3765)
		(end 138.652001 160.9035)
		(width 0.1)
		(layer "In6.Cu")
		(net 166)
	)
	(segment
		(start 136.162063 150.76)
		(end 136.757937 150.76)
		(width 0.1)
		(layer "In6.Cu")
		(net 166)
	)
	(segment
		(start 139.377001 168.1025)
		(end 139.677001 168.4025)
		(width 0.1)
		(layer "In6.Cu")
		(net 166)
	)
	(segment
		(start 137.4 146.6)
		(end 136.77 146.6)
		(width 0.1)
		(layer "In6.Cu")
		(net 166)
	)
	(segment
		(start 136.77 146.6)
		(end 136.46 146.91)
		(width 0.1)
		(layer "In6.Cu")
		(net 166)
	)
	(segment
		(start 136.46 151.36)
		(end 136.46 153.71)
		(width 0.1)
		(layer "In6.Cu")
		(net 166)
	)
	(segment
		(start 138.977001 167.3025)
		(end 139.377001 167.7025)
		(width 0.1)
		(layer "In6.Cu")
		(net 166)
	)
	(segment
		(start 139.424 144.576)
		(end 137.4 146.6)
		(width 0.1)
		(layer "In6.Cu")
		(net 166)
	)
	(segment
		(start 136.46 153.71)
		(end 138.125001 155.375001)
		(width 0.1)
		(layer "In6.Cu")
		(net 166)
	)
	(segment
		(start 138.300501 166.926)
		(end 138.677001 167.3025)
		(width 0.1)
		(layer "In6.Cu")
		(net 166)
	)
	(arc
		(start 135.962063 149.36)
		(mid 136.020642 149.501421)
		(end 136.162063 149.56)
		(width 0.1)
		(layer "In6.Cu")
		(net 166)
	)
	(arc
		(start 136.162063 150.76)
		(mid 136.020642 150.818579)
		(end 135.962063 150.96)
		(width 0.1)
		(layer "In6.Cu")
		(net 166)
	)
	(arc
		(start 136.957937 148.96)
		(mid 136.899358 149.101421)
		(end 136.757937 149.16)
		(width 0.1)
		(layer "In6.Cu")
		(net 166)
	)
	(arc
		(start 136.162063 148.36)
		(mid 136.020642 148.418579)
		(end 135.962063 148.56)
		(width 0.1)
		(layer "In6.Cu")
		(net 166)
	)
	(arc
		(start 135.962063 148.56)
		(mid 136.020642 148.701421)
		(end 136.162063 148.76)
		(width 0.1)
		(layer "In6.Cu")
		(net 166)
	)
	(arc
		(start 136.957937 150.56)
		(mid 136.899358 150.701421)
		(end 136.757937 150.76)
		(width 0.1)
		(layer "In6.Cu")
		(net 166)
	)
	(arc
		(start 135.962063 150.16)
		(mid 136.020642 150.301421)
		(end 136.162063 150.36)
		(width 0.1)
		(layer "In6.Cu")
		(net 166)
	)
	(arc
		(start 136.26 151.16)
		(mid 136.401421 151.218579)
		(end 136.46 151.36)
		(width 0.1)
		(layer "In6.Cu")
		(net 166)
	)
	(arc
		(start 136.162063 149.96)
		(mid 136.020642 150.018579)
		(end 135.962063 150.16)
		(width 0.1)
		(layer "In6.Cu")
		(net 166)
	)
	(arc
		(start 136.957937 148.16)
		(mid 136.899358 148.301421)
		(end 136.757937 148.36)
		(width 0.1)
		(layer "In6.Cu")
		(net 166)
	)
	(arc
		(start 136.757937 150.36)
		(mid 136.899358 150.418579)
		(end 136.957937 150.56)
		(width 0.1)
		(layer "In6.Cu")
		(net 166)
	)
	(arc
		(start 136.957937 149.76)
		(mid 136.899358 149.901421)
		(end 136.757937 149.96)
		(width 0.1)
		(layer "In6.Cu")
		(net 166)
	)
	(arc
		(start 136.46 147.76)
		(mid 136.518579 147.901421)
		(end 136.66 147.96)
		(width 0.1)
		(layer "In6.Cu")
		(net 166)
	)
	(arc
		(start 136.162063 149.16)
		(mid 136.020642 149.218579)
		(end 135.962063 149.36)
		(width 0.1)
		(layer "In6.Cu")
		(net 166)
	)
	(arc
		(start 135.962063 150.96)
		(mid 136.020642 151.101421)
		(end 136.162063 151.16)
		(width 0.1)
		(layer "In6.Cu")
		(net 166)
	)
	(arc
		(start 136.757937 149.56)
		(mid 136.899358 149.618579)
		(end 136.957937 149.76)
		(width 0.1)
		(layer "In6.Cu")
		(net 166)
	)
	(arc
		(start 136.757937 148.76)
		(mid 136.899358 148.818579)
		(end 136.957937 148.96)
		(width 0.1)
		(layer "In6.Cu")
		(net 166)
	)
	(arc
		(start 136.757937 147.96)
		(mid 136.899358 148.018579)
		(end 136.957937 148.16)
		(width 0.1)
		(layer "In6.Cu")
		(net 166)
	)
	(segment
		(start 144.150001 138.8025)
		(end 144.15 139.877499)
		(width 0.201)
		(layer "F.Cu")
		(net 167)
	)
	(segment
		(start 141.375501 170.302)
		(end 141.875001 169.8025)
		(width 0.256)
		(layer "F.Cu")
		(net 167)
	)
	(via
		(at 144.15 139.877499)
		(size 0.45)
		(drill 0.1)
		(layers "F.Cu" "B.Cu")
		(net 167)
	)
	(via
		(at 141.875001 169.8025)
		(size 0.45)
		(drill 0.1)
		(layers "F.Cu" "B.Cu")
		(net 167)
	)
	(segment
		(start 137.409336 167.584835)
		(end 137.409336 167.984835)
		(width 0.1)
		(layer "In6.Cu")
		(net 167)
	)
	(segment
		(start 137.091666 167.267165)
		(end 137.409336 167.584835)
		(width 0.1)
		(layer "In6.Cu")
		(net 167)
	)
	(segment
		(start 144.15 139.877499)
		(end 143.027499 141)
		(width 0.1)
		(layer "In6.Cu")
		(net 167)
	)
	(segment
		(start 136.72167 164.1775)
		(end 136.400501 164.498669)
		(width 0.1)
		(layer "In6.Cu")
		(net 167)
	)
	(segment
		(start 139.250001 169.9255)
		(end 139.600501 170.276)
		(width 0.1)
		(layer "In6.Cu")
		(net 167)
	)
	(segment
		(start 137.72167 162.177499)
		(end 137.252001 162.647168)
		(width 0.1)
		(layer "In6.Cu")
		(net 167)
	)
	(segment
		(start 141.401501 170.276)
		(end 141.875001 169.8025)
		(width 0.1)
		(layer "In6.Cu")
		(net 167)
	)
	(segment
		(start 139.600501 170.276)
		(end 141.401501 170.276)
		(width 0.1)
		(layer "In6.Cu")
		(net 167)
	)
	(segment
		(start 134.713895 148.8)
		(end 134.6 148.8)
		(width 0.1)
		(layer "In6.Cu")
		(net 167)
	)
	(segment
		(start 137.727001 168.3025)
		(end 137.992167 168.3025)
		(width 0.1)
		(layer "In6.Cu")
		(net 167)
	)
	(segment
		(start 137.032332 164.1775)
		(end 136.72167 164.1775)
		(width 0.1)
		(layer "In6.Cu")
		(net 167)
	)
	(segment
		(start 136.400501 164.498669)
		(end 136.400501 166.85833)
		(width 0.1)
		(layer "In6.Cu")
		(net 167)
	)
	(segment
		(start 137.200501 156.376)
		(end 137.200501 160.160842)
		(width 0.1)
		(layer "In6.Cu")
		(net 167)
	)
	(segment
		(start 134.2 148)
		(end 134.086105 148)
		(width 0.1)
		(layer "In6.Cu")
		(net 167)
	)
	(segment
		(start 134.086105 148.4)
		(end 134.713895 148.4)
		(width 0.1)
		(layer "In6.Cu")
		(net 167)
	)
	(segment
		(start 143.027499 141)
		(end 138.9 141)
		(width 0.1)
		(layer "In6.Cu")
		(net 167)
	)
	(segment
		(start 134.96 144.94)
		(end 134.96 145.77)
		(width 0.1)
		(layer "In6.Cu")
		(net 167)
	)
	(segment
		(start 137.200501 160.160842)
		(end 138.252001 161.212342)
		(width 0.1)
		(layer "In6.Cu")
		(net 167)
	)
	(segment
		(start 134.4 153.575499)
		(end 137.200501 156.376)
		(width 0.1)
		(layer "In6.Cu")
		(net 167)
	)
	(segment
		(start 134.4 146.33)
		(end 134.4 147.8)
		(width 0.1)
		(layer "In6.Cu")
		(net 167)
	)
	(segment
		(start 138.032332 162.177499)
		(end 137.72167 162.177499)
		(width 0.1)
		(layer "In6.Cu")
		(net 167)
	)
	(segment
		(start 139.250001 169.560334)
		(end 139.250001 169.9255)
		(width 0.1)
		(layer "In6.Cu")
		(net 167)
	)
	(segment
		(start 136.809336 167.267165)
		(end 137.091666 167.267165)
		(width 0.1)
		(layer "In6.Cu")
		(net 167)
	)
	(segment
		(start 137.252001 162.647168)
		(end 137.252001 163.957831)
		(width 0.1)
		(layer "In6.Cu")
		(net 167)
	)
	(segment
		(start 137.992167 168.3025)
		(end 139.250001 169.560334)
		(width 0.1)
		(layer "In6.Cu")
		(net 167)
	)
	(segment
		(start 136.400501 166.85833)
		(end 136.809336 167.267165)
		(width 0.1)
		(layer "In6.Cu")
		(net 167)
	)
	(segment
		(start 138.9 141)
		(end 134.96 144.94)
		(width 0.1)
		(layer "In6.Cu")
		(net 167)
	)
	(segment
		(start 134.96 145.77)
		(end 134.4 146.33)
		(width 0.1)
		(layer "In6.Cu")
		(net 167)
	)
	(segment
		(start 137.252001 163.957831)
		(end 137.032332 164.1775)
		(width 0.1)
		(layer "In6.Cu")
		(net 167)
	)
	(segment
		(start 134.4 149)
		(end 134.4 153.575499)
		(width 0.1)
		(layer "In6.Cu")
		(net 167)
	)
	(segment
		(start 138.252001 161.212342)
		(end 138.252001 161.95783)
		(width 0.1)
		(layer "In6.Cu")
		(net 167)
	)
	(segment
		(start 137.409336 167.984835)
		(end 137.727001 168.3025)
		(width 0.1)
		(layer "In6.Cu")
		(net 167)
	)
	(segment
		(start 138.252001 161.95783)
		(end 138.032332 162.177499)
		(width 0.1)
		(layer "In6.Cu")
		(net 167)
	)
	(arc
		(start 134.6 148.8)
		(mid 134.458579 148.858579)
		(end 134.4 149)
		(width 0.1)
		(layer "In6.Cu")
		(net 167)
	)
	(arc
		(start 134.4 147.8)
		(mid 134.341421 147.941421)
		(end 134.2 148)
		(width 0.1)
		(layer "In6.Cu")
		(net 167)
	)
	(arc
		(start 134.913895 148.6)
		(mid 134.855316 148.741421)
		(end 134.713895 148.8)
		(width 0.1)
		(layer "In6.Cu")
		(net 167)
	)
	(arc
		(start 133.886105 148.2)
		(mid 133.944684 148.341421)
		(end 134.086105 148.4)
		(width 0.1)
		(layer "In6.Cu")
		(net 167)
	)
	(arc
		(start 134.086105 148)
		(mid 133.944684 148.058579)
		(end 133.886105 148.2)
		(width 0.1)
		(layer "In6.Cu")
		(net 167)
	)
	(arc
		(start 134.713895 148.4)
		(mid 134.855316 148.458579)
		(end 134.913895 148.6)
		(width 0.1)
		(layer "In6.Cu")
		(net 167)
	)
	(segment
		(start 144.900001 146.2025)
		(end 144.900001 145.127499)
		(width 0.201)
		(layer "F.Cu")
		(net 168)
	)
	(segment
		(start 140.375501 168.302)
		(end 140.875001 167.8025)
		(width 0.256)
		(layer "F.Cu")
		(net 168)
	)
	(via
		(at 144.900001 145.127499)
		(size 0.45)
		(drill 0.1)
		(layers "F.Cu" "B.Cu")
		(net 168)
	)
	(via
		(at 140.875001 167.8025)
		(size 0.45)
		(drill 0.1)
		(layers "F.Cu" "B.Cu")
		(net 168)
	)
	(segment
		(start 139.500001 166.444658)
		(end 139.500001 166.957831)
		(width 0.1)
		(layer "In6.Cu")
		(net 168)
	)
	(segment
		(start 139.052001 154.302001)
		(end 139.052001 165.996658)
		(width 0.1)
		(layer "In6.Cu")
		(net 168)
	)
	(segment
		(start 138.58 153.83)
		(end 139.052001 154.302001)
		(width 0.1)
		(layer "In6.Cu")
		(net 168)
	)
	(segment
		(start 138.20367 152.67)
		(end 138.33 152.67)
		(width 0.1)
		(layer "In6.Cu")
		(net 168)
	)
	(segment
		(start 139.500001 166.957831)
		(end 139.79467 167.2525)
		(width 0.1)
		(layer "In6.Cu")
		(net 168)
	)
	(segment
		(start 138.58 152.92)
		(end 138.58 153.83)
		(width 0.1)
		(layer "In6.Cu")
		(net 168)
	)
	(segment
		(start 140.501001 167.8025)
		(end 140.875001 167.8025)
		(width 0.1)
		(layer "In6.Cu")
		(net 168)
	)
	(segment
		(start 139.052001 165.996658)
		(end 139.500001 166.444658)
		(width 0.1)
		(layer "In6.Cu")
		(net 168)
	)
	(segment
		(start 138.20367 151.67)
		(end 138.95633 151.67)
		(width 0.1)
		(layer "In6.Cu")
		(net 168)
	)
	(segment
		(start 144.457843 146.476)
		(end 139.414 146.476)
		(width 0.1)
		(layer "In6.Cu")
		(net 168)
	)
	(segment
		(start 138.20367 151.17)
		(end 138.95633 151.17)
		(width 0.1)
		(layer "In6.Cu")
		(net 168)
	)
	(segment
		(start 139.414 146.476)
		(end 138.58 147.31)
		(width 0.1)
		(layer "In6.Cu")
		(net 168)
	)
	(segment
		(start 139.951001 167.2525)
		(end 140.501001 167.8025)
		(width 0.1)
		(layer "In6.Cu")
		(net 168)
	)
	(segment
		(start 138.20367 149.67)
		(end 138.95633 149.67)
		(width 0.1)
		(layer "In6.Cu")
		(net 168)
	)
	(segment
		(start 144.900001 145.127499)
		(end 144.900001 146.033842)
		(width 0.1)
		(layer "In6.Cu")
		(net 168)
	)
	(segment
		(start 138.58 147.31)
		(end 138.58 147.42)
		(width 0.1)
		(layer "In6.Cu")
		(net 168)
	)
	(segment
		(start 139.79467 167.2525)
		(end 139.951001 167.2525)
		(width 0.1)
		(layer "In6.Cu")
		(net 168)
	)
	(segment
		(start 138.20367 152.17)
		(end 138.95633 152.17)
		(width 0.1)
		(layer "In6.Cu")
		(net 168)
	)
	(segment
		(start 138.20367 148.67)
		(end 138.95633 148.67)
		(width 0.1)
		(layer "In6.Cu")
		(net 168)
	)
	(segment
		(start 144.900001 146.033842)
		(end 144.457843 146.476)
		(width 0.1)
		(layer "In6.Cu")
		(net 168)
	)
	(segment
		(start 138.20367 148.17)
		(end 138.95633 148.17)
		(width 0.1)
		(layer "In6.Cu")
		(net 168)
	)
	(segment
		(start 138.83 147.67)
		(end 138.95633 147.67)
		(width 0.1)
		(layer "In6.Cu")
		(net 168)
	)
	(segment
		(start 138.20367 150.67)
		(end 138.95633 150.67)
		(width 0.1)
		(layer "In6.Cu")
		(net 168)
	)
	(segment
		(start 138.20367 149.17)
		(end 138.95633 149.17)
		(width 0.1)
		(layer "In6.Cu")
		(net 168)
	)
	(segment
		(start 138.20367 150.17)
		(end 138.95633 150.17)
		(width 0.1)
		(layer "In6.Cu")
		(net 168)
	)
	(arc
		(start 137.95367 148.42)
		(mid 138.026893 148.596777)
		(end 138.20367 148.67)
		(width 0.1)
		(layer "In6.Cu")
		(net 168)
	)
	(arc
		(start 137.95367 152.42)
		(mid 138.026893 152.596777)
		(end 138.20367 152.67)
		(width 0.1)
		(layer "In6.Cu")
		(net 168)
	)
	(arc
		(start 138.20367 152.17)
		(mid 138.026893 152.243223)
		(end 137.95367 152.42)
		(width 0.1)
		(layer "In6.Cu")
		(net 168)
	)
	(arc
		(start 139.20633 148.92)
		(mid 139.133107 149.096777)
		(end 138.95633 149.17)
		(width 0.1)
		(layer "In6.Cu")
		(net 168)
	)
	(arc
		(start 139.20633 150.92)
		(mid 139.133107 151.096777)
		(end 138.95633 151.17)
		(width 0.1)
		(layer "In6.Cu")
		(net 168)
	)
	(arc
		(start 137.95367 149.42)
		(mid 138.026893 149.596777)
		(end 138.20367 149.67)
		(width 0.1)
		(layer "In6.Cu")
		(net 168)
	)
	(arc
		(start 138.33 152.67)
		(mid 138.506777 152.743223)
		(end 138.58 152.92)
		(width 0.1)
		(layer "In6.Cu")
		(net 168)
	)
	(arc
		(start 138.95633 148.67)
		(mid 139.133107 148.743223)
		(end 139.20633 148.92)
		(width 0.1)
		(layer "In6.Cu")
		(net 168)
	)
	(arc
		(start 138.20367 149.17)
		(mid 138.026893 149.243223)
		(end 137.95367 149.42)
		(width 0.1)
		(layer "In6.Cu")
		(net 168)
	)
	(arc
		(start 137.95367 150.42)
		(mid 138.026893 150.596777)
		(end 138.20367 150.67)
		(width 0.1)
		(layer "In6.Cu")
		(net 168)
	)
	(arc
		(start 138.20367 150.17)
		(mid 138.026893 150.243223)
		(end 137.95367 150.42)
		(width 0.1)
		(layer "In6.Cu")
		(net 168)
	)
	(arc
		(start 138.95633 150.67)
		(mid 139.133107 150.743223)
		(end 139.20633 150.92)
		(width 0.1)
		(layer "In6.Cu")
		(net 168)
	)
	(arc
		(start 139.20633 147.92)
		(mid 139.133107 148.096777)
		(end 138.95633 148.17)
		(width 0.1)
		(layer "In6.Cu")
		(net 168)
	)
	(arc
		(start 138.58 147.42)
		(mid 138.653223 147.596777)
		(end 138.83 147.67)
		(width 0.1)
		(layer "In6.Cu")
		(net 168)
	)
	(arc
		(start 138.20367 151.17)
		(mid 138.026893 151.243223)
		(end 137.95367 151.42)
		(width 0.1)
		(layer "In6.Cu")
		(net 168)
	)
	(arc
		(start 139.20633 151.92)
		(mid 139.133107 152.096777)
		(end 138.95633 152.17)
		(width 0.1)
		(layer "In6.Cu")
		(net 168)
	)
	(arc
		(start 139.20633 149.92)
		(mid 139.133107 150.096777)
		(end 138.95633 150.17)
		(width 0.1)
		(layer "In6.Cu")
		(net 168)
	)
	(arc
		(start 138.95633 147.67)
		(mid 139.133107 147.743223)
		(end 139.20633 147.92)
		(width 0.1)
		(layer "In6.Cu")
		(net 168)
	)
	(arc
		(start 138.20367 148.17)
		(mid 138.026893 148.243223)
		(end 137.95367 148.42)
		(width 0.1)
		(layer "In6.Cu")
		(net 168)
	)
	(arc
		(start 138.95633 151.67)
		(mid 139.133107 151.743223)
		(end 139.20633 151.92)
		(width 0.1)
		(layer "In6.Cu")
		(net 168)
	)
	(arc
		(start 137.95367 151.42)
		(mid 138.026893 151.596777)
		(end 138.20367 151.67)
		(width 0.1)
		(layer "In6.Cu")
		(net 168)
	)
	(arc
		(start 138.95633 149.67)
		(mid 139.133107 149.743223)
		(end 139.20633 149.92)
		(width 0.1)
		(layer "In6.Cu")
		(net 168)
	)
	(segment
		(start 145.15 138.8025)
		(end 145.15 139.877498)
		(width 0.201)
		(layer "F.Cu")
		(net 169)
	)
	(segment
		(start 139.375501 168.302)
		(end 139.875001 167.8025)
		(width 0.256)
		(layer "F.Cu")
		(net 169)
	)
	(via
		(at 145.15 139.877498)
		(size 0.45)
		(drill 0.1)
		(layers "F.Cu" "B.Cu")
		(net 169)
	)
	(via
		(at 139.875001 167.8025)
		(size 0.45)
		(drill 0.1)
		(layers "F.Cu" "B.Cu")
		(net 169)
	)
	(segment
		(start 144.440628 143.85)
		(end 144.35 143.85)
		(width 0.1)
		(layer "In6.Cu")
		(net 169)
	)
	(segment
		(start 138.700501 163.075016)
		(end 138.700501 166.002)
		(width 0.1)
		(layer "In6.Cu")
		(net 169)
	)
	(segment
		(start 138.974 145.776)
		(end 137.51 147.24)
		(width 0.1)
		(layer "In6.Cu")
		(net 169)
	)
	(segment
		(start 144.400501 145.476)
		(end 144.100501 145.776)
		(width 0.1)
		(layer "In6.Cu")
		(net 169)
	)
	(segment
		(start 144.1 144.1)
		(end 144.1 144.6)
		(width 0.1)
		(layer "In6.Cu")
		(net 169)
	)
	(segment
		(start 138.600501 155.000501)
		(end 138.600501 160.495158)
		(width 0.1)
		(layer "In6.Cu")
		(net 169)
	)
	(segment
		(start 143.759372 142.85)
		(end 144.440628 142.85)
		(width 0.1)
		(layer "In6.Cu")
		(net 169)
	)
	(segment
		(start 145.15 139.877498)
		(end 145.15 140.519125)
		(width 0.1)
		(layer "In6.Cu")
		(net 169)
	)
	(segment
		(start 144.1 141.569125)
		(end 144.1 141.6)
		(width 0.1)
		(layer "In6.Cu")
		(net 169)
	)
	(segment
		(start 144.400501 144.900501)
		(end 144.400501 145.476)
		(width 0.1)
		(layer "In6.Cu")
		(net 169)
	)
	(segment
		(start 138.600501 160.495158)
		(end 138.852001 160.746657)
		(width 0.1)
		(layer "In6.Cu")
		(net 169)
	)
	(segment
		(start 139.300501 166.602)
		(end 139.300501 167.228)
		(width 0.1)
		(layer "In6.Cu")
		(net 169)
	)
	(segment
		(start 139.300501 167.228)
		(end 139.875001 167.8025)
		(width 0.1)
		(layer "In6.Cu")
		(net 169)
	)
	(segment
		(start 143.85 142.35)
		(end 144.440628 142.35)
		(width 0.1)
		(layer "In6.Cu")
		(net 169)
	)
	(segment
		(start 144.1 144.6)
		(end 144.400501 144.900501)
		(width 0.1)
		(layer "In6.Cu")
		(net 169)
	)
	(segment
		(start 137.51 153.91)
		(end 138.600501 155.000501)
		(width 0.1)
		(layer "In6.Cu")
		(net 169)
	)
	(segment
		(start 138.852001 160.746657)
		(end 138.852001 162.923516)
		(width 0.1)
		(layer "In6.Cu")
		(net 169)
	)
	(segment
		(start 137.51 147.24)
		(end 137.51 153.91)
		(width 0.1)
		(layer "In6.Cu")
		(net 169)
	)
	(segment
		(start 145.15 140.519125)
		(end 144.1 141.569125)
		(width 0.1)
		(layer "In6.Cu")
		(net 169)
	)
	(segment
		(start 143.759372 143.35)
		(end 144.440628 143.35)
		(width 0.1)
		(layer "In6.Cu")
		(net 169)
	)
	(segment
		(start 144.100501 145.776)
		(end 138.974 145.776)
		(width 0.1)
		(layer "In6.Cu")
		(net 169)
	)
	(segment
		(start 143.85 141.85)
		(end 143.759372 141.85)
		(width 0.1)
		(layer "In6.Cu")
		(net 169)
	)
	(segment
		(start 138.852001 162.923516)
		(end 138.700501 163.075016)
		(width 0.1)
		(layer "In6.Cu")
		(net 169)
	)
	(segment
		(start 143.759372 142.35)
		(end 143.85 142.35)
		(width 0.1)
		(layer "In6.Cu")
		(net 169)
	)
	(segment
		(start 138.700501 166.002)
		(end 139.300501 166.602)
		(width 0.1)
		(layer "In6.Cu")
		(net 169)
	)
	(arc
		(start 144.690628 143.6)
		(mid 144.617405 143.776777)
		(end 144.440628 143.85)
		(width 0.1)
		(layer "In6.Cu")
		(net 169)
	)
	(arc
		(start 144.440628 142.35)
		(mid 144.617405 142.423223)
		(end 144.690628 142.6)
		(width 0.1)
		(layer "In6.Cu")
		(net 169)
	)
	(arc
		(start 143.759372 141.85)
		(mid 143.582595 141.923223)
		(end 143.509372 142.1)
		(width 0.1)
		(layer "In6.Cu")
		(net 169)
	)
	(arc
		(start 144.440628 143.35)
		(mid 144.617405 143.423223)
		(end 144.690628 143.6)
		(width 0.1)
		(layer "In6.Cu")
		(net 169)
	)
	(arc
		(start 143.759372 142.85)
		(mid 143.582595 142.923223)
		(end 143.509372 143.1)
		(width 0.1)
		(layer "In6.Cu")
		(net 169)
	)
	(arc
		(start 144.1 141.6)
		(mid 144.026777 141.776777)
		(end 143.85 141.85)
		(width 0.1)
		(layer "In6.Cu")
		(net 169)
	)
	(arc
		(start 144.35 143.85)
		(mid 144.173223 143.923223)
		(end 144.1 144.1)
		(width 0.1)
		(layer "In6.Cu")
		(net 169)
	)
	(arc
		(start 143.509372 142.1)
		(mid 143.582595 142.276777)
		(end 143.759372 142.35)
		(width 0.1)
		(layer "In6.Cu")
		(net 169)
	)
	(arc
		(start 144.690628 142.6)
		(mid 144.617405 142.776777)
		(end 144.440628 142.85)
		(width 0.1)
		(layer "In6.Cu")
		(net 169)
	)
	(arc
		(start 143.509372 143.1)
		(mid 143.582595 143.276777)
		(end 143.759372 143.35)
		(width 0.1)
		(layer "In6.Cu")
		(net 169)
	)
	(segment
		(start 145.400002 146.2025)
		(end 145.400001 147.277499)
		(width 0.201)
		(layer "F.Cu")
		(net 170)
	)
	(segment
		(start 139.375501 167.302)
		(end 139.875001 166.8025)
		(width 0.256)
		(layer "F.Cu")
		(net 170)
	)
	(via
		(at 145.400001 147.277499)
		(size 0.45)
		(drill 0.1)
		(layers "F.Cu" "B.Cu")
		(net 170)
	)
	(via
		(at 139.875001 166.8025)
		(size 0.45)
		(drill 0.1)
		(layers "F.Cu" "B.Cu")
		(net 170)
	)
	(segment
		(start 141.531813 150.368681)
		(end 141.531813 150.368682)
		(width 0.1)
		(layer "In6.Cu")
		(net 170)
	)
	(segment
		(start 140.966126 150.934368)
		(end 140.966126 150.934369)
		(width 0.1)
		(layer "In6.Cu")
		(net 170)
	)
	(segment
		(start 144.288724 149.165782)
		(end 144.288722 149.165783)
		(width 0.1)
		(layer "In6.Cu")
		(net 170)
	)
	(segment
		(start 143.15735 150.297156)
		(end 143.157348 150.297157)
		(width 0.1)
		(layer "In6.Cu")
		(net 170)
	)
	(segment
		(start 141.248969 150.934369)
		(end 141.743132 151.428531)
		(width 0.1)
		(layer "In6.Cu")
		(net 170)
	)
	(segment
		(start 143.794561 148.105933)
		(end 143.794561 148.105934)
		(width 0.1)
		(layer "In6.Cu")
		(net 170)
	)
	(segment
		(start 141.460289 151.994217)
		(end 141.460287 151.994218)
		(width 0.1)
		(layer "In6.Cu")
		(net 170)
	)
	(segment
		(start 140.683282 151.500056)
		(end 141.177445 151.994218)
		(width 0.1)
		(layer "In6.Cu")
		(net 170)
	)
	(segment
		(start 139.834752 152.065742)
		(end 139.834752 152.065743)
		(width 0.1)
		(layer "In6.Cu")
		(net 170)
	)
	(segment
		(start 139.400501 162.940701)
		(end 139.500501 163.040701)
		(width 0.1)
		(layer "In6.Cu")
		(net 170)
	)
	(segment
		(start 144.854409 148.600096)
		(end 144.85441 148.600096)
		(width 0.1)
		(layer "In6.Cu")
		(net 170)
	)
	(segment
		(start 139.500501 165.958331)
		(end 139.875001 166.332831)
		(width 0.1)
		(layer "In6.Cu")
		(net 170)
	)
	(segment
		(start 139.65757 153.019932)
		(end 139.400501 153.276999)
		(width 0.1)
		(layer "In6.Cu")
		(net 170)
	)
	(segment
		(start 144.74875 148.211594)
		(end 144.748749 148.211594)
		(width 0.1)
		(layer "In6.Cu")
		(net 170)
	)
	(segment
		(start 140.328915 153.125591)
		(end 140.328913 153.125592)
		(width 0.1)
		(layer "In6.Cu")
		(net 170)
	)
	(segment
		(start 142.591663 150.862843)
		(end 142.591661 150.862844)
		(width 0.1)
		(layer "In6.Cu")
		(net 170)
	)
	(segment
		(start 142.94603 149.237308)
		(end 143.440193 149.73147)
		(width 0.1)
		(layer "In6.Cu")
		(net 170)
	)
	(segment
		(start 139.400501 153.276999)
		(end 139.400501 162.940701)
		(width 0.1)
		(layer "In6.Cu")
		(net 170)
	)
	(segment
		(start 142.025976 151.42853)
		(end 142.025974 151.428531)
		(width 0.1)
		(layer "In6.Cu")
		(net 170)
	)
	(segment
		(start 140.046071 153.125592)
		(end 139.940412 153.019933)
		(width 0.1)
		(layer "In6.Cu")
		(net 170)
	)
	(segment
		(start 144.077404 148.105934)
		(end 144.571568 148.600096)
		(width 0.1)
		(layer "In6.Cu")
		(net 170)
	)
	(segment
		(start 145.400001 147.277499)
		(end 144.74875 147.92875)
		(width 0.1)
		(layer "In6.Cu")
		(net 170)
	)
	(segment
		(start 140.400439 151.500055)
		(end 140.400439 151.500056)
		(width 0.1)
		(layer "In6.Cu")
		(net 170)
	)
	(segment
		(start 144.748749 148.211594)
		(end 144.854409 148.317254)
		(width 0.1)
		(layer "In6.Cu")
		(net 170)
	)
	(segment
		(start 143.228874 148.67162)
		(end 143.228874 148.671621)
		(width 0.1)
		(layer "In6.Cu")
		(net 170)
	)
	(segment
		(start 142.663187 149.52015)
		(end 143.157349 150.014313)
		(width 0.1)
		(layer "In6.Cu")
		(net 170)
	)
	(segment
		(start 139.875001 166.332831)
		(end 139.875001 166.8025)
		(width 0.1)
		(layer "In6.Cu")
		(net 170)
	)
	(segment
		(start 139.834752 152.348585)
		(end 140.328914 152.842748)
		(width 0.1)
		(layer "In6.Cu")
		(net 170)
	)
	(segment
		(start 139.65757 153.019933)
		(end 139.65757 153.019932)
		(width 0.1)
		(layer "In6.Cu")
		(net 170)
	)
	(segment
		(start 142.380343 149.802995)
		(end 142.874506 150.297157)
		(width 0.1)
		(layer "In6.Cu")
		(net 170)
	)
	(segment
		(start 140.894602 152.559904)
		(end 140.8946 152.559905)
		(width 0.1)
		(layer "In6.Cu")
		(net 170)
	)
	(segment
		(start 140.117595 152.065743)
		(end 140.611758 152.559905)
		(width 0.1)
		(layer "In6.Cu")
		(net 170)
	)
	(segment
		(start 140.966126 151.217211)
		(end 141.460288 151.711374)
		(width 0.1)
		(layer "In6.Cu")
		(net 170)
	)
	(segment
		(start 142.0975 149.802994)
		(end 142.0975 149.802995)
		(width 0.1)
		(layer "In6.Cu")
		(net 170)
	)
	(segment
		(start 141.531813 150.651524)
		(end 142.025975 151.145687)
		(width 0.1)
		(layer "In6.Cu")
		(net 170)
	)
	(segment
		(start 140.400439 151.782898)
		(end 140.894601 152.277061)
		(width 0.1)
		(layer "In6.Cu")
		(net 170)
	)
	(segment
		(start 143.794561 148.388776)
		(end 144.288723 148.882939)
		(width 0.1)
		(layer "In6.Cu")
		(net 170)
	)
	(segment
		(start 142.663187 149.237307)
		(end 142.663187 149.237308)
		(width 0.1)
		(layer "In6.Cu")
		(net 170)
	)
	(segment
		(start 143.228874 148.954463)
		(end 143.723036 149.448626)
		(width 0.1)
		(layer "In6.Cu")
		(net 170)
	)
	(segment
		(start 143.723037 149.731469)
		(end 143.723035 149.73147)
		(width 0.1)
		(layer "In6.Cu")
		(net 170)
	)
	(segment
		(start 139.500501 163.040701)
		(end 139.500501 165.958331)
		(width 0.1)
		(layer "In6.Cu")
		(net 170)
	)
	(segment
		(start 141.814656 150.368682)
		(end 142.308819 150.862844)
		(width 0.1)
		(layer "In6.Cu")
		(net 170)
	)
	(segment
		(start 142.0975 150.085837)
		(end 142.591662 150.58)
		(width 0.1)
		(layer "In6.Cu")
		(net 170)
	)
	(segment
		(start 143.511717 148.671621)
		(end 144.00588 149.165783)
		(width 0.1)
		(layer "In6.Cu")
		(net 170)
	)
	(arc
		(start 140.683282 151.500056)
		(mid 140.541861 151.441477)
		(end 140.400439 151.500055)
		(width 0.1)
		(layer "In6.Cu")
		(net 170)
	)
	(arc
		(start 143.157349 150.014313)
		(mid 143.215928 150.155734)
		(end 143.15735 150.297156)
		(width 0.1)
		(layer "In6.Cu")
		(net 170)
	)
	(arc
		(start 140.328913 153.125592)
		(mid 140.187493 153.184169)
		(end 140.046071 153.125592)
		(width 0.1)
		(layer "In6.Cu")
		(net 170)
	)
	(arc
		(start 140.328914 152.842748)
		(mid 140.387493 152.984169)
		(end 140.328915 153.125591)
		(width 0.1)
		(layer "In6.Cu")
		(net 170)
	)
	(arc
		(start 144.854409 148.317254)
		(mid 144.912988 148.458674)
		(end 144.854409 148.600096)
		(width 0.1)
		(layer "In6.Cu")
		(net 170)
	)
	(arc
		(start 140.117595 152.065743)
		(mid 139.976174 152.007164)
		(end 139.834752 152.065742)
		(width 0.1)
		(layer "In6.Cu")
		(net 170)
	)
	(arc
		(start 141.814656 150.368682)
		(mid 141.673235 150.310103)
		(end 141.531813 150.368681)
		(width 0.1)
		(layer "In6.Cu")
		(net 170)
	)
	(arc
		(start 140.894601 152.277061)
		(mid 140.95318 152.418482)
		(end 140.894602 152.559904)
		(width 0.1)
		(layer "In6.Cu")
		(net 170)
	)
	(arc
		(start 144.288722 149.165783)
		(mid 144.147302 149.22436)
		(end 144.00588 149.165783)
		(width 0.1)
		(layer "In6.Cu")
		(net 170)
	)
	(arc
		(start 142.380343 149.802995)
		(mid 142.238922 149.744416)
		(end 142.0975 149.802994)
		(width 0.1)
		(layer "In6.Cu")
		(net 170)
	)
	(arc
		(start 142.591662 150.58)
		(mid 142.650241 150.721421)
		(end 142.591663 150.862843)
		(width 0.1)
		(layer "In6.Cu")
		(net 170)
	)
	(arc
		(start 140.400439 151.500056)
		(mid 140.341861 151.641477)
		(end 140.400439 151.782898)
		(width 0.1)
		(layer "In6.Cu")
		(net 170)
	)
	(arc
		(start 142.591661 150.862844)
		(mid 142.450241 150.921421)
		(end 142.308819 150.862844)
		(width 0.1)
		(layer "In6.Cu")
		(net 170)
	)
	(arc
		(start 142.663187 149.237308)
		(mid 142.604609 149.378729)
		(end 142.663187 149.52015)
		(width 0.1)
		(layer "In6.Cu")
		(net 170)
	)
	(arc
		(start 144.288723 148.882939)
		(mid 144.347302 149.02436)
		(end 144.288724 149.165782)
		(width 0.1)
		(layer "In6.Cu")
		(net 170)
	)
	(arc
		(start 142.025974 151.428531)
		(mid 141.884554 151.487108)
		(end 141.743132 151.428531)
		(width 0.1)
		(layer "In6.Cu")
		(net 170)
	)
	(arc
		(start 144.85441 148.600096)
		(mid 144.712988 148.658675)
		(end 144.571568 148.600096)
		(width 0.1)
		(layer "In6.Cu")
		(net 170)
	)
	(arc
		(start 143.511717 148.671621)
		(mid 143.370296 148.613042)
		(end 143.228874 148.67162)
		(width 0.1)
		(layer "In6.Cu")
		(net 170)
	)
	(arc
		(start 142.94603 149.237308)
		(mid 142.804609 149.178729)
		(end 142.663187 149.237307)
		(width 0.1)
		(layer "In6.Cu")
		(net 170)
	)
	(arc
		(start 144.077404 148.105934)
		(mid 143.935983 148.047355)
		(end 143.794561 148.105933)
		(width 0.1)
		(layer "In6.Cu")
		(net 170)
	)
	(arc
		(start 139.834752 152.065743)
		(mid 139.776174 152.207164)
		(end 139.834752 152.348585)
		(width 0.1)
		(layer "In6.Cu")
		(net 170)
	)
	(arc
		(start 143.723036 149.448626)
		(mid 143.781615 149.590047)
		(end 143.723037 149.731469)
		(width 0.1)
		(layer "In6.Cu")
		(net 170)
	)
	(arc
		(start 143.157348 150.297157)
		(mid 143.015928 150.355734)
		(end 142.874506 150.297157)
		(width 0.1)
		(layer "In6.Cu")
		(net 170)
	)
	(arc
		(start 144.74875 147.92875)
		(mid 144.69017 148.070173)
		(end 144.74875 148.211594)
		(width 0.1)
		(layer "In6.Cu")
		(net 170)
	)
	(arc
		(start 142.025975 151.145687)
		(mid 142.084554 151.287108)
		(end 142.025976 151.42853)
		(width 0.1)
		(layer "In6.Cu")
		(net 170)
	)
	(arc
		(start 142.0975 149.802995)
		(mid 142.038922 149.944416)
		(end 142.0975 150.085837)
		(width 0.1)
		(layer "In6.Cu")
		(net 170)
	)
	(arc
		(start 143.228874 148.671621)
		(mid 143.170296 148.813042)
		(end 143.228874 148.954463)
		(width 0.1)
		(layer "In6.Cu")
		(net 170)
	)
	(arc
		(start 143.794561 148.105934)
		(mid 143.735983 148.247355)
		(end 143.794561 148.388776)
		(width 0.1)
		(layer "In6.Cu")
		(net 170)
	)
	(arc
		(start 141.531813 150.368682)
		(mid 141.473235 150.510103)
		(end 141.531813 150.651524)
		(width 0.1)
		(layer "In6.Cu")
		(net 170)
	)
	(arc
		(start 140.966126 150.934369)
		(mid 140.907548 151.07579)
		(end 140.966126 151.217211)
		(width 0.1)
		(layer "In6.Cu")
		(net 170)
	)
	(arc
		(start 141.460288 151.711374)
		(mid 141.518867 151.852795)
		(end 141.460289 151.994217)
		(width 0.1)
		(layer "In6.Cu")
		(net 170)
	)
	(arc
		(start 143.723035 149.73147)
		(mid 143.581615 149.790047)
		(end 143.440193 149.73147)
		(width 0.1)
		(layer "In6.Cu")
		(net 170)
	)
	(arc
		(start 140.8946 152.559905)
		(mid 140.75318 152.618482)
		(end 140.611758 152.559905)
		(width 0.1)
		(layer "In6.Cu")
		(net 170)
	)
	(arc
		(start 141.460287 151.994218)
		(mid 141.318867 152.052795)
		(end 141.177445 151.994218)
		(width 0.1)
		(layer "In6.Cu")
		(net 170)
	)
	(arc
		(start 139.940412 153.019933)
		(mid 139.798992 152.961354)
		(end 139.65757 153.019933)
		(width 0.1)
		(layer "In6.Cu")
		(net 170)
	)
	(arc
		(start 141.248969 150.934369)
		(mid 141.107548 150.87579)
		(end 140.966126 150.934368)
		(width 0.1)
		(layer "In6.Cu")
		(net 170)
	)
	(segment
		(start 139.650001 138.8025)
		(end 139.650001 137.727503)
		(width 0.201)
		(layer "F.Cu")
		(net 171)
	)
	(via
		(at 139.650001 137.727503)
		(size 0.45)
		(drill 0.1)
		(layers "F.Cu" "B.Cu")
		(net 171)
	)
	(segment
		(start 140.67 138.747502)
		(end 139.650001 137.727503)
		(width 0.201)
		(layer "B.Cu")
		(net 171)
	)
	(segment
		(start 140.7 141.915)
		(end 141.67 142.885)
		(width 0.201)
		(layer "B.Cu")
		(net 171)
	)
	(segment
		(start 140.67 141.915)
		(end 140.7 141.915)
		(width 0.201)
		(layer "B.Cu")
		(net 171)
	)
	(segment
		(start 140.67 141.915)
		(end 140.67 138.747502)
		(width 0.201)
		(layer "B.Cu")
		(net 171)
	)
	(segment
		(start 140.150001 138.8025)
		(end 140.15 139.877501)
		(width 0.201)
		(layer "F.Cu")
		(net 172)
	)
	(via
		(at 140.15 139.877501)
		(size 0.45)
		(drill 0.1)
		(layers "F.Cu" "B.Cu")
		(net 172)
	)
	(segment
		(start 140.15 139.877501)
		(end 140.15 140.765)
		(width 0.201)
		(layer "B.Cu")
		(net 172)
	)
	(segment
		(start 139 141.915)
		(end 137 141.915)
		(width 0.201)
		(layer "B.Cu")
		(net 172)
	)
	(segment
		(start 140.15 140.765)
		(end 139 141.915)
		(width 0.201)
		(layer "B.Cu")
		(net 172)
	)
	(segment
		(start 143.400001 146.2025)
		(end 143.400001 147.2775)
		(width 0.201)
		(layer "F.Cu")
		(net 173)
	)
	(via
		(at 143.400001 147.2775)
		(size 0.45)
		(drill 0.1)
		(layers "F.Cu" "B.Cu")
		(net 173)
	)
	(segment
		(start 144.399998 141.915)
		(end 144.37 141.915)
		(width 0.256)
		(layer "B.Cu")
		(net 173)
	)
	(segment
		(start 143.4 143.784998)
		(end 143.400002 143.785)
		(width 0.256)
		(layer "B.Cu")
		(net 173)
	)
	(segment
		(start 143.400002 143.785)
		(end 143.400001 147.2775)
		(width 0.256)
		(layer "B.Cu")
		(net 173)
	)
	(segment
		(start 144.37 141.915)
		(end 143.4 142.885)
		(width 0.256)
		(layer "B.Cu")
		(net 173)
	)
	(segment
		(start 143.4 142.885)
		(end 143.4 143.784998)
		(width 0.256)
		(layer "B.Cu")
		(net 173)
	)
	(segment
		(start 143.375501 169.302)
		(end 143.875001 168.8025)
		(width 0.256)
		(layer "F.Cu")
		(net 174)
	)
	(segment
		(start 145.65 138.8025)
		(end 145.65 137.727499)
		(width 0.201)
		(layer "F.Cu")
		(net 174)
	)
	(via
		(at 145.65 137.727499)
		(size 0.45)
		(drill 0.1)
		(layers "F.Cu" "B.Cu")
		(net 174)
	)
	(via
		(at 143.875001 168.8025)
		(size 0.45)
		(drill 0.1)
		(layers "F.Cu" "B.Cu")
		(net 174)
	)
	(segment
		(start 139.825001 161.0005)
		(end 140.250001 161.4255)
		(width 0.1)
		(layer "In6.Cu")
		(net 174)
	)
	(segment
		(start 140.250001 166.990673)
		(end 140.636828 167.3775)
		(width 0.1)
		(layer "In6.Cu")
		(net 174)
	)
	(segment
		(start 145.802436 143.7245)
		(end 145.7245 143.7245)
		(width 0.1)
		(layer "In6.Cu")
		(net 174)
	)
	(segment
		(start 145.3 139.35)
		(end 145.4 139.35)
		(width 0.1)
		(layer "In6.Cu")
		(net 174)
	)
	(segment
		(start 145.875501 148.124499)
		(end 139.825001 154.174999)
		(width 0.1)
		(layer "In6.Cu")
		(net 174)
	)
	(segment
		(start 145.9 138.35)
		(end 146 138.35)
		(width 0.1)
		(layer "In6.Cu")
		(net 174)
	)
	(segment
		(start 141.250001 167.647169)
		(end 141.250001 167.7775)
		(width 0.1)
		(layer "In6.Cu")
		(net 174)
	)
	(segment
		(start 141.250001 167.7775)
		(end 141.675001 168.2025)
		(width 0.1)
		(layer "In6.Cu")
		(net 174)
	)
	(segment
		(start 145.146564 143.2245)
		(end 145.802436 143.2245)
		(width 0.1)
		(layer "In6.Cu")
		(net 174)
	)
	(segment
		(start 140.636828 167.3775)
		(end 140.980332 167.3775)
		(width 0.1)
		(layer "In6.Cu")
		(net 174)
	)
	(segment
		(start 145.65 139.6)
		(end 145.65 141.026501)
		(width 0.1)
		(layer "In6.Cu")
		(net 174)
	)
	(segment
		(start 145.2245 141.7245)
		(end 145.146564 141.7245)
		(width 0.1)
		(layer "In6.Cu")
		(net 174)
	)
	(segment
		(start 145.4745 143.9745)
		(end 145.4745 145.987375)
		(width 0.1)
		(layer "In6.Cu")
		(net 174)
	)
	(segment
		(start 145.146564 142.2245)
		(end 145.802436 142.2245)
		(width 0.1)
		(layer "In6.Cu")
		(net 174)
	)
	(segment
		(start 140.980332 167.3775)
		(end 141.250001 167.647169)
		(width 0.1)
		(layer "In6.Cu")
		(net 174)
	)
	(segment
		(start 145.4745 145.987375)
		(end 145.875501 146.388376)
		(width 0.1)
		(layer "In6.Cu")
		(net 174)
	)
	(segment
		(start 145.65 137.727499)
		(end 145.65 138.1)
		(width 0.1)
		(layer "In6.Cu")
		(net 174)
	)
	(segment
		(start 146 138.85)
		(end 145.3 138.85)
		(width 0.1)
		(layer "In6.Cu")
		(net 174)
	)
	(segment
		(start 145.65 141.026501)
		(end 145.4745 141.202001)
		(width 0.1)
		(layer "In6.Cu")
		(net 174)
	)
	(segment
		(start 145.4745 141.202001)
		(end 145.4745 141.4745)
		(width 0.1)
		(layer "In6.Cu")
		(net 174)
	)
	(segment
		(start 140.250001 161.4255)
		(end 140.250001 166.990673)
		(width 0.1)
		(layer "In6.Cu")
		(net 174)
	)
	(segment
		(start 143.275001 168.2025)
		(end 143.875001 168.8025)
		(width 0.1)
		(layer "In6.Cu")
		(net 174)
	)
	(segment
		(start 139.825001 154.174999)
		(end 139.825001 161.0005)
		(width 0.1)
		(layer "In6.Cu")
		(net 174)
	)
	(segment
		(start 145.802436 142.7245)
		(end 145.146564 142.7245)
		(width 0.1)
		(layer "In6.Cu")
		(net 174)
	)
	(segment
		(start 141.675001 168.2025)
		(end 143.275001 168.2025)
		(width 0.1)
		(layer "In6.Cu")
		(net 174)
	)
	(segment
		(start 145.875501 146.388376)
		(end 145.875501 148.124499)
		(width 0.1)
		(layer "In6.Cu")
		(net 174)
	)
	(arc
		(start 145.3 138.85)
		(mid 145.123223 138.923223)
		(end 145.05 139.1)
		(width 0.1)
		(layer "In6.Cu")
		(net 174)
	)
	(arc
		(start 145.802436 143.2245)
		(mid 145.979213 143.297723)
		(end 146.052436 143.4745)
		(width 0.1)
		(layer "In6.Cu")
		(net 174)
	)
	(arc
		(start 145.146564 142.7245)
		(mid 144.969787 142.797723)
		(end 144.896564 142.9745)
		(width 0.1)
		(layer "In6.Cu")
		(net 174)
	)
	(arc
		(start 146.25 138.6)
		(mid 146.176777 138.776777)
		(end 146 138.85)
		(width 0.1)
		(layer "In6.Cu")
		(net 174)
	)
	(arc
		(start 144.896564 142.9745)
		(mid 144.969787 143.151277)
		(end 145.146564 143.2245)
		(width 0.1)
		(layer "In6.Cu")
		(net 174)
	)
	(arc
		(start 145.4 139.35)
		(mid 145.576777 139.423223)
		(end 145.65 139.6)
		(width 0.1)
		(layer "In6.Cu")
		(net 174)
	)
	(arc
		(start 146.052436 142.4745)
		(mid 145.979213 142.651277)
		(end 145.802436 142.7245)
		(width 0.1)
		(layer "In6.Cu")
		(net 174)
	)
	(arc
		(start 145.146564 141.7245)
		(mid 144.969787 141.797723)
		(end 144.896564 141.9745)
		(width 0.1)
		(layer "In6.Cu")
		(net 174)
	)
	(arc
		(start 145.4745 141.4745)
		(mid 145.401277 141.651277)
		(end 145.2245 141.7245)
		(width 0.1)
		(layer "In6.Cu")
		(net 174)
	)
	(arc
		(start 146.052436 143.4745)
		(mid 145.979213 143.651277)
		(end 145.802436 143.7245)
		(width 0.1)
		(layer "In6.Cu")
		(net 174)
	)
	(arc
		(start 144.896564 141.9745)
		(mid 144.969787 142.151277)
		(end 145.146564 142.2245)
		(width 0.1)
		(layer "In6.Cu")
		(net 174)
	)
	(arc
		(start 146 138.35)
		(mid 146.176777 138.423223)
		(end 146.25 138.6)
		(width 0.1)
		(layer "In6.Cu")
		(net 174)
	)
	(arc
		(start 145.65 138.1)
		(mid 145.723223 138.276777)
		(end 145.9 138.35)
		(width 0.1)
		(layer "In6.Cu")
		(net 174)
	)
	(arc
		(start 145.7245 143.7245)
		(mid 145.547723 143.797723)
		(end 145.4745 143.9745)
		(width 0.1)
		(layer "In6.Cu")
		(net 174)
	)
	(arc
		(start 145.802436 142.2245)
		(mid 145.979213 142.297723)
		(end 146.052436 142.4745)
		(width 0.1)
		(layer "In6.Cu")
		(net 174)
	)
	(arc
		(start 145.05 139.1)
		(mid 145.123223 139.276777)
		(end 145.3 139.35)
		(width 0.1)
		(layer "In6.Cu")
		(net 174)
	)
	(segment
		(start 198.775501 159.7)
		(end 198.776501 159.699)
		(width 0.1)
		(layer "F.Cu")
		(net 175)
	)
	(segment
		(start 198.353501 159.7)
		(end 198.775501 159.7)
		(width 0.1)
		(layer "F.Cu")
		(net 175)
	)
	(segment
		(start 180.926107 166.997001)
		(end 180.1445 166.997)
		(width 0.2)
		(layer "F.Cu")
		(net 175)
	)
	(segment
		(start 180.1445 166.997)
		(end 180.1 166.952499)
		(width 0.2)
		(layer "F.Cu")
		(net 175)
	)
	(via
		(at 198.776501 159.699)
		(size 0.45)
		(drill 0.1)
		(layers "F.Cu" "B.Cu")
		(net 175)
	)
	(via
		(at 180.1 166.952499)
		(size 0.45)
		(drill 0.1)
		(layers "F.Cu" "B.Cu")
		(net 175)
	)
	(segment
		(start 184.3 161.958578)
		(end 184.3 164.058578)
		(width 0.1)
		(layer "In4.Cu")
		(net 175)
	)
	(segment
		(start 198.951501 159.874)
		(end 198.951501 160.107077)
		(width 0.1)
		(layer "In4.Cu")
		(net 175)
	)
	(segment
		(start 198.432512 160.449289)
		(end 198.417242 160.434019)
		(width 0.1)
		(layer "In4.Cu")
		(net 175)
	)
	(segment
		(start 187.041422 160.5)
		(end 185.758578 160.5)
		(width 0.1)
		(layer "In4.Cu")
		(net 175)
	)
	(segment
		(start 198.240466 160.610795)
		(end 198.255735 160.626064)
		(width 0.1)
		(layer "In4.Cu")
		(net 175)
	)
	(segment
		(start 198.432511 160.449289)
		(end 198.432512 160.449289)
		(width 0.1)
		(layer "In4.Cu")
		(net 175)
	)
	(segment
		(start 197.958578 161.1)
		(end 187.641422 161.1)
		(width 0.1)
		(layer "In4.Cu")
		(net 175)
	)
	(segment
		(start 198.776501 159.699)
		(end 198.951501 159.874)
		(width 0.1)
		(layer "In4.Cu")
		(net 175)
	)
	(segment
		(start 180.29175 167.144249)
		(end 180.1 166.952499)
		(width 0.1)
		(layer "In4.Cu")
		(net 175)
	)
	(segment
		(start 198.240465 160.43402)
		(end 198.240466 160.434019)
		(width 0.1)
		(layer "In4.Cu")
		(net 175)
	)
	(segment
		(start 198.951501 160.107077)
		(end 198.609289 160.449289)
		(width 0.1)
		(layer "In4.Cu")
		(net 175)
	)
	(segment
		(start 185.758578 160.5)
		(end 184.3 161.958578)
		(width 0.1)
		(layer "In4.Cu")
		(net 175)
	)
	(segment
		(start 187.641422 161.1)
		(end 187.041422 160.5)
		(width 0.1)
		(layer "In4.Cu")
		(net 175)
	)
	(segment
		(start 198.255734 160.802841)
		(end 198.255735 160.80284)
		(width 0.1)
		(layer "In4.Cu")
		(net 175)
	)
	(segment
		(start 184.3 164.058578)
		(end 181.214329 167.144249)
		(width 0.1)
		(layer "In4.Cu")
		(net 175)
	)
	(segment
		(start 198.255735 160.80284)
		(end 197.958578 161.1)
		(width 0.1)
		(layer "In4.Cu")
		(net 175)
	)
	(segment
		(start 181.214329 167.144249)
		(end 180.29175 167.144249)
		(width 0.1)
		(layer "In4.Cu")
		(net 175)
	)
	(arc
		(start 198.240466 160.434019)
		(mid 198.203854 160.522407)
		(end 198.240466 160.610795)
		(width 0.1)
		(layer "In4.Cu")
		(net 175)
	)
	(arc
		(start 198.417242 160.434019)
		(mid 198.328853 160.397408)
		(end 198.240465 160.43402)
		(width 0.1)
		(layer "In4.Cu")
		(net 175)
	)
	(arc
		(start 198.255735 160.626064)
		(mid 198.292346 160.714453)
		(end 198.255734 160.802841)
		(width 0.1)
		(layer "In4.Cu")
		(net 175)
	)
	(arc
		(start 198.609289 160.449289)
		(mid 198.5209 160.485901)
		(end 198.432511 160.449289)
		(width 0.1)
		(layer "In4.Cu")
		(net 175)
	)
	(segment
		(start 146.400001 146.2025)
		(end 146.400001 147.277498)
		(width 0.201)
		(layer "F.Cu")
		(net 176)
	)
	(segment
		(start 141.375501 168.302)
		(end 141.875001 167.802499)
		(width 0.256)
		(layer "F.Cu")
		(net 176)
	)
	(via
		(at 141.875001 167.802499)
		(size 0.45)
		(drill 0.1)
		(layers "F.Cu" "B.Cu")
		(net 176)
	)
	(via
		(at 146.400001 147.277498)
		(size 0.45)
		(drill 0.1)
		(layers "F.Cu" "B.Cu")
		(net 176)
	)
	(segment
		(start 140.715162 154.116633)
		(end 141.133367 154.534839)
		(width 0.1)
		(layer "In6.Cu")
		(net 176)
	)
	(segment
		(start 145.806343 149.025451)
		(end 145.874026 149.093134)
		(width 0.1)
		(layer "In6.Cu")
		(net 176)
	)
	(segment
		(start 144.957813 149.591139)
		(end 144.957814 149.591137)
		(width 0.1)
		(layer "In6.Cu")
		(net 176)
	)
	(segment
		(start 144.244644 151.706404)
		(end 144.244645 151.706404)
		(width 0.1)
		(layer "In6.Cu")
		(net 176)
	)
	(segment
		(start 143.113271 152.554934)
		(end 143.113271 152.554935)
		(width 0.1)
		(layer "In6.Cu")
		(net 176)
	)
	(segment
		(start 141.280847 153.550947)
		(end 141.699054 153.969152)
		(width 0.1)
		(layer "In6.Cu")
		(net 176)
	)
	(segment
		(start 140.300501 161.026)
		(end 140.300501 154.949499)
		(width 0.1)
		(layer "In6.Cu")
		(net 176)
	)
	(segment
		(start 144.244645 151.42356)
		(end 144.244645 151.423561)
		(width 0.1)
		(layer "In6.Cu")
		(net 176)
	)
	(segment
		(start 144.810331 151.140717)
		(end 144.810332 151.140717)
		(width 0.1)
		(layer "In6.Cu")
		(net 176)
	)
	(segment
		(start 142.97791 151.853885)
		(end 142.977908 151.853886)
		(width 0.1)
		(layer "In6.Cu")
		(net 176)
	)
	(segment
		(start 141.875001 167.802499)
		(end 141.250002 167.1775)
		(width 0.1)
		(layer "In6.Cu")
		(net 176)
	)
	(segment
		(start 142.547584 153.120622)
		(end 142.129378 152.702416)
		(width 0.1)
		(layer "In6.Cu")
		(net 176)
	)
	(segment
		(start 141.280849 153.550946)
		(end 141.280847 153.550947)
		(width 0.1)
		(layer "In6.Cu")
		(net 176)
	)
	(segment
		(start 145.376019 150.292187)
		(end 144.957813 149.873981)
		(width 0.1)
		(layer "In6.Cu")
		(net 176)
	)
	(segment
		(start 140.300501 154.949499)
		(end 140.5 154.75)
		(width 0.1)
		(layer "In6.Cu")
		(net 176)
	)
	(segment
		(start 145.240656 149.591138)
		(end 145.658863 150.009343)
		(width 0.1)
		(layer "In6.Cu")
		(net 176)
	)
	(segment
		(start 144.810332 150.857873)
		(end 144.810332 150.857874)
		(width 0.1)
		(layer "In6.Cu")
		(net 176)
	)
	(segment
		(start 141.416209 154.534839)
		(end 141.41621 154.534839)
		(width 0.1)
		(layer "In6.Cu")
		(net 176)
	)
	(segment
		(start 144.109284 150.722511)
		(end 144.109282 150.722512)
		(width 0.1)
		(layer "In6.Cu")
		(net 176)
	)
	(segment
		(start 143.678957 152.272091)
		(end 143.678958 152.272091)
		(width 0.1)
		(layer "In6.Cu")
		(net 176)
	)
	(segment
		(start 146.400001 148.849999)
		(end 146.400001 147.277498)
		(width 0.1)
		(layer "In6.Cu")
		(net 176)
	)
	(segment
		(start 146.156868 149.093134)
		(end 146.400001 148.849999)
		(width 0.1)
		(layer "In6.Cu")
		(net 176)
	)
	(segment
		(start 142.977908 151.853886)
		(end 143.396115 152.272091)
		(width 0.1)
		(layer "In6.Cu")
		(net 176)
	)
	(segment
		(start 140.715162 154.116634)
		(end 140.715162 154.116633)
		(width 0.1)
		(layer "In6.Cu")
		(net 176)
	)
	(segment
		(start 145.941706 149.7265)
		(end 145.5235 149.308294)
		(width 0.1)
		(layer "In6.Cu")
		(net 176)
	)
	(segment
		(start 143.11327 152.837778)
		(end 143.113271 152.837778)
		(width 0.1)
		(layer "In6.Cu")
		(net 176)
	)
	(segment
		(start 145.5235 149.025452)
		(end 145.523501 149.02545)
		(width 0.1)
		(layer "In6.Cu")
		(net 176)
	)
	(segment
		(start 141.981897 153.686309)
		(end 141.563691 153.268103)
		(width 0.1)
		(layer "In6.Cu")
		(net 176)
	)
	(segment
		(start 140.998004 153.550948)
		(end 140.998005 153.550946)
		(width 0.1)
		(layer "In6.Cu")
		(net 176)
	)
	(segment
		(start 141.846536 152.985259)
		(end 141.846534 152.98526)
		(width 0.1)
		(layer "In6.Cu")
		(net 176)
	)
	(segment
		(start 141.41621 154.251996)
		(end 140.998004 153.83379)
		(width 0.1)
		(layer "In6.Cu")
		(net 176)
	)
	(segment
		(start 140.432319 154.116633)
		(end 140.432318 154.116634)
		(width 0.1)
		(layer "In6.Cu")
		(net 176)
	)
	(segment
		(start 146.156869 149.093133)
		(end 146.156868 149.093134)
		(width 0.1)
		(layer "In6.Cu")
		(net 176)
	)
	(segment
		(start 142.547583 153.403465)
		(end 142.547584 153.403465)
		(width 0.1)
		(layer "In6.Cu")
		(net 176)
	)
	(segment
		(start 141.563691 152.985261)
		(end 141.563692 152.985259)
		(width 0.1)
		(layer "In6.Cu")
		(net 176)
	)
	(segment
		(start 145.376019 150.292186)
		(end 145.376019 150.292187)
		(width 0.1)
		(layer "In6.Cu")
		(net 176)
	)
	(segment
		(start 144.109282 150.722512)
		(end 144.527489 151.140717)
		(width 0.1)
		(layer "In6.Cu")
		(net 176)
	)
	(segment
		(start 145.941706 149.726499)
		(end 145.941706 149.7265)
		(width 0.1)
		(layer "In6.Cu")
		(net 176)
	)
	(segment
		(start 144.674971 150.156824)
		(end 144.674969 150.156825)
		(width 0.1)
		(layer "In6.Cu")
		(net 176)
	)
	(segment
		(start 142.695065 151.853887)
		(end 142.695066 151.853885)
		(width 0.1)
		(layer "In6.Cu")
		(net 176)
	)
	(segment
		(start 141.250002 167.1775)
		(end 141.250002 166.527501)
		(width 0.1)
		(layer "In6.Cu")
		(net 176)
	)
	(segment
		(start 141.41621 154.251995)
		(end 141.41621 154.251996)
		(width 0.1)
		(layer "In6.Cu")
		(net 176)
	)
	(segment
		(start 141.250002 166.527501)
		(end 141.025001 166.3025)
		(width 0.1)
		(layer "In6.Cu")
		(net 176)
	)
	(segment
		(start 143.543597 151.288198)
		(end 143.543595 151.288199)
		(width 0.1)
		(layer "In6.Cu")
		(net 176)
	)
	(segment
		(start 140.5 154.467158)
		(end 140.432318 154.399476)
		(width 0.1)
		(layer "In6.Cu")
		(net 176)
	)
	(segment
		(start 145.240658 149.591137)
		(end 145.240656 149.591138)
		(width 0.1)
		(layer "In6.Cu")
		(net 176)
	)
	(segment
		(start 140.775001 166.3025)
		(end 140.500001 166.0275)
		(width 0.1)
		(layer "In6.Cu")
		(net 176)
	)
	(segment
		(start 145.941705 150.009343)
		(end 145.941706 150.009343)
		(width 0.1)
		(layer "In6.Cu")
		(net 176)
	)
	(segment
		(start 140.500001 161.2255)
		(end 140.300501 161.026)
		(width 0.1)
		(layer "In6.Cu")
		(net 176)
	)
	(segment
		(start 141.981897 153.686308)
		(end 141.981897 153.686309)
		(width 0.1)
		(layer "In6.Cu")
		(net 176)
	)
	(segment
		(start 144.810332 150.857874)
		(end 144.392126 150.439668)
		(width 0.1)
		(layer "In6.Cu")
		(net 176)
	)
	(segment
		(start 145.806345 149.02545)
		(end 145.806343 149.025451)
		(width 0.1)
		(layer "In6.Cu")
		(net 176)
	)
	(segment
		(start 144.392126 150.156826)
		(end 144.392127 150.156824)
		(width 0.1)
		(layer "In6.Cu")
		(net 176)
	)
	(segment
		(start 143.543595 151.288199)
		(end 143.961802 151.706404)
		(width 0.1)
		(layer "In6.Cu")
		(net 176)
	)
	(segment
		(start 141.981896 153.969152)
		(end 141.981897 153.969152)
		(width 0.1)
		(layer "In6.Cu")
		(net 176)
	)
	(segment
		(start 142.412221 152.419573)
		(end 142.830428 152.837778)
		(width 0.1)
		(layer "In6.Cu")
		(net 176)
	)
	(segment
		(start 143.260752 151.2882)
		(end 143.260753 151.288198)
		(width 0.1)
		(layer "In6.Cu")
		(net 176)
	)
	(segment
		(start 141.025001 166.3025)
		(end 140.775001 166.3025)
		(width 0.1)
		(layer "In6.Cu")
		(net 176)
	)
	(segment
		(start 141.846534 152.98526)
		(end 142.264741 153.403465)
		(width 0.1)
		(layer "In6.Cu")
		(net 176)
	)
	(segment
		(start 142.412223 152.419572)
		(end 142.412221 152.419573)
		(width 0.1)
		(layer "In6.Cu")
		(net 176)
	)
	(segment
		(start 144.674969 150.156825)
		(end 145.093176 150.57503)
		(width 0.1)
		(layer "In6.Cu")
		(net 176)
	)
	(segment
		(start 144.244645 151.423561)
		(end 143.826439 151.005355)
		(width 0.1)
		(layer "In6.Cu")
		(net 176)
	)
	(segment
		(start 143.678958 151.989247)
		(end 143.678958 151.989248)
		(width 0.1)
		(layer "In6.Cu")
		(net 176)
	)
	(segment
		(start 142.129378 152.419574)
		(end 142.129379 152.419572)
		(width 0.1)
		(layer "In6.Cu")
		(net 176)
	)
	(segment
		(start 143.678958 151.989248)
		(end 143.260752 151.571042)
		(width 0.1)
		(layer "In6.Cu")
		(net 176)
	)
	(segment
		(start 145.376018 150.57503)
		(end 145.376019 150.57503)
		(width 0.1)
		(layer "In6.Cu")
		(net 176)
	)
	(segment
		(start 140.500001 166.0275)
		(end 140.500001 161.2255)
		(width 0.1)
		(layer "In6.Cu")
		(net 176)
	)
	(segment
		(start 143.826439 150.722513)
		(end 143.82644 150.722511)
		(width 0.1)
		(layer "In6.Cu")
		(net 176)
	)
	(segment
		(start 143.113271 152.554935)
		(end 142.695065 152.136729)
		(width 0.1)
		(layer "In6.Cu")
		(net 176)
	)
	(segment
		(start 142.547584 153.120621)
		(end 142.547584 153.120622)
		(width 0.1)
		(layer "In6.Cu")
		(net 176)
	)
	(arc
		(start 143.678958 152.272091)
		(mid 143.737537 152.130669)
		(end 143.678958 151.989247)
		(width 0.1)
		(layer "In6.Cu")
		(net 176)
	)
	(arc
		(start 140.432318 154.399476)
		(mid 140.37374 154.258054)
		(end 140.432319 154.116633)
		(width 0.1)
		(layer "In6.Cu")
		(net 176)
	)
	(arc
		(start 142.129379 152.419572)
		(mid 142.2708 152.360994)
		(end 142.412223 152.419572)
		(width 0.1)
		(layer "In6.Cu")
		(net 176)
	)
	(arc
		(start 145.658863 150.009343)
		(mid 145.800284 150.067921)
		(end 145.941705 150.009343)
		(width 0.1)
		(layer "In6.Cu")
		(net 176)
	)
	(arc
		(start 144.957814 149.591137)
		(mid 145.099235 149.532559)
		(end 145.240658 149.591137)
		(width 0.1)
		(layer "In6.Cu")
		(net 176)
	)
	(arc
		(start 140.5 154.75)
		(mid 140.558579 154.608578)
		(end 140.5 154.467158)
		(width 0.1)
		(layer "In6.Cu")
		(net 176)
	)
	(arc
		(start 140.998004 153.83379)
		(mid 140.939427 153.692368)
		(end 140.998004 153.550948)
		(width 0.1)
		(layer "In6.Cu")
		(net 176)
	)
	(arc
		(start 144.957813 149.873981)
		(mid 144.899236 149.732559)
		(end 144.957813 149.591139)
		(width 0.1)
		(layer "In6.Cu")
		(net 176)
	)
	(arc
		(start 142.695065 152.136729)
		(mid 142.636488 151.995307)
		(end 142.695065 151.853887)
		(width 0.1)
		(layer "In6.Cu")
		(net 176)
	)
	(arc
		(start 141.981897 153.969152)
		(mid 142.040476 153.82773)
		(end 141.981897 153.686308)
		(width 0.1)
		(layer "In6.Cu")
		(net 176)
	)
	(arc
		(start 144.527489 151.140717)
		(mid 144.66891 151.199295)
		(end 144.810331 151.140717)
		(width 0.1)
		(layer "In6.Cu")
		(net 176)
	)
	(arc
		(start 142.264741 153.403465)
		(mid 142.406162 153.462043)
		(end 142.547583 153.403465)
		(width 0.1)
		(layer "In6.Cu")
		(net 176)
	)
	(arc
		(start 144.244645 151.706404)
		(mid 144.303224 151.564982)
		(end 144.244645 151.42356)
		(width 0.1)
		(layer "In6.Cu")
		(net 176)
	)
	(arc
		(start 140.432318 154.116634)
		(mid 140.573741 154.058054)
		(end 140.715162 154.116634)
		(width 0.1)
		(layer "In6.Cu")
		(net 176)
	)
	(arc
		(start 142.547584 153.403465)
		(mid 142.606163 153.262043)
		(end 142.547584 153.120621)
		(width 0.1)
		(layer "In6.Cu")
		(net 176)
	)
	(arc
		(start 142.129378 152.702416)
		(mid 142.070801 152.560994)
		(end 142.129378 152.419574)
		(width 0.1)
		(layer "In6.Cu")
		(net 176)
	)
	(arc
		(start 141.563691 153.268103)
		(mid 141.505114 153.126681)
		(end 141.563691 152.985261)
		(width 0.1)
		(layer "In6.Cu")
		(net 176)
	)
	(arc
		(start 145.5235 149.308294)
		(mid 145.464923 149.166872)
		(end 145.5235 149.025452)
		(width 0.1)
		(layer "In6.Cu")
		(net 176)
	)
	(arc
		(start 144.392127 150.156824)
		(mid 144.533548 150.098246)
		(end 144.674971 150.156824)
		(width 0.1)
		(layer "In6.Cu")
		(net 176)
	)
	(arc
		(start 145.093176 150.57503)
		(mid 145.234597 150.633608)
		(end 145.376018 150.57503)
		(width 0.1)
		(layer "In6.Cu")
		(net 176)
	)
	(arc
		(start 143.260753 151.288198)
		(mid 143.402174 151.22962)
		(end 143.543597 151.288198)
		(width 0.1)
		(layer "In6.Cu")
		(net 176)
	)
	(arc
		(start 141.699054 153.969152)
		(mid 141.840475 154.02773)
		(end 141.981896 153.969152)
		(width 0.1)
		(layer "In6.Cu")
		(net 176)
	)
	(arc
		(start 142.695066 151.853885)
		(mid 142.836487 151.795307)
		(end 142.97791 151.853885)
		(width 0.1)
		(layer "In6.Cu")
		(net 176)
	)
	(arc
		(start 144.392126 150.439668)
		(mid 144.333549 150.298246)
		(end 144.392126 150.156826)
		(width 0.1)
		(layer "In6.Cu")
		(net 176)
	)
	(arc
		(start 143.113271 152.837778)
		(mid 143.17185 152.696356)
		(end 143.113271 152.554934)
		(width 0.1)
		(layer "In6.Cu")
		(net 176)
	)
	(arc
		(start 141.563692 152.985259)
		(mid 141.705113 152.926681)
		(end 141.846536 152.985259)
		(width 0.1)
		(layer "In6.Cu")
		(net 176)
	)
	(arc
		(start 141.41621 154.534839)
		(mid 141.474789 154.393417)
		(end 141.41621 154.251995)
		(width 0.1)
		(layer "In6.Cu")
		(net 176)
	)
	(arc
		(start 145.874026 149.093134)
		(mid 146.015448 149.151712)
		(end 146.156869 149.093133)
		(width 0.1)
		(layer "In6.Cu")
		(net 176)
	)
	(arc
		(start 143.82644 150.722511)
		(mid 143.967861 150.663933)
		(end 144.109284 150.722511)
		(width 0.1)
		(layer "In6.Cu")
		(net 176)
	)
	(arc
		(start 141.133367 154.534839)
		(mid 141.274788 154.593417)
		(end 141.416209 154.534839)
		(width 0.1)
		(layer "In6.Cu")
		(net 176)
	)
	(arc
		(start 145.523501 149.02545)
		(mid 145.664922 148.966872)
		(end 145.806345 149.02545)
		(width 0.1)
		(layer "In6.Cu")
		(net 176)
	)
	(arc
		(start 145.376019 150.57503)
		(mid 145.434598 150.433608)
		(end 145.376019 150.292186)
		(width 0.1)
		(layer "In6.Cu")
		(net 176)
	)
	(arc
		(start 145.941706 150.009343)
		(mid 146.000285 149.867921)
		(end 145.941706 149.726499)
		(width 0.1)
		(layer "In6.Cu")
		(net 176)
	)
	(arc
		(start 143.826439 151.005355)
		(mid 143.767862 150.863933)
		(end 143.826439 150.722513)
		(width 0.1)
		(layer "In6.Cu")
		(net 176)
	)
	(arc
		(start 144.810332 151.140717)
		(mid 144.868911 150.999295)
		(end 144.810332 150.857873)
		(width 0.1)
		(layer "In6.Cu")
		(net 176)
	)
	(arc
		(start 143.396115 152.272091)
		(mid 143.537536 152.330669)
		(end 143.678957 152.272091)
		(width 0.1)
		(layer "In6.Cu")
		(net 176)
	)
	(arc
		(start 143.260752 151.571042)
		(mid 143.202175 151.42962)
		(end 143.260752 151.2882)
		(width 0.1)
		(layer "In6.Cu")
		(net 176)
	)
	(arc
		(start 140.998005 153.550946)
		(mid 141.139426 153.492368)
		(end 141.280849 153.550946)
		(width 0.1)
		(layer "In6.Cu")
		(net 176)
	)
	(arc
		(start 142.830428 152.837778)
		(mid 142.971849 152.896356)
		(end 143.11327 152.837778)
		(width 0.1)
		(layer "In6.Cu")
		(net 176)
	)
	(arc
		(start 143.961802 151.706404)
		(mid 144.103223 151.764982)
		(end 144.244644 151.706404)
		(width 0.1)
		(layer "In6.Cu")
		(net 176)
	)
	(segment
		(start 146.650001 138.8025)
		(end 146.65 137.7275)
		(width 0.201)
		(layer "F.Cu")
		(net 177)
	)
	(segment
		(start 142.375501 168.302)
		(end 142.875001 167.8025)
		(width 0.256)
		(layer "F.Cu")
		(net 177)
	)
	(via
		(at 146.65 137.7275)
		(size 0.45)
		(drill 0.1)
		(layers "F.Cu" "B.Cu")
		(net 177)
	)
	(via
		(at 142.875001 167.8025)
		(size 0.45)
		(drill 0.1)
		(layers "F.Cu" "B.Cu")
		(net 177)
	)
	(segment
		(start 142.875001 167.8025)
		(end 142.250002 167.177501)
		(width 0.1)
		(layer "In6.Cu")
		(net 177)
	)
	(segment
		(start 147.07 137.2)
		(end 146.75 137.2)
		(width 0.1)
		(layer "In6.Cu")
		(net 177)
	)
	(segment
		(start 142.70532 154.594047)
		(end 142.70532 154.594048)
		(width 0.1)
		(layer "In6.Cu")
		(net 177)
	)
	(segment
		(start 142.250002 167.177501)
		(end 141.71967 167.177501)
		(width 0.1)
		(layer "In6.Cu")
		(net 177)
	)
	(segment
		(start 146.65 139.68)
		(end 147.17 139.16)
		(width 0.1)
		(layer "In6.Cu")
		(net 177)
	)
	(segment
		(start 142.139634 155.159734)
		(end 141.840266 154.860366)
		(width 0.1)
		(layer "In6.Cu")
		(net 177)
	)
	(segment
		(start 146.65 140.19)
		(end 146.65 139.68)
		(width 0.1)
		(layer "In6.Cu")
		(net 177)
	)
	(segment
		(start 141.573947 155.725419)
		(end 141.573947 155.72542)
		(width 0.1)
		(layer "In6.Cu")
		(net 177)
	)
	(segment
		(start 143.271005 154.311205)
		(end 143.271006 154.311205)
		(width 0.1)
		(layer "In6.Cu")
		(net 177)
	)
	(segment
		(start 141.573948 156.008262)
		(end 141.573947 156.008263)
		(width 0.1)
		(layer "In6.Cu")
		(net 177)
	)
	(segment
		(start 141.71967 167.177501)
		(end 141.500001 166.957832)
		(width 0.1)
		(layer "In6.Cu")
		(net 177)
	)
	(segment
		(start 140.800501 156.199499)
		(end 141 156)
		(width 0.1)
		(layer "In6.Cu")
		(net 177)
	)
	(segment
		(start 143.262742 153.737256)
		(end 146.9 150.1)
		(width 0.1)
		(layer "In6.Cu")
		(net 177)
	)
	(segment
		(start 142.688797 154.011836)
		(end 142.688795 154.011837)
		(width 0.1)
		(layer "In6.Cu")
		(net 177)
	)
	(segment
		(start 141.282842 156)
		(end 141.291105 156.008263)
		(width 0.1)
		(layer "In6.Cu")
		(net 177)
	)
	(segment
		(start 143.271006 154.028361)
		(end 143.271006 154.028362)
		(width 0.1)
		(layer "In6.Cu")
		(net 177)
	)
	(segment
		(start 142.705319 154.876891)
		(end 142.70532 154.876891)
		(width 0.1)
		(layer "In6.Cu")
		(net 177)
	)
	(segment
		(start 147.17 139.16)
		(end 147.17 137.3)
		(width 0.1)
		(layer "In6.Cu")
		(net 177)
	)
	(segment
		(start 146.474501 140.365499)
		(end 146.65 140.19)
		(width 0.1)
		(layer "In6.Cu")
		(net 177)
	)
	(segment
		(start 146.65 137.3)
		(end 146.65 137.7275)
		(width 0.1)
		(layer "In6.Cu")
		(net 177)
	)
	(segment
		(start 141.840266 154.577524)
		(end 141.840267 154.577522)
		(width 0.1)
		(layer "In6.Cu")
		(net 177)
	)
	(segment
		(start 141.557423 155.143209)
		(end 141.856791 155.442577)
		(width 0.1)
		(layer "In6.Cu")
		(net 177)
	)
	(segment
		(start 141.27458 155.14321)
		(end 141.274581 155.143208)
		(width 0.1)
		(layer "In6.Cu")
		(net 177)
	)
	(segment
		(start 142.123111 154.577522)
		(end 142.123109 154.577523)
		(width 0.1)
		(layer "In6.Cu")
		(net 177)
	)
	(segment
		(start 146.9 146.912875)
		(end 146.474501 146.487376)
		(width 0.1)
		(layer "In6.Cu")
		(net 177)
	)
	(segment
		(start 141.275001 161.5005)
		(end 140.800501 161.026)
		(width 0.1)
		(layer "In6.Cu")
		(net 177)
	)
	(segment
		(start 143.262743 153.737255)
		(end 143.262742 153.737256)
		(width 0.1)
		(layer "In6.Cu")
		(net 177)
	)
	(segment
		(start 142.139634 155.159733)
		(end 142.139634 155.159734)
		(width 0.1)
		(layer "In6.Cu")
		(net 177)
	)
	(segment
		(start 141.500001 166.2275)
		(end 141.275001 166.0025)
		(width 0.1)
		(layer "In6.Cu")
		(net 177)
	)
	(segment
		(start 146.474501 146.487376)
		(end 146.474501 140.365499)
		(width 0.1)
		(layer "In6.Cu")
		(net 177)
	)
	(segment
		(start 146.9 150.1)
		(end 146.9 146.912875)
		(width 0.1)
		(layer "In6.Cu")
		(net 177)
	)
	(segment
		(start 141.275001 166.0025)
		(end 141.275001 161.5005)
		(width 0.1)
		(layer "In6.Cu")
		(net 177)
	)
	(segment
		(start 142.405952 154.011838)
		(end 142.405953 154.011836)
		(width 0.1)
		(layer "In6.Cu")
		(net 177)
	)
	(segment
		(start 143.271006 154.028362)
		(end 143.262742 154.020098)
		(width 0.1)
		(layer "In6.Cu")
		(net 177)
	)
	(segment
		(start 141.500001 166.957832)
		(end 141.500001 166.2275)
		(width 0.1)
		(layer "In6.Cu")
		(net 177)
	)
	(segment
		(start 142.123109 154.577523)
		(end 142.422477 154.876891)
		(width 0.1)
		(layer "In6.Cu")
		(net 177)
	)
	(segment
		(start 142.139633 155.442577)
		(end 142.139634 155.442577)
		(width 0.1)
		(layer "In6.Cu")
		(net 177)
	)
	(segment
		(start 146.75 137.2)
		(end 146.65 137.3)
		(width 0.1)
		(layer "In6.Cu")
		(net 177)
	)
	(segment
		(start 141.557425 155.143208)
		(end 141.557423 155.143209)
		(width 0.1)
		(layer "In6.Cu")
		(net 177)
	)
	(segment
		(start 140.800501 161.026)
		(end 140.800501 156.199499)
		(width 0.1)
		(layer "In6.Cu")
		(net 177)
	)
	(segment
		(start 147.17 137.3)
		(end 147.07 137.2)
		(width 0.1)
		(layer "In6.Cu")
		(net 177)
	)
	(segment
		(start 142.688795 154.011837)
		(end 142.988163 154.311205)
		(width 0.1)
		(layer "In6.Cu")
		(net 177)
	)
	(segment
		(start 141.573947 155.72542)
		(end 141.27458 155.426052)
		(width 0.1)
		(layer "In6.Cu")
		(net 177)
	)
	(segment
		(start 142.70532 154.594048)
		(end 142.405952 154.29468)
		(width 0.1)
		(layer "In6.Cu")
		(net 177)
	)
	(arc
		(start 142.405953 154.011836)
		(mid 142.547374 153.953258)
		(end 142.688797 154.011836)
		(width 0.1)
		(layer "In6.Cu")
		(net 177)
	)
	(arc
		(start 142.70532 154.876891)
		(mid 142.763899 154.735469)
		(end 142.70532 154.594047)
		(width 0.1)
		(layer "In6.Cu")
		(net 177)
	)
	(arc
		(start 142.139634 155.442577)
		(mid 142.198213 155.301155)
		(end 142.139634 155.159733)
		(width 0.1)
		(layer "In6.Cu")
		(net 177)
	)
	(arc
		(start 141.840267 154.577522)
		(mid 141.981688 154.518944)
		(end 142.123111 154.577522)
		(width 0.1)
		(layer "In6.Cu")
		(net 177)
	)
	(arc
		(start 141 156)
		(mid 141.141421 155.941422)
		(end 141.282842 156)
		(width 0.1)
		(layer "In6.Cu")
		(net 177)
	)
	(arc
		(start 141.27458 155.426052)
		(mid 141.216003 155.28463)
		(end 141.27458 155.14321)
		(width 0.1)
		(layer "In6.Cu")
		(net 177)
	)
	(arc
		(start 141.856791 155.442577)
		(mid 141.998212 155.501155)
		(end 142.139633 155.442577)
		(width 0.1)
		(layer "In6.Cu")
		(net 177)
	)
	(arc
		(start 142.422477 154.876891)
		(mid 142.563898 154.935469)
		(end 142.705319 154.876891)
		(width 0.1)
		(layer "In6.Cu")
		(net 177)
	)
	(arc
		(start 143.271006 154.311205)
		(mid 143.329585 154.169783)
		(end 143.271006 154.028361)
		(width 0.1)
		(layer "In6.Cu")
		(net 177)
	)
	(arc
		(start 142.405952 154.29468)
		(mid 142.347375 154.153258)
		(end 142.405952 154.011838)
		(width 0.1)
		(layer "In6.Cu")
		(net 177)
	)
	(arc
		(start 143.262742 154.020098)
		(mid 143.204164 153.878676)
		(end 143.262743 153.737255)
		(width 0.1)
		(layer "In6.Cu")
		(net 177)
	)
	(arc
		(start 141.274581 155.143208)
		(mid 141.416002 155.08463)
		(end 141.557425 155.143208)
		(width 0.1)
		(layer "In6.Cu")
		(net 177)
	)
	(arc
		(start 141.840266 154.860366)
		(mid 141.781689 154.718944)
		(end 141.840266 154.577524)
		(width 0.1)
		(layer "In6.Cu")
		(net 177)
	)
	(arc
		(start 141.573947 156.008263)
		(mid 141.632526 155.866841)
		(end 141.573947 155.725419)
		(width 0.1)
		(layer "In6.Cu")
		(net 177)
	)
	(arc
		(start 141.291105 156.008263)
		(mid 141.432527 156.066841)
		(end 141.573948 156.008262)
		(width 0.1)
		(layer "In6.Cu")
		(net 177)
	)
	(arc
		(start 142.988163 154.311205)
		(mid 143.129584 154.369783)
		(end 143.271005 154.311205)
		(width 0.1)
		(layer "In6.Cu")
		(net 177)
	)
	(segment
		(start 143.375501 170.302)
		(end 143.875002 169.8025)
		(width 0.256)
		(layer "F.Cu")
		(net 178)
	)
	(segment
		(start 146.900001 146.2025)
		(end 146.900001 145.127499)
		(width 0.201)
		(layer "F.Cu")
		(net 178)
	)
	(via
		(at 146.900001 145.127499)
		(size 0.45)
		(drill 0.1)
		(layers "F.Cu" "B.Cu")
		(net 178)
	)
	(via
		(at 143.875002 169.8025)
		(size 0.45)
		(drill 0.1)
		(layers "F.Cu" "B.Cu")
		(net 178)
	)
	(segment
		(start 142.030332 165.1775)
		(end 141.71967 165.1775)
		(width 0.1)
		(layer "In6.Cu")
		(net 178)
	)
	(segment
		(start 146.87414 150.868752)
		(end 147.111274 151.105886)
		(width 0.1)
		(layer "In6.Cu")
		(net 178)
	)
	(segment
		(start 141.300501 157.199499)
		(end 144 154.5)
		(width 0.1)
		(layer "In6.Cu")
		(net 178)
	)
	(segment
		(start 147.348404 152.191546)
		(end 147.348405 152.191546)
		(width 0.1)
		(layer "In6.Cu")
		(net 178)
	)
	(segment
		(start 145.651347 153.605761)
		(end 144.894239 152.848653)
		(width 0.1)
		(layer "In6.Cu")
		(net 178)
	)
	(segment
		(start 144.045711 153.697183)
		(end 144.045711 153.697182)
		(width 0.1)
		(layer "In6.Cu")
		(net 178)
	)
	(segment
		(start 147.775001 147.432831)
		(end 147.775001 147.0505)
		(width 0.1)
		(layer "In6.Cu")
		(net 178)
	)
	(segment
		(start 143.71967 168.1775)
		(end 143.425001 167.882831)
		(width 0.1)
		(layer "In6.Cu")
		(net 178)
	)
	(segment
		(start 143.875002 169.8025)
		(end 144.328001 169.349501)
		(width 0.1)
		(layer "In6.Cu")
		(net 178)
	)
	(segment
		(start 145.74277 152.000123)
		(end 145.742768 152.000124)
		(width 0.1)
		(layer "In6.Cu")
		(net 178)
	)
	(segment
		(start 144 154.217158)
		(end 143.762867 153.980025)
		(width 0.1)
		(layer "In6.Cu")
		(net 178)
	)
	(segment
		(start 144.045711 153.697182)
		(end 144.802818 154.45429)
		(width 0.1)
		(layer "In6.Cu")
		(net 178)
	)
	(segment
		(start 146.217033 153.040075)
		(end 145.459925 152.282967)
		(width 0.1)
		(layer "In6.Cu")
		(net 178)
	)
	(segment
		(start 145.177082 152.56581)
		(end 145.93419 153.322918)
		(width 0.1)
		(layer "In6.Cu")
		(net 178)
	)
	(segment
		(start 145.085661 154.171447)
		(end 144.328553 153.414339)
		(width 0.1)
		(layer "In6.Cu")
		(net 178)
	)
	(segment
		(start 145.651346 153.888604)
		(end 145.651347 153.888604)
		(width 0.1)
		(layer "In6.Cu")
		(net 178)
	)
	(segment
		(start 141.300501 161.026)
		(end 141.300501 157.199499)
		(width 0.1)
		(layer "In6.Cu")
		(net 178)
	)
	(segment
		(start 144.611396 153.131496)
		(end 145.368504 153.888604)
		(width 0.1)
		(layer "In6.Cu")
		(net 178)
	)
	(segment
		(start 145.085661 154.171446)
		(end 145.085661 154.171447)
		(width 0.1)
		(layer "In6.Cu")
		(net 178)
	)
	(segment
		(start 141.71967 165.1775)
		(end 141.500001 164.957831)
		(width 0.1)
		(layer "In6.Cu")
		(net 178)
	)
	(segment
		(start 145.742768 152.000124)
		(end 146.499876 152.757232)
		(width 0.1)
		(layer "In6.Cu")
		(net 178)
	)
	(segment
		(start 146.782718 152.757232)
		(end 146.782719 152.757232)
		(width 0.1)
		(layer "In6.Cu")
		(net 178)
	)
	(segment
		(start 142.922918 167.380748)
		(end 142.368414 166.826244)
		(width 0.1)
		(layer "In6.Cu")
		(net 178)
	)
	(segment
		(start 144.894239 152.565811)
		(end 144.89424 152.565809)
		(width 0.1)
		(layer "In6.Cu")
		(net 178)
	)
	(segment
		(start 146.782719 152.474388)
		(end 146.782719 152.474389)
		(width 0.1)
		(layer "In6.Cu")
		(net 178)
	)
	(segment
		(start 147.600501 150.899499)
		(end 147.600501 147.607331)
		(width 0.1)
		(layer "In6.Cu")
		(net 178)
	)
	(segment
		(start 146.308454 151.434438)
		(end 147.065562 152.191546)
		(width 0.1)
		(layer "In6.Cu")
		(net 178)
	)
	(segment
		(start 144.328001 168.475169)
		(end 144.030332 168.1775)
		(width 0.1)
		(layer "In6.Cu")
		(net 178)
	)
	(segment
		(start 146.782719 152.474389)
		(end 146.025611 151.717281)
		(width 0.1)
		(layer "In6.Cu")
		(net 178)
	)
	(segment
		(start 145.08566 154.45429)
		(end 145.085661 154.45429)
		(width 0.1)
		(layer "In6.Cu")
		(net 178)
	)
	(segment
		(start 147.775001 147.0505)
		(end 146.900501 146.176)
		(width 0.1)
		(layer "In6.Cu")
		(net 178)
	)
	(segment
		(start 147.394116 151.105886)
		(end 147.600501 150.899499)
		(width 0.1)
		(layer "In6.Cu")
		(net 178)
	)
	(segment
		(start 144.328553 153.131497)
		(end 144.328554 153.131495)
		(width 0.1)
		(layer "In6.Cu")
		(net 178)
	)
	(segment
		(start 143.425001 167.6025)
		(end 143.203249 167.380748)
		(width 0.1)
		(layer "In6.Cu")
		(net 178)
	)
	(segment
		(start 143.203249 167.380748)
		(end 142.922918 167.380748)
		(width 0.1)
		(layer "In6.Cu")
		(net 178)
	)
	(segment
		(start 146.217033 153.040074)
		(end 146.217033 153.040075)
		(width 0.1)
		(layer "In6.Cu")
		(net 178)
	)
	(segment
		(start 146.025611 151.434439)
		(end 146.025612 151.434437)
		(width 0.1)
		(layer "In6.Cu")
		(net 178)
	)
	(segment
		(start 145.651347 153.60576)
		(end 145.651347 153.605761)
		(width 0.1)
		(layer "In6.Cu")
		(net 178)
	)
	(segment
		(start 147.394117 151.105885)
		(end 147.394116 151.105886)
		(width 0.1)
		(layer "In6.Cu")
		(net 178)
	)
	(segment
		(start 145.459925 152.000125)
		(end 145.459926 152.000123)
		(width 0.1)
		(layer "In6.Cu")
		(net 178)
	)
	(segment
		(start 146.308456 151.434437)
		(end 146.308454 151.434438)
		(width 0.1)
		(layer "In6.Cu")
		(net 178)
	)
	(segment
		(start 142.368414 165.515582)
		(end 142.030332 165.1775)
		(width 0.1)
		(layer "In6.Cu")
		(net 178)
	)
	(segment
		(start 147.600501 147.607331)
		(end 147.775001 147.432831)
		(width 0.1)
		(layer "In6.Cu")
		(net 178)
	)
	(segment
		(start 147.348405 151.908702)
		(end 147.348405 151.908703)
		(width 0.1)
		(layer "In6.Cu")
		(net 178)
	)
	(segment
		(start 143.425001 167.882831)
		(end 143.425001 167.6025)
		(width 0.1)
		(layer "In6.Cu")
		(net 178)
	)
	(segment
		(start 144.328001 169.349501)
		(end 144.328001 168.475169)
		(width 0.1)
		(layer "In6.Cu")
		(net 178)
	)
	(segment
		(start 146.591297 150.868753)
		(end 146.591298 150.868751)
		(width 0.1)
		(layer "In6.Cu")
		(net 178)
	)
	(segment
		(start 146.874142 150.868751)
		(end 146.87414 150.868752)
		(width 0.1)
		(layer "In6.Cu")
		(net 178)
	)
	(segment
		(start 143.762868 153.697182)
		(end 143.762867 153.697183)
		(width 0.1)
		(layer "In6.Cu")
		(net 178)
	)
	(segment
		(start 141.500001 161.2255)
		(end 141.300501 161.026)
		(width 0.1)
		(layer "In6.Cu")
		(net 178)
	)
	(segment
		(start 146.217032 153.322918)
		(end 146.217033 153.322918)
		(width 0.1)
		(layer "In6.Cu")
		(net 178)
	)
	(segment
		(start 146.900501 145.127999)
		(end 146.900001 145.127499)
		(width 0.1)
		(layer "In6.Cu")
		(net 178)
	)
	(segment
		(start 145.177084 152.565809)
		(end 145.177082 152.56581)
		(width 0.1)
		(layer "In6.Cu")
		(net 178)
	)
	(segment
		(start 141.500001 164.957831)
		(end 141.500001 161.2255)
		(width 0.1)
		(layer "In6.Cu")
		(net 178)
	)
	(segment
		(start 144.030332 168.1775)
		(end 143.71967 168.1775)
		(width 0.1)
		(layer "In6.Cu")
		(net 178)
	)
	(segment
		(start 144.611398 153.131495)
		(end 144.611396 153.131496)
		(width 0.1)
		(layer "In6.Cu")
		(net 178)
	)
	(segment
		(start 142.368414 166.826244)
		(end 142.368414 165.515582)
		(width 0.1)
		(layer "In6.Cu")
		(net 178)
	)
	(segment
		(start 146.900501 146.176)
		(end 146.900501 145.127999)
		(width 0.1)
		(layer "In6.Cu")
		(net 178)
	)
	(segment
		(start 147.348405 151.908703)
		(end 146.591297 151.151595)
		(width 0.1)
		(layer "In6.Cu")
		(net 178)
	)
	(arc
		(start 146.782719 152.757232)
		(mid 146.841298 152.61581)
		(end 146.782719 152.474388)
		(width 0.1)
		(layer "In6.Cu")
		(net 178)
	)
	(arc
		(start 146.499876 152.757232)
		(mid 146.641297 152.81581)
		(end 146.782718 152.757232)
		(width 0.1)
		(layer "In6.Cu")
		(net 178)
	)
	(arc
		(start 145.368504 153.888604)
		(mid 145.509925 153.947182)
		(end 145.651346 153.888604)
		(width 0.1)
		(layer "In6.Cu")
		(net 178)
	)
	(arc
		(start 147.348405 152.191546)
		(mid 147.406984 152.050124)
		(end 147.348405 151.908702)
		(width 0.1)
		(layer "In6.Cu")
		(net 178)
	)
	(arc
		(start 143.762867 153.980025)
		(mid 143.704289 153.838603)
		(end 143.762868 153.697182)
		(width 0.1)
		(layer "In6.Cu")
		(net 178)
	)
	(arc
		(start 146.591297 151.151595)
		(mid 146.53272 151.010173)
		(end 146.591297 150.868753)
		(width 0.1)
		(layer "In6.Cu")
		(net 178)
	)
	(arc
		(start 147.111274 151.105886)
		(mid 147.252696 151.164464)
		(end 147.394117 151.105885)
		(width 0.1)
		(layer "In6.Cu")
		(net 178)
	)
	(arc
		(start 146.591298 150.868751)
		(mid 146.732719 150.810173)
		(end 146.874142 150.868751)
		(width 0.1)
		(layer "In6.Cu")
		(net 178)
	)
	(arc
		(start 144.328553 153.414339)
		(mid 144.269976 153.272917)
		(end 144.328553 153.131497)
		(width 0.1)
		(layer "In6.Cu")
		(net 178)
	)
	(arc
		(start 144 154.5)
		(mid 144.058579 154.358578)
		(end 144 154.217158)
		(width 0.1)
		(layer "In6.Cu")
		(net 178)
	)
	(arc
		(start 144.802818 154.45429)
		(mid 144.944239 154.512868)
		(end 145.08566 154.45429)
		(width 0.1)
		(layer "In6.Cu")
		(net 178)
	)
	(arc
		(start 143.762867 153.697183)
		(mid 143.90429 153.638603)
		(end 144.045711 153.697183)
		(width 0.1)
		(layer "In6.Cu")
		(net 178)
	)
	(arc
		(start 146.025612 151.434437)
		(mid 146.167033 151.375859)
		(end 146.308456 151.434437)
		(width 0.1)
		(layer "In6.Cu")
		(net 178)
	)
	(arc
		(start 144.89424 152.565809)
		(mid 145.035661 152.507231)
		(end 145.177084 152.565809)
		(width 0.1)
		(layer "In6.Cu")
		(net 178)
	)
	(arc
		(start 145.651347 153.888604)
		(mid 145.709926 153.747182)
		(end 145.651347 153.60576)
		(width 0.1)
		(layer "In6.Cu")
		(net 178)
	)
	(arc
		(start 145.459925 152.282967)
		(mid 145.401348 152.141545)
		(end 145.459925 152.000125)
		(width 0.1)
		(layer "In6.Cu")
		(net 178)
	)
	(arc
		(start 144.894239 152.848653)
		(mid 144.835662 152.707231)
		(end 144.894239 152.565811)
		(width 0.1)
		(layer "In6.Cu")
		(net 178)
	)
	(arc
		(start 145.085661 154.45429)
		(mid 145.14424 154.312868)
		(end 145.085661 154.171446)
		(width 0.1)
		(layer "In6.Cu")
		(net 178)
	)
	(arc
		(start 147.065562 152.191546)
		(mid 147.206983 152.250124)
		(end 147.348404 152.191546)
		(width 0.1)
		(layer "In6.Cu")
		(net 178)
	)
	(arc
		(start 145.459926 152.000123)
		(mid 145.601347 151.941545)
		(end 145.74277 152.000123)
		(width 0.1)
		(layer "In6.Cu")
		(net 178)
	)
	(arc
		(start 146.217033 153.322918)
		(mid 146.275612 153.181496)
		(end 146.217033 153.040074)
		(width 0.1)
		(layer "In6.Cu")
		(net 178)
	)
	(arc
		(start 145.93419 153.322918)
		(mid 146.075611 153.381496)
		(end 146.217032 153.322918)
		(width 0.1)
		(layer "In6.Cu")
		(net 178)
	)
	(arc
		(start 144.328554 153.131495)
		(mid 144.469975 153.072917)
		(end 144.611398 153.131495)
		(width 0.1)
		(layer "In6.Cu")
		(net 178)
	)
	(arc
		(start 146.025611 151.717281)
		(mid 145.967034 151.575859)
		(end 146.025611 151.434439)
		(width 0.1)
		(layer "In6.Cu")
		(net 178)
	)
	(segment
		(start 144.375501 170.302)
		(end 144.875 169.8025)
		(width 0.256)
		(layer "F.Cu")
		(net 179)
	)
	(segment
		(start 147.150001 138.8025)
		(end 147.150002 139.8775)
		(width 0.201)
		(layer "F.Cu")
		(net 179)
	)
	(via
		(at 147.150002 139.8775)
		(size 0.45)
		(drill 0.1)
		(layers "F.Cu" "B.Cu")
		(net 179)
	)
	(via
		(at 144.875 169.8025)
		(size 0.45)
		(drill 0.1)
		(layers "F.Cu" "B.Cu")
		(net 179)
	)
	(segment
		(start 148.400501 144.840501)
		(end 147.66 144.1)
		(width 0.1)
		(layer "In6.Cu")
		(net 179)
	)
	(segment
		(start 143.005022 157.656494)
		(end 143.343507 157.994979)
		(width 0.1)
		(layer "In6.Cu")
		(net 179)
	)
	(segment
		(start 147.91 142.8)
		(end 148.11 142.8)
		(width 0.1)
		(layer "In6.Cu")
		(net 179)
	)
	(segment
		(start 145.328001 167.5055)
		(end 145.125001 167.3025)
		(width 0.1)
		(layer "In6.Cu")
		(net 179)
	)
	(segment
		(start 144.192035 157.146449)
		(end 144.192035 157.14645)
		(width 0.1)
		(layer "In6.Cu")
		(net 179)
	)
	(segment
		(start 144.375001 165.5275)
		(end 144.100001 165.2525)
		(width 0.1)
		(layer "In6.Cu")
		(net 179)
	)
	(segment
		(start 144.192035 157.14645)
		(end 143.85355 156.807964)
		(width 0.1)
		(layer "In6.Cu")
		(net 179)
	)
	(segment
		(start 148.11 142.3)
		(end 147.21 142.3)
		(width 0.1)
		(layer "In6.Cu")
		(net 179)
	)
	(segment
		(start 143.570708 157.090807)
		(end 143.909193 157.429293)
		(width 0.1)
		(layer "In6.Cu")
		(net 179)
	)
	(segment
		(start 143.287865 157.090807)
		(end 143.287864 157.090808)
		(width 0.1)
		(layer "In6.Cu")
		(net 179)
	)
	(segment
		(start 143.626349 157.712135)
		(end 143.626349 157.712136)
		(width 0.1)
		(layer "In6.Cu")
		(net 179)
	)
	(segment
		(start 144.447059 156.552944)
		(end 144.447058 156.552944)
		(width 0.1)
		(layer "In6.Cu")
		(net 179)
	)
	(segment
		(start 142.925001 164.1775)
		(end 142.71967 164.1775)
		(width 0.1)
		(layer "In6.Cu")
		(net 179)
	)
	(segment
		(start 144.375001 166.832831)
		(end 144.375001 165.5275)
		(width 0.1)
		(layer "In6.Cu")
		(net 179)
	)
	(segment
		(start 143.005024 157.656493)
		(end 143.005022 157.656494)
		(width 0.1)
		(layer "In6.Cu")
		(net 179)
	)
	(segment
		(start 143.626349 157.712136)
		(end 143.287864 157.37365)
		(width 0.1)
		(layer "In6.Cu")
		(net 179)
	)
	(segment
		(start 148.11 141.3)
		(end 147.21 141.3)
		(width 0.1)
		(layer "In6.Cu")
		(net 179)
	)
	(segment
		(start 144.100001 165.2525)
		(end 143.725001 165.2525)
		(width 0.1)
		(layer "In6.Cu")
		(net 179)
	)
	(segment
		(start 142.350501 160.926)
		(end 142.350501 158.649499)
		(width 0.1)
		(layer "In6.Cu")
		(net 179)
	)
	(segment
		(start 143.853551 156.525121)
		(end 143.85355 156.525122)
		(width 0.1)
		(layer "In6.Cu")
		(net 179)
	)
	(segment
		(start 144.84467 167.3025)
		(end 144.375001 166.832831)
		(width 0.1)
		(layer "In6.Cu")
		(net 179)
	)
	(segment
		(start 144.192036 157.429292)
		(end 144.192035 157.429293)
		(width 0.1)
		(layer "In6.Cu")
		(net 179)
	)
	(segment
		(start 142.350501 158.649499)
		(end 142.75 158.25)
		(width 0.1)
		(layer "In6.Cu")
		(net 179)
	)
	(segment
		(start 148.400501 146.576)
		(end 148.400501 144.840501)
		(width 0.1)
		(layer "In6.Cu")
		(net 179)
	)
	(segment
		(start 143.62635 157.994978)
		(end 143.626349 157.994979)
		(width 0.1)
		(layer "In6.Cu")
		(net 179)
	)
	(segment
		(start 147.66 140.387498)
		(end 147.150002 139.8775)
		(width 0.1)
		(layer "In6.Cu")
		(net 179)
	)
	(segment
		(start 144.875 169.8025)
		(end 145.328001 169.349499)
		(width 0.1)
		(layer "In6.Cu")
		(net 179)
	)
	(segment
		(start 142.71967 164.1775)
		(end 142.500001 163.957831)
		(width 0.1)
		(layer "In6.Cu")
		(net 179)
	)
	(segment
		(start 144.447058 156.552944)
		(end 148.800501 152.199499)
		(width 0.1)
		(layer "In6.Cu")
		(net 179)
	)
	(segment
		(start 144.136394 156.525122)
		(end 144.136394 156.525121)
		(width 0.1)
		(layer "In6.Cu")
		(net 179)
	)
	(segment
		(start 145.328001 169.349499)
		(end 145.328001 167.5055)
		(width 0.1)
		(layer "In6.Cu")
		(net 179)
	)
	(segment
		(start 148.800501 146.976)
		(end 148.400501 146.576)
		(width 0.1)
		(layer "In6.Cu")
		(net 179)
	)
	(segment
		(start 147.21 141.8)
		(end 148.11 141.8)
		(width 0.1)
		(layer "In6.Cu")
		(net 179)
	)
	(segment
		(start 143.570708 157.090808)
		(end 143.570708 157.090807)
		(width 0.1)
		(layer "In6.Cu")
		(net 179)
	)
	(segment
		(start 142.500001 161.0755)
		(end 142.350501 160.926)
		(width 0.1)
		(layer "In6.Cu")
		(net 179)
	)
	(segment
		(start 143.325001 164.8525)
		(end 143.325001 164.5775)
		(width 0.1)
		(layer "In6.Cu")
		(net 179)
	)
	(segment
		(start 147.21 140.8)
		(end 147.41 140.8)
		(width 0.1)
		(layer "In6.Cu")
		(net 179)
	)
	(segment
		(start 143.325001 164.5775)
		(end 142.925001 164.1775)
		(width 0.1)
		(layer "In6.Cu")
		(net 179)
	)
	(segment
		(start 143.725001 165.2525)
		(end 143.325001 164.8525)
		(width 0.1)
		(layer "In6.Cu")
		(net 179)
	)
	(segment
		(start 144.136394 156.525121)
		(end 144.164216 156.552943)
		(width 0.1)
		(layer "In6.Cu")
		(net 179)
	)
	(segment
		(start 145.125001 167.3025)
		(end 144.84467 167.3025)
		(width 0.1)
		(layer "In6.Cu")
		(net 179)
	)
	(segment
		(start 147.66 144.1)
		(end 147.66 143.05)
		(width 0.1)
		(layer "In6.Cu")
		(net 179)
	)
	(segment
		(start 148.800501 152.199499)
		(end 148.800501 146.976)
		(width 0.1)
		(layer "In6.Cu")
		(net 179)
	)
	(segment
		(start 142.722178 157.656494)
		(end 142.72218 157.656493)
		(width 0.1)
		(layer "In6.Cu")
		(net 179)
	)
	(segment
		(start 147.66 140.55)
		(end 147.66 140.387498)
		(width 0.1)
		(layer "In6.Cu")
		(net 179)
	)
	(segment
		(start 142.500001 163.957831)
		(end 142.500001 161.0755)
		(width 0.1)
		(layer "In6.Cu")
		(net 179)
	)
	(segment
		(start 142.75 157.967158)
		(end 142.722179 157.939337)
		(width 0.1)
		(layer "In6.Cu")
		(net 179)
	)
	(arc
		(start 142.72218 157.656493)
		(mid 142.863601 157.597915)
		(end 143.005024 157.656493)
		(width 0.1)
		(layer "In6.Cu")
		(net 179)
	)
	(arc
		(start 147.21 141.3)
		(mid 147.033223 141.226777)
		(end 146.96 141.05)
		(width 0.1)
		(layer "In6.Cu")
		(net 179)
	)
	(arc
		(start 143.343507 157.994979)
		(mid 143.484929 158.053557)
		(end 143.62635 157.994978)
		(width 0.1)
		(layer "In6.Cu")
		(net 179)
	)
	(arc
		(start 147.41 140.8)
		(mid 147.586777 140.726777)
		(end 147.66 140.55)
		(width 0.1)
		(layer "In6.Cu")
		(net 179)
	)
	(arc
		(start 143.626349 157.994979)
		(mid 143.684928 157.853557)
		(end 143.626349 157.712135)
		(width 0.1)
		(layer "In6.Cu")
		(net 179)
	)
	(arc
		(start 142.722179 157.939337)
		(mid 142.6636 157.797916)
		(end 142.722178 157.656494)
		(width 0.1)
		(layer "In6.Cu")
		(net 179)
	)
	(arc
		(start 147.66 143.05)
		(mid 147.733223 142.873223)
		(end 147.91 142.8)
		(width 0.1)
		(layer "In6.Cu")
		(net 179)
	)
	(arc
		(start 143.287864 157.090808)
		(mid 143.429287 157.032228)
		(end 143.570708 157.090808)
		(width 0.1)
		(layer "In6.Cu")
		(net 179)
	)
	(arc
		(start 143.85355 156.525122)
		(mid 143.994973 156.466542)
		(end 144.136394 156.525122)
		(width 0.1)
		(layer "In6.Cu")
		(net 179)
	)
	(arc
		(start 143.287864 157.37365)
		(mid 143.229286 157.232228)
		(end 143.287865 157.090807)
		(width 0.1)
		(layer "In6.Cu")
		(net 179)
	)
	(arc
		(start 143.85355 156.807964)
		(mid 143.794972 156.666542)
		(end 143.853551 156.525121)
		(width 0.1)
		(layer "In6.Cu")
		(net 179)
	)
	(arc
		(start 146.96 142.05)
		(mid 147.033223 141.873223)
		(end 147.21 141.8)
		(width 0.1)
		(layer "In6.Cu")
		(net 179)
	)
	(arc
		(start 146.96 141.05)
		(mid 147.033223 140.873223)
		(end 147.21 140.8)
		(width 0.1)
		(layer "In6.Cu")
		(net 179)
	)
	(arc
		(start 144.164216 156.552943)
		(mid 144.305637 156.611522)
		(end 144.447059 156.552944)
		(width 0.1)
		(layer "In6.Cu")
		(net 179)
	)
	(arc
		(start 142.75 158.25)
		(mid 142.808579 158.108578)
		(end 142.75 157.967158)
		(width 0.1)
		(layer "In6.Cu")
		(net 179)
	)
	(arc
		(start 148.36 142.55)
		(mid 148.286777 142.373223)
		(end 148.11 142.3)
		(width 0.1)
		(layer "In6.Cu")
		(net 179)
	)
	(arc
		(start 148.36 141.55)
		(mid 148.286777 141.373223)
		(end 148.11 141.3)
		(width 0.1)
		(layer "In6.Cu")
		(net 179)
	)
	(arc
		(start 148.11 141.8)
		(mid 148.286777 141.726777)
		(end 148.36 141.55)
		(width 0.1)
		(layer "In6.Cu")
		(net 179)
	)
	(arc
		(start 147.21 142.3)
		(mid 147.033223 142.226777)
		(end 146.96 142.05)
		(width 0.1)
		(layer "In6.Cu")
		(net 179)
	)
	(arc
		(start 148.11 142.8)
		(mid 148.286777 142.726777)
		(end 148.36 142.55)
		(width 0.1)
		(layer "In6.Cu")
		(net 179)
	)
	(arc
		(start 144.192035 157.429293)
		(mid 144.250614 157.287871)
		(end 144.192035 157.146449)
		(width 0.1)
		(layer "In6.Cu")
		(net 179)
	)
	(arc
		(start 143.909193 157.429293)
		(mid 144.050615 157.487871)
		(end 144.192036 157.429292)
		(width 0.1)
		(layer "In6.Cu")
		(net 179)
	)
	(segment
		(start 147.900002 146.2025)
		(end 147.900001 145.1275)
		(width 0.201)
		(layer "F.Cu")
		(net 180)
	)
	(segment
		(start 144.375501 168.302)
		(end 144.875001 167.8025)
		(width 0.256)
		(layer "F.Cu")
		(net 180)
	)
	(via
		(at 144.875001 167.8025)
		(size 0.45)
		(drill 0.1)
		(layers "F.Cu" "B.Cu")
		(net 180)
	)
	(via
		(at 147.900001 145.1275)
		(size 0.45)
		(drill 0.1)
		(layers "F.Cu" "B.Cu")
		(net 180)
	)
	(segment
		(start 143.84467 167.3025)
		(end 144.025001 167.3025)
		(width 0.1)
		(layer "In6.Cu")
		(net 180)
	)
	(segment
		(start 142.300001 164.757831)
		(end 142.71967 165.1775)
		(width 0.1)
		(layer "In6.Cu")
		(net 180)
	)
	(segment
		(start 148.100501 147.576)
		(end 148.100501 151.899499)
		(width 0.1)
		(layer "In6.Cu")
		(net 180)
	)
	(segment
		(start 143.25858 166.71641)
		(end 143.84467 167.3025)
		(width 0.1)
		(layer "In6.Cu")
		(net 180)
	)
	(segment
		(start 144.525001 167.8025)
		(end 144.875001 167.8025)
		(width 0.1)
		(layer "In6.Cu")
		(net 180)
	)
	(segment
		(start 144.025001 167.3025)
		(end 144.525001 167.8025)
		(width 0.1)
		(layer "In6.Cu")
		(net 180)
	)
	(segment
		(start 147.900001 145.1275)
		(end 148.000501 145.228)
		(width 0.1)
		(layer "In6.Cu")
		(net 180)
	)
	(segment
		(start 142.300001 161.5505)
		(end 142.300001 164.757831)
		(width 0.1)
		(layer "In6.Cu")
		(net 180)
	)
	(segment
		(start 142.71967 165.1775)
		(end 142.850001 165.1775)
		(width 0.1)
		(layer "In6.Cu")
		(net 180)
	)
	(segment
		(start 148.000501 147.476)
		(end 148.100501 147.576)
		(width 0.1)
		(layer "In6.Cu")
		(net 180)
	)
	(segment
		(start 141.800501 158.199499)
		(end 141.800501 161.051)
		(width 0.1)
		(layer "In6.Cu")
		(net 180)
	)
	(segment
		(start 148.100501 151.899499)
		(end 141.800501 158.199499)
		(width 0.1)
		(layer "In6.Cu")
		(net 180)
	)
	(segment
		(start 141.800501 161.051)
		(end 142.300001 161.5505)
		(width 0.1)
		(layer "In6.Cu")
		(net 180)
	)
	(segment
		(start 148.000501 145.228)
		(end 148.000501 147.476)
		(width 0.1)
		(layer "In6.Cu")
		(net 180)
	)
	(segment
		(start 142.850001 165.1775)
		(end 143.25858 165.586079)
		(width 0.1)
		(layer "In6.Cu")
		(net 180)
	)
	(segment
		(start 143.25858 165.586079)
		(end 143.25858 166.71641)
		(width 0.1)
		(layer "In6.Cu")
		(net 180)
	)
	(segment
		(start 145.375501 168.302)
		(end 145.875001 167.8025)
		(width 0.256)
		(layer "F.Cu")
		(net 181)
	)
	(segment
		(start 148.15 138.8025)
		(end 148.15 139.877498)
		(width 0.201)
		(layer "F.Cu")
		(net 181)
	)
	(via
		(at 148.15 139.877498)
		(size 0.45)
		(drill 0.1)
		(layers "F.Cu" "B.Cu")
		(net 181)
	)
	(via
		(at 145.875001 167.8025)
		(size 0.45)
		(drill 0.1)
		(layers "F.Cu" "B.Cu")
		(net 181)
	)
	(segment
		(start 144.635505 159.155605)
		(end 144.294395 158.814495)
		(width 0.1)
		(layer "In6.Cu")
		(net 181)
	)
	(segment
		(start 145.708612 157.400279)
		(end 145.70861 157.40028)
		(width 0.1)
		(layer "In6.Cu")
		(net 181)
	)
	(segment
		(start 149.400501 146.499499)
		(end 150.2 145.7)
		(width 0.1)
		(layer "In6.Cu")
		(net 181)
	)
	(segment
		(start 143.825001 164.1775)
		(end 143.71967 164.1775)
		(width 0.1)
		(layer "In6.Cu")
		(net 181)
	)
	(segment
		(start 146.332563 157.458547)
		(end 145.991453 157.117437)
		(width 0.1)
		(layer "In6.Cu")
		(net 181)
	)
	(segment
		(start 146.332562 157.74139)
		(end 146.332563 157.74139)
		(width 0.1)
		(layer "In6.Cu")
		(net 181)
	)
	(segment
		(start 143.728709 159.097339)
		(end 143.72871 159.097337)
		(width 0.1)
		(layer "In6.Cu")
		(net 181)
	)
	(segment
		(start 145.300001 166.8775)
		(end 145.300001 165.487335)
		(width 0.1)
		(layer "In6.Cu")
		(net 181)
	)
	(segment
		(start 144.719669 165.1775)
		(end 144.250002 164.707833)
		(width 0.1)
		(layer "In6.Cu")
		(net 181)
	)
	(segment
		(start 149.400501 147.793158)
		(end 149.400501 146.499499)
		(width 0.1)
		(layer "In6.Cu")
		(net 181)
	)
	(segment
		(start 144.069818 159.721291)
		(end 143.728709 159.380181)
		(width 0.1)
		(layer "In6.Cu")
		(net 181)
	)
	(segment
		(start 144.990166 165.1775)
		(end 144.719669 165.1775)
		(width 0.1)
		(layer "In6.Cu")
		(net 181)
	)
	(segment
		(start 146.586274 156.863728)
		(end 146.586273 156.863729)
		(width 0.1)
		(layer "In6.Cu")
		(net 181)
	)
	(segment
		(start 144.011554 159.097337)
		(end 144.011552 159.097338)
		(width 0.1)
		(layer "In6.Cu")
		(net 181)
	)
	(segment
		(start 150.2 142)
		(end 148.15 139.95)
		(width 0.1)
		(layer "In6.Cu")
		(net 181)
	)
	(segment
		(start 146.274296 156.834594)
		(end 146.303431 156.863729)
		(width 0.1)
		(layer "In6.Cu")
		(net 181)
	)
	(segment
		(start 150.1 148.492657)
		(end 149.400501 147.793158)
		(width 0.1)
		(layer "In6.Cu")
		(net 181)
	)
	(segment
		(start 145.20119 158.872762)
		(end 145.201191 158.872762)
		(width 0.1)
		(layer "In6.Cu")
		(net 181)
	)
	(segment
		(start 144.860081 157.965967)
		(end 144.860082 157.965965)
		(width 0.1)
		(layer "In6.Cu")
		(net 181)
	)
	(segment
		(start 145.766876 158.307076)
		(end 145.766877 158.307076)
		(width 0.1)
		(layer "In6.Cu")
		(net 181)
	)
	(segment
		(start 150.2 145.7)
		(end 150.2 142)
		(width 0.1)
		(layer "In6.Cu")
		(net 181)
	)
	(segment
		(start 145.766877 158.024233)
		(end 145.425767 157.683123)
		(width 0.1)
		(layer "In6.Cu")
		(net 181)
	)
	(segment
		(start 145.875001 167.8025)
		(end 145.875001 167.4525)
		(width 0.1)
		(layer "In6.Cu")
		(net 181)
	)
	(segment
		(start 145.201191 158.589918)
		(end 145.201191 158.589919)
		(width 0.1)
		(layer "In6.Cu")
		(net 181)
	)
	(segment
		(start 144.250002 164.602501)
		(end 143.825001 164.1775)
		(width 0.1)
		(layer "In6.Cu")
		(net 181)
	)
	(segment
		(start 144.069819 160.004133)
		(end 144.069818 160.004134)
		(width 0.1)
		(layer "In6.Cu")
		(net 181)
	)
	(segment
		(start 145.425767 157.400281)
		(end 145.425768 157.400279)
		(width 0.1)
		(layer "In6.Cu")
		(net 181)
	)
	(segment
		(start 145.991453 156.834595)
		(end 145.991454 156.834593)
		(width 0.1)
		(layer "In6.Cu")
		(net 181)
	)
	(segment
		(start 145.875001 167.4525)
		(end 145.300001 166.8775)
		(width 0.1)
		(layer "In6.Cu")
		(net 181)
	)
	(segment
		(start 145.201191 158.589919)
		(end 144.860081 158.248809)
		(width 0.1)
		(layer "In6.Cu")
		(net 181)
	)
	(segment
		(start 144.250002 164.707833)
		(end 144.250002 164.602501)
		(width 0.1)
		(layer "In6.Cu")
		(net 181)
	)
	(segment
		(start 148.15 139.95)
		(end 148.15 139.877498)
		(width 0.1)
		(layer "In6.Cu")
		(net 181)
	)
	(segment
		(start 143.275001 160.174999)
		(end 143.475 159.975)
		(width 0.1)
		(layer "In6.Cu")
		(net 181)
	)
	(segment
		(start 143.71967 164.1775)
		(end 143.275001 163.732831)
		(width 0.1)
		(layer "In6.Cu")
		(net 181)
	)
	(segment
		(start 144.635505 159.155604)
		(end 144.635505 159.155605)
		(width 0.1)
		(layer "In6.Cu")
		(net 181)
	)
	(segment
		(start 144.577238 158.531652)
		(end 144.918348 158.872762)
		(width 0.1)
		(layer "In6.Cu")
		(net 181)
	)
	(segment
		(start 145.300001 165.487335)
		(end 144.990166 165.1775)
		(width 0.1)
		(layer "In6.Cu")
		(net 181)
	)
	(segment
		(start 146.274298 156.834593)
		(end 146.274296 156.834594)
		(width 0.1)
		(layer "In6.Cu")
		(net 181)
	)
	(segment
		(start 146.586273 156.863729)
		(end 150.1 153.35)
		(width 0.1)
		(layer "In6.Cu")
		(net 181)
	)
	(segment
		(start 145.766877 158.024232)
		(end 145.766877 158.024233)
		(width 0.1)
		(layer "In6.Cu")
		(net 181)
	)
	(segment
		(start 143.275001 163.732831)
		(end 143.275001 160.174999)
		(width 0.1)
		(layer "In6.Cu")
		(net 181)
	)
	(segment
		(start 146.332563 157.458546)
		(end 146.332563 157.458547)
		(width 0.1)
		(layer "In6.Cu")
		(net 181)
	)
	(segment
		(start 145.70861 157.40028)
		(end 146.04972 157.74139)
		(width 0.1)
		(layer "In6.Cu")
		(net 181)
	)
	(segment
		(start 144.57724 158.531651)
		(end 144.577238 158.531652)
		(width 0.1)
		(layer "In6.Cu")
		(net 181)
	)
	(segment
		(start 143.757842 159.975)
		(end 143.786976 160.004134)
		(width 0.1)
		(layer "In6.Cu")
		(net 181)
	)
	(segment
		(start 144.011552 159.097338)
		(end 144.352662 159.438448)
		(width 0.1)
		(layer "In6.Cu")
		(net 181)
	)
	(segment
		(start 144.635504 159.438448)
		(end 144.635505 159.438448)
		(width 0.1)
		(layer "In6.Cu")
		(net 181)
	)
	(segment
		(start 144.294395 158.531653)
		(end 144.294396 158.531651)
		(width 0.1)
		(layer "In6.Cu")
		(net 181)
	)
	(segment
		(start 145.142924 157.965966)
		(end 145.484034 158.307076)
		(width 0.1)
		(layer "In6.Cu")
		(net 181)
	)
	(segment
		(start 150.1 153.35)
		(end 150.1 148.492657)
		(width 0.1)
		(layer "In6.Cu")
		(net 181)
	)
	(segment
		(start 145.142926 157.965965)
		(end 145.142924 157.965966)
		(width 0.1)
		(layer "In6.Cu")
		(net 181)
	)
	(segment
		(start 144.069818 159.72129)
		(end 144.069818 159.721291)
		(width 0.1)
		(layer "In6.Cu")
		(net 181)
	)
	(arc
		(start 145.766877 158.307076)
		(mid 145.825456 158.165654)
		(end 145.766877 158.024232)
		(width 0.1)
		(layer "In6.Cu")
		(net 181)
	)
	(arc
		(start 144.635505 159.438448)
		(mid 144.694084 159.297026)
		(end 144.635505 159.155604)
		(width 0.1)
		(layer "In6.Cu")
		(net 181)
	)
	(arc
		(start 146.04972 157.74139)
		(mid 146.191141 157.799968)
		(end 146.332562 157.74139)
		(width 0.1)
		(layer "In6.Cu")
		(net 181)
	)
	(arc
		(start 146.303431 156.863729)
		(mid 146.444853 156.922307)
		(end 146.586274 156.863728)
		(width 0.1)
		(layer "In6.Cu")
		(net 181)
	)
	(arc
		(start 143.728709 159.380181)
		(mid 143.670132 159.238759)
		(end 143.728709 159.097339)
		(width 0.1)
		(layer "In6.Cu")
		(net 181)
	)
	(arc
		(start 144.860082 157.965965)
		(mid 145.001503 157.907387)
		(end 145.142926 157.965965)
		(width 0.1)
		(layer "In6.Cu")
		(net 181)
	)
	(arc
		(start 143.786976 160.004134)
		(mid 143.928398 160.062712)
		(end 144.069819 160.004133)
		(width 0.1)
		(layer "In6.Cu")
		(net 181)
	)
	(arc
		(start 145.201191 158.872762)
		(mid 145.25977 158.73134)
		(end 145.201191 158.589918)
		(width 0.1)
		(layer "In6.Cu")
		(net 181)
	)
	(arc
		(start 143.475 159.975)
		(mid 143.616421 159.916422)
		(end 143.757842 159.975)
		(width 0.1)
		(layer "In6.Cu")
		(net 181)
	)
	(arc
		(start 144.294396 158.531651)
		(mid 144.435817 158.473073)
		(end 144.57724 158.531651)
		(width 0.1)
		(layer "In6.Cu")
		(net 181)
	)
	(arc
		(start 144.352662 159.438448)
		(mid 144.494083 159.497026)
		(end 144.635504 159.438448)
		(width 0.1)
		(layer "In6.Cu")
		(net 181)
	)
	(arc
		(start 145.425767 157.683123)
		(mid 145.36719 157.541701)
		(end 145.425767 157.400281)
		(width 0.1)
		(layer "In6.Cu")
		(net 181)
	)
	(arc
		(start 144.069818 160.004134)
		(mid 144.128397 159.862712)
		(end 144.069818 159.72129)
		(width 0.1)
		(layer "In6.Cu")
		(net 181)
	)
	(arc
		(start 145.991454 156.834593)
		(mid 146.132875 156.776015)
		(end 146.274298 156.834593)
		(width 0.1)
		(layer "In6.Cu")
		(net 181)
	)
	(arc
		(start 144.918348 158.872762)
		(mid 145.059769 158.93134)
		(end 145.20119 158.872762)
		(width 0.1)
		(layer "In6.Cu")
		(net 181)
	)
	(arc
		(start 144.294395 158.814495)
		(mid 144.235818 158.673073)
		(end 144.294395 158.531653)
		(width 0.1)
		(layer "In6.Cu")
		(net 181)
	)
	(arc
		(start 144.860081 158.248809)
		(mid 144.801504 158.107387)
		(end 144.860081 157.965967)
		(width 0.1)
		(layer "In6.Cu")
		(net 181)
	)
	(arc
		(start 145.991453 157.117437)
		(mid 145.932876 156.976015)
		(end 145.991453 156.834595)
		(width 0.1)
		(layer "In6.Cu")
		(net 181)
	)
	(arc
		(start 146.332563 157.74139)
		(mid 146.391142 157.599968)
		(end 146.332563 157.458546)
		(width 0.1)
		(layer "In6.Cu")
		(net 181)
	)
	(arc
		(start 145.425768 157.400279)
		(mid 145.567189 157.341701)
		(end 145.708612 157.400279)
		(width 0.1)
		(layer "In6.Cu")
		(net 181)
	)
	(arc
		(start 143.72871 159.097337)
		(mid 143.870131 159.038759)
		(end 144.011554 159.097337)
		(width 0.1)
		(layer "In6.Cu")
		(net 181)
	)
	(arc
		(start 145.484034 158.307076)
		(mid 145.625455 158.365654)
		(end 145.766876 158.307076)
		(width 0.1)
		(layer "In6.Cu")
		(net 181)
	)
	(segment
		(start 148.400001 146.2025)
		(end 148.400001 147.2775)
		(width 0.201)
		(layer "F.Cu")
		(net 182)
	)
	(segment
		(start 143.375501 162.302)
		(end 143.875001 161.8025)
		(width 0.256)
		(layer "F.Cu")
		(net 182)
	)
	(via
		(at 148.400001 147.2775)
		(size 0.45)
		(drill 0.1)
		(layers "F.Cu" "B.Cu")
		(net 182)
	)
	(via
		(at 143.875001 161.8025)
		(size 0.45)
		(drill 0.1)
		(layers "F.Cu" "B.Cu")
		(net 182)
	)
	(segment
		(start 148.400001 147.660001)
		(end 148.6 147.86)
		(width 0.1)
		(layer "In2.Cu")
		(net 182)
	)
	(segment
		(start 148.400001 147.2775)
		(end 148.400001 147.660001)
		(width 0.1)
		(layer "In2.Cu")
		(net 182)
	)
	(segment
		(start 143.875001 160.8525)
		(end 148.6 156.127501)
		(width 0.1)
		(layer "In2.Cu")
		(net 182)
	)
	(segment
		(start 148.6 156.127501)
		(end 148.6 147.86)
		(width 0.1)
		(layer "In2.Cu")
		(net 182)
	)
	(segment
		(start 143.875001 161.8025)
		(end 143.875001 160.8525)
		(width 0.1)
		(layer "In2.Cu")
		(net 182)
	)
	(segment
		(start 145.375501 170.302)
		(end 145.875001 169.8025)
		(width 0.256)
		(layer "F.Cu")
		(net 183)
	)
	(segment
		(start 148.65 138.8025)
		(end 148.650001 137.727499)
		(width 0.201)
		(layer "F.Cu")
		(net 183)
	)
	(via
		(at 148.650001 137.727499)
		(size 0.45)
		(drill 0.1)
		(layers "F.Cu" "B.Cu")
		(net 183)
	)
	(via
		(at 145.875001 169.8025)
		(size 0.45)
		(drill 0.1)
		(layers "F.Cu" "B.Cu")
		(net 183)
	)
	(segment
		(start 147.796542 157.248013)
		(end 147.796542 157.248014)
		(width 0.1)
		(layer "In6.Cu")
		(net 183)
	)
	(segment
		(start 149.204901 155.545101)
		(end 150.75 154)
		(width 0.1)
		(layer "In6.Cu")
		(net 183)
	)
	(segment
		(start 149.7 140.5)
		(end 149.7 138.777498)
		(width 0.1)
		(layer "In6.Cu")
		(net 183)
	)
	(segment
		(start 143.475001 161.274999)
		(end 147.225 157.525)
		(width 0.1)
		(layer "In6.Cu")
		(net 183)
	)
	(segment
		(start 148.927915 156.399485)
		(end 148.927914 156.399486)
		(width 0.1)
		(layer "In6.Cu")
		(net 183)
	)
	(segment
		(start 148.927914 156.116642)
		(end 148.927914 156.116643)
		(width 0.1)
		(layer "In6.Cu")
		(net 183)
	)
	(segment
		(start 148.362229 156.965171)
		(end 148.362228 156.965172)
		(width 0.1)
		(layer "In6.Cu")
		(net 183)
	)
	(segment
		(start 143.775001 163.3025)
		(end 143.475001 163.0025)
		(width 0.1)
		(layer "In6.Cu")
		(net 183)
	)
	(segment
		(start 148.350515 156.104929)
		(end 148.350515 156.104928)
		(width 0.1)
		(layer "In6.Cu")
		(net 183)
	)
	(segment
		(start 151.25 145.627874)
		(end 151.25 142.05)
		(width 0.1)
		(layer "In6.Cu")
		(net 183)
	)
	(segment
		(start 148.350515 156.104928)
		(end 148.645072 156.399486)
		(width 0.1)
		(layer "In6.Cu")
		(net 183)
	)
	(segment
		(start 148.927914 156.116643)
		(end 148.633357 155.822085)
		(width 0.1)
		(layer "In6.Cu")
		(net 183)
	)
	(segment
		(start 151.25 142.05)
		(end 149.7 140.5)
		(width 0.1)
		(layer "In6.Cu")
		(net 183)
	)
	(segment
		(start 144.325001 163.9775)
		(end 144.325001 163.5525)
		(width 0.1)
		(layer "In6.Cu")
		(net 183)
	)
	(segment
		(start 147.501986 156.670614)
		(end 147.501985 156.670615)
		(width 0.1)
		(layer "In6.Cu")
		(net 183)
	)
	(segment
		(start 143.475001 163.0025)
		(end 143.475001 161.274999)
		(width 0.1)
		(layer "In6.Cu")
		(net 183)
	)
	(segment
		(start 149.204902 155.545101)
		(end 149.204901 155.545101)
		(width 0.1)
		(layer "In6.Cu")
		(net 183)
	)
	(segment
		(start 148.916201 155.539243)
		(end 148.916201 155.539242)
		(width 0.1)
		(layer "In6.Cu")
		(net 183)
	)
	(segment
		(start 149.7 138.777498)
		(end 148.650001 137.727499)
		(width 0.1)
		(layer "In6.Cu")
		(net 183)
	)
	(segment
		(start 145.375001 164.9525)
		(end 145.375001 164.5525)
		(width 0.1)
		(layer "In6.Cu")
		(net 183)
	)
	(segment
		(start 147.784829 156.670614)
		(end 148.079386 156.965172)
		(width 0.1)
		(layer "In6.Cu")
		(net 183)
	)
	(segment
		(start 145.375001 164.5525)
		(end 145.075001 164.2525)
		(width 0.1)
		(layer "In6.Cu")
		(net 183)
	)
	(segment
		(start 150.9 147.676501)
		(end 150.9 145.977874)
		(width 0.1)
		(layer "In6.Cu")
		(net 183)
	)
	(segment
		(start 147.796542 157.248014)
		(end 147.501985 156.953457)
		(width 0.1)
		(layer "In6.Cu")
		(net 183)
	)
	(segment
		(start 147.507842 157.525)
		(end 147.513699 157.530857)
		(width 0.1)
		(layer "In6.Cu")
		(net 183)
	)
	(segment
		(start 147.784829 156.670615)
		(end 147.784829 156.670614)
		(width 0.1)
		(layer "In6.Cu")
		(net 183)
	)
	(segment
		(start 150.75 147.826501)
		(end 150.9 147.676501)
		(width 0.1)
		(layer "In6.Cu")
		(net 183)
	)
	(segment
		(start 145.075001 164.2525)
		(end 144.600001 164.2525)
		(width 0.1)
		(layer "In6.Cu")
		(net 183)
	)
	(segment
		(start 144.325001 163.5525)
		(end 144.075001 163.3025)
		(width 0.1)
		(layer "In6.Cu")
		(net 183)
	)
	(segment
		(start 144.075001 163.3025)
		(end 143.775001 163.3025)
		(width 0.1)
		(layer "In6.Cu")
		(net 183)
	)
	(segment
		(start 145.725001 165.3025)
		(end 145.375001 164.9525)
		(width 0.1)
		(layer "In6.Cu")
		(net 183)
	)
	(segment
		(start 150.75 154)
		(end 150.75 147.826501)
		(width 0.1)
		(layer "In6.Cu")
		(net 183)
	)
	(segment
		(start 146.125001 165.3025)
		(end 145.725001 165.3025)
		(width 0.1)
		(layer "In6.Cu")
		(net 183)
	)
	(segment
		(start 146.375001 169.3025)
		(end 146.375001 165.5525)
		(width 0.1)
		(layer "In6.Cu")
		(net 183)
	)
	(segment
		(start 147.796542 157.530858)
		(end 147.796542 157.530857)
		(width 0.1)
		(layer "In6.Cu")
		(net 183)
	)
	(segment
		(start 150.9 145.977874)
		(end 151.25 145.627874)
		(width 0.1)
		(layer "In6.Cu")
		(net 183)
	)
	(segment
		(start 148.362228 156.682328)
		(end 148.362228 156.682329)
		(width 0.1)
		(layer "In6.Cu")
		(net 183)
	)
	(segment
		(start 148.362228 156.682329)
		(end 148.067671 156.387771)
		(width 0.1)
		(layer "In6.Cu")
		(net 183)
	)
	(segment
		(start 144.600001 164.2525)
		(end 144.325001 163.9775)
		(width 0.1)
		(layer "In6.Cu")
		(net 183)
	)
	(segment
		(start 146.375001 165.5525)
		(end 146.125001 165.3025)
		(width 0.1)
		(layer "In6.Cu")
		(net 183)
	)
	(segment
		(start 148.633358 155.539242)
		(end 148.633357 155.539243)
		(width 0.1)
		(layer "In6.Cu")
		(net 183)
	)
	(segment
		(start 148.916201 155.539242)
		(end 148.922059 155.5451)
		(width 0.1)
		(layer "In6.Cu")
		(net 183)
	)
	(segment
		(start 145.875001 169.8025)
		(end 146.375001 169.3025)
		(width 0.1)
		(layer "In6.Cu")
		(net 183)
	)
	(segment
		(start 148.067672 156.104928)
		(end 148.067671 156.104929)
		(width 0.1)
		(layer "In6.Cu")
		(net 183)
	)
	(arc
		(start 148.362228 156.965172)
		(mid 148.420807 156.82375)
		(end 148.362228 156.682328)
		(width 0.1)
		(layer "In6.Cu")
		(net 183)
	)
	(arc
		(start 148.633357 155.539243)
		(mid 148.77478 155.480663)
		(end 148.916201 155.539243)
		(width 0.1)
		(layer "In6.Cu")
		(net 183)
	)
	(arc
		(start 147.501985 156.670615)
		(mid 147.643408 156.612035)
		(end 147.784829 156.670615)
		(width 0.1)
		(layer "In6.Cu")
		(net 183)
	)
	(arc
		(start 147.225 157.525)
		(mid 147.366421 157.466422)
		(end 147.507842 157.525)
		(width 0.1)
		(layer "In6.Cu")
		(net 183)
	)
	(arc
		(start 147.796542 157.530857)
		(mid 147.855121 157.389435)
		(end 147.796542 157.248013)
		(width 0.1)
		(layer "In6.Cu")
		(net 183)
	)
	(arc
		(start 148.633357 155.822085)
		(mid 148.574779 155.680663)
		(end 148.633358 155.539242)
		(width 0.1)
		(layer "In6.Cu")
		(net 183)
	)
	(arc
		(start 148.922059 155.5451)
		(mid 149.06348 155.603679)
		(end 149.204902 155.545101)
		(width 0.1)
		(layer "In6.Cu")
		(net 183)
	)
	(arc
		(start 148.067671 156.387771)
		(mid 148.009093 156.246349)
		(end 148.067672 156.104928)
		(width 0.1)
		(layer "In6.Cu")
		(net 183)
	)
	(arc
		(start 147.501985 156.953457)
		(mid 147.443407 156.812035)
		(end 147.501986 156.670614)
		(width 0.1)
		(layer "In6.Cu")
		(net 183)
	)
	(arc
		(start 148.067671 156.104929)
		(mid 148.209094 156.046349)
		(end 148.350515 156.104929)
		(width 0.1)
		(layer "In6.Cu")
		(net 183)
	)
	(arc
		(start 148.079386 156.965172)
		(mid 148.220808 157.02375)
		(end 148.362229 156.965171)
		(width 0.1)
		(layer "In6.Cu")
		(net 183)
	)
	(arc
		(start 148.645072 156.399486)
		(mid 148.786494 156.458064)
		(end 148.927915 156.399485)
		(width 0.1)
		(layer "In6.Cu")
		(net 183)
	)
	(arc
		(start 147.513699 157.530857)
		(mid 147.65512 157.589436)
		(end 147.796542 157.530858)
		(width 0.1)
		(layer "In6.Cu")
		(net 183)
	)
	(arc
		(start 148.927914 156.399486)
		(mid 148.986493 156.258064)
		(end 148.927914 156.116642)
		(width 0.1)
		(layer "In6.Cu")
		(net 183)
	)
	(segment
		(start 142.375501 162.302001)
		(end 142.875001 161.8025)
		(width 0.256)
		(layer "F.Cu")
		(net 184)
	)
	(segment
		(start 148.900001 146.2025)
		(end 148.900001 145.1275)
		(width 0.201)
		(layer "F.Cu")
		(net 184)
	)
	(via
		(at 148.900001 145.1275)
		(size 0.45)
		(drill 0.1)
		(layers "F.Cu" "B.Cu")
		(net 184)
	)
	(via
		(at 142.875001 161.8025)
		(size 0.45)
		(drill 0.1)
		(layers "F.Cu" "B.Cu")
		(net 184)
	)
	(segment
		(start 149.100501 148.399499)
		(end 149.100501 145.328)
		(width 0.1)
		(layer "In6.Cu")
		(net 184)
	)
	(segment
		(start 142.875001 159.374999)
		(end 145.5 156.75)
		(width 0.1)
		(layer "In6.Cu")
		(net 184)
	)
	(segment
		(start 147.75 153.75)
		(end 148.25 153.75)
		(width 0.1)
		(layer "In6.Cu")
		(net 184)
	)
	(segment
		(start 149.5 152.5)
		(end 149.5 148.798998)
		(width 0.1)
		(layer "In6.Cu")
		(net 184)
	)
	(segment
		(start 148.25 153.75)
		(end 149.5 152.5)
		(width 0.1)
		(layer "In6.Cu")
		(net 184)
	)
	(segment
		(start 145.5 156)
		(end 147.75 153.75)
		(width 0.1)
		(layer "In6.Cu")
		(net 184)
	)
	(segment
		(start 145.5 156.75)
		(end 145.5 156)
		(width 0.1)
		(layer "In6.Cu")
		(net 184)
	)
	(segment
		(start 149.5 148.798998)
		(end 149.100501 148.399499)
		(width 0.1)
		(layer "In6.Cu")
		(net 184)
	)
	(segment
		(start 149.100501 145.328)
		(end 148.900001 145.1275)
		(width 0.1)
		(layer "In6.Cu")
		(net 184)
	)
	(segment
		(start 142.875001 161.8025)
		(end 142.875001 159.374999)
		(width 0.1)
		(layer "In6.Cu")
		(net 184)
	)
	(segment
		(start 194.615 140.215)
		(end 195.25 140.215)
		(width 0.15)
		(layer "F.Cu")
		(net 185)
	)
	(segment
		(start 193.695 139.75352)
		(end 193.695 138.945)
		(width 0.15)
		(layer "F.Cu")
		(net 185)
	)
	(segment
		(start 193.87074 139.92926)
		(end 193.695 139.75352)
		(width 0.15)
		(layer "F.Cu")
		(net 185)
	)
	(segment
		(start 194.32926 139.92926)
		(end 194.615 140.215)
		(width 0.15)
		(layer "F.Cu")
		(net 185)
	)
	(segment
		(start 194.32926 139.92926)
		(end 193.87074 139.92926)
		(width 0.15)
		(layer "F.Cu")
		(net 185)
	)
	(segment
		(start 205.0785 150.8035)
		(end 206.0795 150.8035)
		(width 0.256)
		(layer "F.Cu")
		(net 185)
	)
	(via
		(at 194.32926 139.92926)
		(size 0.45)
		(drill 0.1)
		(layers "F.Cu" "B.Cu")
		(net 185)
	)
	(via
		(at 206.0795 150.8035)
		(size 0.45)
		(drill 0.1)
		(layers "F.Cu" "B.Cu")
		(net 185)
	)
	(segment
		(start 193.1 148.675)
		(end 194.725 150.3)
		(width 0.15)
		(layer "B.Cu")
		(net 185)
	)
	(segment
		(start 193.89574 139.92926)
		(end 193.1 140.725)
		(width 0.15)
		(layer "B.Cu")
		(net 185)
	)
	(segment
		(start 194.725 150.3)
		(end 205.576 150.3)
		(width 0.15)
		(layer "B.Cu")
		(net 185)
	)
	(segment
		(start 193.1 140.725)
		(end 193.1 148.675)
		(width 0.15)
		(layer "B.Cu")
		(net 185)
	)
	(segment
		(start 195.95574 139.92926)
		(end 196.65 139.235)
		(width 0.15)
		(layer "B.Cu")
		(net 185)
	)
	(segment
		(start 194.32926 139.92926)
		(end 193.89574 139.92926)
		(width 0.15)
		(layer "B.Cu")
		(net 185)
	)
	(segment
		(start 205.576 150.3)
		(end 206.0795 150.8035)
		(width 0.15)
		(layer "B.Cu")
		(net 185)
	)
	(segment
		(start 194.32926 139.92926)
		(end 195.95574 139.92926)
		(width 0.15)
		(layer "B.Cu")
		(net 185)
	)
	(segment
		(start 194.503 138.318)
		(end 194.5 138.315)
		(width 0.15)
		(layer "F.Cu")
		(net 186)
	)
	(segment
		(start 199.1765 149.8035)
		(end 198.1755 149.8035)
		(width 0.256)
		(layer "F.Cu")
		(net 186)
	)
	(segment
		(start 195.386 138.318)
		(end 194.503 138.318)
		(width 0.15)
		(layer "F.Cu")
		(net 186)
	)
	(via
		(at 194.5 138.315)
		(size 0.45)
		(drill 0.1)
		(layers "F.Cu" "B.Cu")
		(net 186)
	)
	(via
		(at 198.1755 149.8035)
		(size 0.45)
		(drill 0.1)
		(layers "F.Cu" "B.Cu")
		(net 186)
	)
	(segment
		(start 197.375 138.99)
		(end 197.375 139.9)
		(width 0.15)
		(layer "B.Cu")
		(net 186)
	)
	(segment
		(start 196.65 138.265)
		(end 195.3 138.265)
		(width 0.15)
		(layer "B.Cu")
		(net 186)
	)
	(segment
		(start 194.6625 149.1375)
		(end 195.3285 149.8035)
		(width 0.15)
		(layer "B.Cu")
		(net 186)
	)
	(segment
		(start 194.5 138.315)
		(end 195.265 138.315)
		(width 0.256)
		(layer "B.Cu")
		(net 186)
	)
	(segment
		(start 193.625 141.375)
		(end 193.625 148.1)
		(width 0.15)
		(layer "B.Cu")
		(net 186)
	)
	(segment
		(start 197.375 139.9)
		(end 196.8 140.475)
		(width 0.15)
		(layer "B.Cu")
		(net 186)
	)
	(segment
		(start 195.3285 149.8035)
		(end 198.1755 149.8035)
		(width 0.15)
		(layer "B.Cu")
		(net 186)
	)
	(segment
		(start 193.625 148.1)
		(end 194.6625 149.1375)
		(width 0.15)
		(layer "B.Cu")
		(net 186)
	)
	(segment
		(start 194.525 140.475)
		(end 193.625 141.375)
		(width 0.15)
		(layer "B.Cu")
		(net 186)
	)
	(segment
		(start 195.265 138.315)
		(end 195.3 138.28)
		(width 0.1)
		(layer "B.Cu")
		(net 186)
	)
	(segment
		(start 196.65 138.265)
		(end 197.375 138.99)
		(width 0.15)
		(layer "B.Cu")
		(net 186)
	)
	(segment
		(start 195.3 138.28)
		(end 195.3 138.265)
		(width 0.1)
		(layer "B.Cu")
		(net 186)
	)
	(segment
		(start 196.8 140.475)
		(end 194.525 140.475)
		(width 0.15)
		(layer "B.Cu")
		(net 186)
	)
	(segment
		(start 146.375501 183.301)
		(end 146.875001 183.8005)
		(width 0.256)
		(layer "F.Cu")
		(net 187)
	)
	(segment
		(start 146.375502 185.301)
		(end 146.875001 185.8005)
		(width 0.256)
		(layer "F.Cu")
		(net 187)
	)
	(segment
		(start 146.375501 181.301)
		(end 146.875001 181.8005)
		(width 0.256)
		(layer "F.Cu")
		(net 187)
	)
	(segment
		(start 146.375501 179.301)
		(end 146.875001 179.800501)
		(width 0.256)
		(layer "F.Cu")
		(net 187)
	)
	(segment
		(start 146.375501 177.301)
		(end 146.875001 177.8005)
		(width 0.256)
		(layer "F.Cu")
		(net 187)
	)
	(via
		(at 188.2 187.75)
		(size 0.45)
		(drill 0.1)
		(layers "F.Cu" "B.Cu")
		(net 187)
	)
	(via
		(at 146.875001 177.8005)
		(size 0.45)
		(drill 0.1)
		(layers "F.Cu" "B.Cu")
		(net 187)
	)
	(via
		(at 186.1 187.5)
		(size 0.45)
		(drill 0.1)
		(layers "F.Cu" "B.Cu")
		(net 187)
	)
	(via
		(at 186.1 186.75)
		(size 0.45)
		(drill 0.1)
		(layers "F.Cu" "B.Cu")
		(net 187)
	)
	(via
		(at 186.1 189.7)
		(size 0.45)
		(drill 0.1)
		(layers "F.Cu" "B.Cu")
		(net 187)
	)
	(via
		(at 186.1 188.2)
		(size 0.45)
		(drill 0.1)
		(layers "F.Cu" "B.Cu")
		(net 187)
	)
	(via
		(at 188.2 187.15)
		(size 0.45)
		(drill 0.1)
		(layers "F.Cu" "B.Cu")
		(net 187)
	)
	(via
		(at 186.1 188.9)
		(size 0.45)
		(drill 0.1)
		(layers "F.Cu" "B.Cu")
		(net 187)
	)
	(via
		(at 146.875001 185.8005)
		(size 0.45)
		(drill 0.1)
		(layers "F.Cu" "B.Cu")
		(net 187)
	)
	(via
		(at 187.2 187.7)
		(size 0.45)
		(drill 0.1)
		(layers "F.Cu" "B.Cu")
		(net 187)
	)
	(via
		(at 146.875001 179.800501)
		(size 0.45)
		(drill 0.1)
		(layers "F.Cu" "B.Cu")
		(net 187)
	)
	(via
		(at 146.875001 181.8005)
		(size 0.45)
		(drill 0.1)
		(layers "F.Cu" "B.Cu")
		(net 187)
	)
	(via
		(at 146.875001 183.8005)
		(size 0.45)
		(drill 0.1)
		(layers "F.Cu" "B.Cu")
		(net 187)
	)
	(segment
		(start 146.877 179.800501)
		(end 147.377001 179.3005)
		(width 0.4)
		(layer "B.Cu")
		(net 187)
	)
	(segment
		(start 186.4 186.45)
		(end 186.1 186.75)
		(width 0.15)
		(layer "B.Cu")
		(net 187)
	)
	(segment
		(start 146.873001 183.8005)
		(end 146.375001 184.2985)
		(width 0.4)
		(layer "B.Cu")
		(net 187)
	)
	(segment
		(start 146.375001 181.3005)
		(end 146.875001 181.8005)
		(width 0.4)
		(layer "B.Cu")
		(net 187)
	)
	(segment
		(start 147.379001 178.3025)
		(end 147.377001 178.3025)
		(width 0.4)
		(layer "B.Cu")
		(net 187)
	)
	(segment
		(start 146.875001 179.800501)
		(end 146.877 179.800501)
		(width 0.4)
		(layer "B.Cu")
		(net 187)
	)
	(segment
		(start 146.875001 185.8005)
		(end 146.375501 185.301)
		(width 0.4)
		(layer "B.Cu")
		(net 187)
	)
	(segment
		(start 186.4 184.85)
		(end 186.4 186.45)
		(width 0.15)
		(layer "B.Cu")
		(net 187)
	)
	(segment
		(start 147.377001 178.3025)
		(end 146.875001 177.8005)
		(width 0.4)
		(layer "B.Cu")
		(net 187)
	)
	(segment
		(start 146.875001 183.8005)
		(end 146.873001 183.8005)
		(width 0.4)
		(layer "B.Cu")
		(net 187)
	)
	(segment
		(start 143.375501 173.302)
		(end 143.875001 172.8025)
		(width 0.256)
		(layer "F.Cu")
		(net 188)
	)
	(segment
		(start 98.224 133.995)
		(end 98.205 133.976)
		(width 0.256)
		(layer "F.Cu")
		(net 188)
	)
	(segment
		(start 140.375501 176.301)
		(end 140.875001 176.8005)
		(width 0.256)
		(layer "F.Cu")
		(net 188)
	)
	(segment
		(start 142.375501 176.300999)
		(end 142.875001 176.8005)
		(width 0.256)
		(layer "F.Cu")
		(net 188)
	)
	(segment
		(start 141.375501 177.301)
		(end 141.875001 177.8005)
		(width 0.256)
		(layer "F.Cu")
		(net 188)
	)
	(segment
		(start 142.375501 172.301999)
		(end 142.875001 171.8025)
		(width 0.256)
		(layer "F.Cu")
		(net 188)
	)
	(segment
		(start 144.375501 172.302)
		(end 144.875001 171.8025)
		(width 0.256)
		(layer "F.Cu")
		(net 188)
	)
	(segment
		(start 141.375501 171.302)
		(end 141.875001 170.8025)
		(width 0.256)
		(layer "F.Cu")
		(net 188)
	)
	(segment
		(start 98.925 133.995)
		(end 98.224 133.995)
		(width 0.256)
		(layer "F.Cu")
		(net 188)
	)
	(segment
		(start 144.375501 183.301)
		(end 144.875001 183.8005)
		(width 0.256)
		(layer "F.Cu")
		(net 188)
	)
	(segment
		(start 146.375502 175.301)
		(end 146.875001 175.800499)
		(width 0.256)
		(layer "F.Cu")
		(net 188)
	)
	(segment
		(start 144.375501 174.301999)
		(end 144.875 173.8025)
		(width 0.256)
		(layer "F.Cu")
		(net 188)
	)
	(segment
		(start 142.375501 174.302)
		(end 142.875001 173.8025)
		(width 0.256)
		(layer "F.Cu")
		(net 188)
	)
	(via
		(at 187.2 182.075)
		(size 0.45)
		(drill 0.1)
		(layers "F.Cu" "B.Cu")
		(net 188)
	)
	(via
		(at 187.8 181.7)
		(size 0.45)
		(drill 0.1)
		(layers "F.Cu" "B.Cu")
		(net 188)
	)
	(via
		(at 187.8 180.9)
		(size 0.45)
		(drill 0.1)
		(layers "F.Cu" "B.Cu")
		(net 188)
	)
	(via
		(at 141.875001 170.8025)
		(size 0.45)
		(drill 0.1)
		(layers "F.Cu" "B.Cu")
		(net 188)
	)
	(via
		(at 143.875001 172.8025)
		(size 0.45)
		(drill 0.1)
		(layers "F.Cu" "B.Cu")
		(net 188)
	)
	(via
		(at 144.875 173.8025)
		(size 0.45)
		(drill 0.1)
		(layers "F.Cu" "B.Cu")
		(net 188)
	)
	(via
		(at 187.2 181.4)
		(size 0.45)
		(drill 0.1)
		(layers "F.Cu" "B.Cu")
		(net 188)
	)
	(via
		(at 179.2 161.6)
		(size 0.45)
		(drill 0.1)
		(layers "F.Cu" "B.Cu")
		(free yes)
		(net 188)
	)
	(via
		(at 144.875001 183.8005)
		(size 0.45)
		(drill 0.1)
		(layers "F.Cu" "B.Cu")
		(net 188)
	)
	(via
		(at 142.875001 171.8025)
		(size 0.45)
		(drill 0.1)
		(layers "F.Cu" "B.Cu")
		(net 188)
	)
	(via
		(at 141.875001 177.8005)
		(size 0.45)
		(drill 0.1)
		(layers "F.Cu" "B.Cu")
		(net 188)
	)
	(via
		(at 186.175 179.725)
		(size 0.45)
		(drill 0.1)
		(layers "F.Cu" "B.Cu")
		(net 188)
	)
	(via
		(at 144.875001 171.8025)
		(size 0.45)
		(drill 0.1)
		(layers "F.Cu" "B.Cu")
		(net 188)
	)
	(via
		(at 186.9 180.8)
		(size 0.45)
		(drill 0.1)
		(layers "F.Cu" "B.Cu")
		(net 188)
	)
	(via
		(at 188.325 182.05)
		(size 0.45)
		(drill 0.1)
		(layers "F.Cu" "B.Cu")
		(net 188)
	)
	(via
		(at 146.875001 175.800499)
		(size 0.45)
		(drill 0.1)
		(layers "F.Cu" "B.Cu")
		(net 188)
	)
	(via
		(at 186.175 179)
		(size 0.45)
		(drill 0.1)
		(layers "F.Cu" "B.Cu")
		(net 188)
	)
	(via
		(at 142.875001 176.8005)
		(size 0.45)
		(drill 0.1)
		(layers "F.Cu" "B.Cu")
		(net 188)
	)
	(via
		(at 186.175 181.15)
		(size 0.45)
		(drill 0.1)
		(layers "F.Cu" "B.Cu")
		(net 188)
	)
	(via
		(at 140.875001 176.8005)
		(size 0.45)
		(drill 0.1)
		(layers "F.Cu" "B.Cu")
		(net 188)
	)
	(via
		(at 98.205 133.976)
		(size 0.45)
		(drill 0.1)
		(layers "F.Cu" "B.Cu")
		(net 188)
	)
	(via
		(at 186.175 180.45)
		(size 0.45)
		(drill 0.1)
		(layers "F.Cu" "B.Cu")
		(net 188)
	)
	(via
		(at 140.875501 174.801)
		(size 0.45)
		(drill 0.1)
		(layers "F.Cu" "B.Cu")
		(net 188)
	)
	(via
		(at 142.875001 173.8025)
		(size 0.45)
		(drill 0.1)
		(layers "F.Cu" "B.Cu")
		(net 188)
	)
	(via
		(at 188.325 181.3)
		(size 0.45)
		(drill 0.1)
		(layers "F.Cu" "B.Cu")
		(net 188)
	)
	(segment
		(start 141.950001 174.3265)
		(end 141.475501 174.801)
		(width 0.256)
		(layer "B.Cu")
		(net 188)
	)
	(segment
		(start 145.475501 174.851)
		(end 145.900001 175.2755)
		(width 0.4)
		(layer "B.Cu")
		(net 188)
	)
	(segment
		(start 140.275501 174.801)
		(end 141.475501 174.801)
		(width 0.4)
		(layer "B.Cu")
		(net 188)
	)
	(segment
		(start 141.373501 175.603)
		(end 141.475501 175.501)
		(width 0.256)
		(layer "B.Cu")
		(net 188)
	)
	(segment
		(start 141.375501 178.301)
		(end 141.375501 178.3)
		(width 0.4)
		(layer "B.Cu")
		(net 188)
	)
	(segment
		(start 141.373501 176.302)
		(end 140.875001 176.8005)
		(width 0.4)
		(layer "B.Cu")
		(net 188)
	)
	(segment
		(start 145.475501 174.801)
		(end 145.475501 174.851)
		(width 0.4)
		(layer "B.Cu")
		(net 188)
	)
	(segment
		(start 99.429 135.2)
		(end 172.6 135.2)
		(width 0.4)
		(layer "B.Cu")
		(net 188)
	)
	(segment
		(start 142.351001 174.3265)
		(end 142.875001 173.8025)
		(width 0.256)
		(layer "B.Cu")
		(net 188)
	)
	(segment
		(start 142.351001 174.3265)
		(end 141.950001 174.3265)
		(width 0.256)
		(layer "B.Cu")
		(net 188)
	)
	(segment
		(start 144.377501 173.301)
		(end 144.377501 173.305001)
		(width 0.4)
		(layer "B.Cu")
		(net 188)
	)
	(segment
		(start 142.375501 177.303)
		(end 142.375501 177.3)
		(width 0.4)
		(layer "B.Cu")
		(net 188)
	)
	(segment
		(start 142.375501 173.303)
		(end 142.875001 173.8025)
		(width 0.4)
		(layer "B.Cu")
		(net 188)
	)
	(segment
		(start 141.475501 174.801)
		(end 141.475501 175.501)
		(width 0.256)
		(layer "B.Cu")
		(net 188)
	)
	(segment
		(start 146.375501 176.299999)
		(end 146.875001 175.800499)
		(width 0.4)
		(layer "B.Cu")
		(net 188)
	)
	(segment
		(start 142.375501 177.3)
		(end 142.875001 176.8005)
		(width 0.4)
		(layer "B.Cu")
		(net 188)
	)
	(segment
		(start 145.900001 175.2755)
		(end 146.092464 175.2755)
		(width 0.4)
		(layer "B.Cu")
		(net 188)
	)
	(segment
		(start 142.376501 172.301)
		(end 142.875001 171.8025)
		(width 0.4)
		(layer "B.Cu")
		(net 188)
	)
	(segment
		(start 145.475501 174.751)
		(end 144.875 174.150499)
		(width 0.4)
		(layer "B.Cu")
		(net 188)
	)
	(segment
		(start 143.872001 172.8025)
		(end 143.375501 173.299)
		(width 0.4)
		(layer "B.Cu")
		(net 188)
	)
	(segment
		(start 141.875001 170.8025)
		(end 142.375001 171.3025)
		(width 0.4)
		(layer "B.Cu")
		(net 188)
	)
	(segment
		(start 145.373501 172.301)
		(end 144.875001 171.8025)
		(width 0.4)
		(layer "B.Cu")
		(net 188)
	)
	(segment
		(start 186.425 182.075)
		(end 186.4 182.1)
		(width 0.15)
		(layer "B.Cu")
		(net 188)
	)
	(segment
		(start 142.373501 172.301)
		(end 142.376501 172.301)
		(width 0.4)
		(layer "B.Cu")
		(net 188)
	)
	(segment
		(start 146.375501 176.301)
		(end 146.375501 176.299999)
		(width 0.4)
		(layer "B.Cu")
		(net 188)
	)
	(segment
		(start 146.617463 175.800499)
		(end 146.875001 175.800499)
		(width 0.4)
		(layer "B.Cu")
		(net 188)
	)
	(segment
		(start 144.377001 184.2985)
		(end 144.875001 183.8005)
		(width 0.4)
		(layer "B.Cu")
		(net 188)
	)
	(segment
		(start 141.375501 178.3)
		(end 141.875001 177.8005)
		(width 0.4)
		(layer "B.Cu")
		(net 188)
	)
	(segment
		(start 187.2 182.075)
		(end 186.425 182.075)
		(width 0.15)
		(layer "B.Cu")
		(net 188)
	)
	(segment
		(start 143.875001 172.8025)
		(end 143.872001 172.8025)
		(width 0.4)
		(layer "B.Cu")
		(net 188)
	)
	(segment
		(start 144.377001 184.3005)
		(end 144.377001 184.2985)
		(width 0.4)
		(layer "B.Cu")
		(net 188)
	)
	(segment
		(start 185.4 155.4)
		(end 179.2 161.6)
		(width 0.4)
		(layer "B.Cu")
		(net 188)
	)
	(segment
		(start 98.205 133.976)
		(end 99.429 135.2)
		(width 0.4)
		(layer "B.Cu")
		(net 188)
	)
	(segment
		(start 146.875001 175.800499)
		(end 146.877 175.800499)
		(width 0.4)
		(layer "B.Cu")
		(net 188)
	)
	(segment
		(start 142.375501 177.303)
		(end 142.372501 177.303)
		(width 0.4)
		(layer "B.Cu")
		(net 188)
	)
	(segment
		(start 172.6 135.2)
		(end 185.4 148)
		(width 0.4)
		(layer "B.Cu")
		(net 188)
	)
	(segment
		(start 146.092464 175.2755)
		(end 146.617463 175.800499)
		(width 0.4)
		(layer "B.Cu")
		(net 188)
	)
	(segment
		(start 141.373501 176.301)
		(end 141.373501 175.603)
		(width 0.256)
		(layer "B.Cu")
		(net 188)
	)
	(segment
		(start 142.375501 173.301)
		(end 142.375501 173.303)
		(width 0.4)
		(layer "B.Cu")
		(net 188)
	)
	(segment
		(start 185.4 148)
		(end 185.4 155.4)
		(width 0.4)
		(layer "B.Cu")
		(net 188)
	)
	(segment
		(start 144.377501 173.305001)
		(end 144.875 173.8025)
		(width 0.4)
		(layer "B.Cu")
		(net 188)
	)
	(segment
		(start 142.372501 177.303)
		(end 141.875001 177.8005)
		(width 0.4)
		(layer "B.Cu")
		(net 188)
	)
	(segment
		(start 145.475501 174.801)
		(end 145.475501 174.751)
		(width 0.4)
		(layer "B.Cu")
		(net 188)
	)
	(segment
		(start 141.373501 176.301)
		(end 141.373501 176.302)
		(width 0.4)
		(layer "B.Cu")
		(net 188)
	)
	(segment
		(start 146.877 175.800499)
		(end 147.377501 176.301)
		(width 0.4)
		(layer "B.Cu")
		(net 188)
	)
	(segment
		(start 144.875 174.150499)
		(end 144.875 173.8025)
		(width 0.4)
		(layer "B.Cu")
		(net 188)
	)
	(segment
		(start 145.328001 183.3475)
		(end 145.992001 183.3475)
		(width 0.256)
		(layer "In8.Cu")
		(net 188)
	)
	(segment
		(start 145.992001 183.3475)
		(end 146.350501 182.989)
		(width 0.256)
		(layer "In8.Cu")
		(net 188)
	)
	(segment
		(start 146.350501 176.324999)
		(end 146.875001 175.800499)
		(width 0.256)
		(layer "In8.Cu")
		(net 188)
	)
	(segment
		(start 144.875001 183.8005)
		(end 145.328001 183.3475)
		(width 0.256)
		(layer "In8.Cu")
		(net 188)
	)
	(segment
		(start 146.350501 182.989)
		(end 146.350501 176.324999)
		(width 0.256)
		(layer "In8.Cu")
		(net 188)
	)
	(segment
		(start 146.375501 164.302)
		(end 146.875001 163.8025)
		(width 0.256)
		(layer "F.Cu")
		(net 189)
	)
	(segment
		(start 149.65 138.8025)
		(end 149.65 137.727499)
		(width 0.201)
		(layer "F.Cu")
		(net 189)
	)
	(via
		(at 149.65 137.727499)
		(size 0.45)
		(drill 0.1)
		(layers "F.Cu" "B.Cu")
		(net 189)
	)
	(via
		(at 146.875001 163.8025)
		(size 0.45)
		(drill 0.1)
		(layers "F.Cu" "B.Cu")
		(net 189)
	)
	(segment
		(start 150.125501 145.302)
		(end 150.125501 144.7515)
		(width 0.148)
		(layer "In9.Cu")
		(net 189)
	)
	(segment
		(start 150.980115 158.603299)
		(end 150.828934 158.452118)
		(width 0.148)
		(layer "In9.Cu")
		(net 189)
	)
	(segment
		(start 149.945048 158.98245)
		(end 149.617093 158.654494)
		(width 0.148)
		(layer "In9.Cu")
		(net 189)
	)
	(segment
		(start 150.273006 159.310408)
		(end 149.945048 158.98245)
		(width 0.148)
		(layer "In9.Cu")
		(net 189)
	)
	(segment
		(start 149.65 144.275999)
		(end 149.65 137.727499)
		(width 0.148)
		(layer "In9.Cu")
		(net 189)
	)
	(segment
		(start 149.970648 158.30094)
		(end 150.298606 158.628898)
		(width 0.148)
		(layer "In9.Cu")
		(net 189)
	)
	(segment
		(start 147.340501 163.337)
		(end 147.340501 161.587)
		(width 0.148)
		(layer "In9.Cu")
		(net 189)
	)
	(segment
		(start 149.263539 159.008049)
		(end 149.591497 159.336007)
		(width 0.148)
		(layer "In9.Cu")
		(net 189)
	)
	(segment
		(start 150.980116 158.956853)
		(end 150.980115 158.956853)
		(width 0.148)
		(layer "In9.Cu")
		(net 189)
	)
	(segment
		(start 148.909984 159.008049)
		(end 148.909985 159.008049)
		(width 0.148)
		(layer "In9.Cu")
		(net 189)
	)
	(segment
		(start 151.125501 147.88925)
		(end 150.900501 147.66425)
		(width 0.148)
		(layer "In9.Cu")
		(net 189)
	)
	(segment
		(start 148.858788 160.724626)
		(end 148.707607 160.573445)
		(width 0.148)
		(layer "In9.Cu")
		(net 189)
	)
	(segment
		(start 150.900501 146.077)
		(end 150.125501 145.302)
		(width 0.148)
		(layer "In9.Cu")
		(net 189)
	)
	(segment
		(start 148.884388 160.043116)
		(end 149.212344 160.371071)
		(width 0.148)
		(layer "In9.Cu")
		(net 189)
	)
	(segment
		(start 150.125501 144.7515)
		(end 149.65 144.275999)
		(width 0.148)
		(layer "In9.Cu")
		(net 189)
	)
	(segment
		(start 149.617093 158.30094)
		(end 149.617094 158.30094)
		(width 0.148)
		(layer "In9.Cu")
		(net 189)
	)
	(segment
		(start 151.125501 157.802)
		(end 151.125501 147.88925)
		(width 0.148)
		(layer "In9.Cu")
		(net 189)
	)
	(segment
		(start 148.202875 159.715158)
		(end 148.202876 159.715158)
		(width 0.148)
		(layer "In9.Cu")
		(net 189)
	)
	(segment
		(start 147.340501 161.587)
		(end 148.000501 160.927)
		(width 0.148)
		(layer "In9.Cu")
		(net 189)
	)
	(segment
		(start 149.565897 160.017517)
		(end 149.237939 159.689559)
		(width 0.148)
		(layer "In9.Cu")
		(net 189)
	)
	(segment
		(start 148.707607 160.573445)
		(end 148.202875 160.068712)
		(width 0.148)
		(layer "In9.Cu")
		(net 189)
	)
	(segment
		(start 150.828934 158.098564)
		(end 151.125501 157.802)
		(width 0.148)
		(layer "In9.Cu")
		(net 189)
	)
	(segment
		(start 148.55643 159.715158)
		(end 148.884388 160.043116)
		(width 0.148)
		(layer "In9.Cu")
		(net 189)
	)
	(segment
		(start 150.298606 158.628898)
		(end 150.626562 158.956853)
		(width 0.148)
		(layer "In9.Cu")
		(net 189)
	)
	(segment
		(start 148.354053 160.927)
		(end 148.354054 160.927)
		(width 0.148)
		(layer "In9.Cu")
		(net 189)
	)
	(segment
		(start 148.858787 161.078181)
		(end 148.858788 161.07818)
		(width 0.148)
		(layer "In9.Cu")
		(net 189)
	)
	(segment
		(start 146.875001 163.8025)
		(end 147.340501 163.337)
		(width 0.148)
		(layer "In9.Cu")
		(net 189)
	)
	(segment
		(start 150.900501 147.66425)
		(end 150.900501 146.077)
		(width 0.148)
		(layer "In9.Cu")
		(net 189)
	)
	(segment
		(start 148.354054 160.927)
		(end 148.505234 161.07818)
		(width 0.148)
		(layer "In9.Cu")
		(net 189)
	)
	(segment
		(start 150.828933 158.098565)
		(end 150.828934 158.098564)
		(width 0.148)
		(layer "In9.Cu")
		(net 189)
	)
	(segment
		(start 149.565898 160.371071)
		(end 149.565897 160.371071)
		(width 0.148)
		(layer "In9.Cu")
		(net 189)
	)
	(segment
		(start 149.591497 159.336007)
		(end 149.919453 159.663962)
		(width 0.148)
		(layer "In9.Cu")
		(net 189)
	)
	(segment
		(start 149.237939 159.689559)
		(end 148.909984 159.361603)
		(width 0.148)
		(layer "In9.Cu")
		(net 189)
	)
	(segment
		(start 150.273007 159.663962)
		(end 150.273006 159.663962)
		(width 0.148)
		(layer "In9.Cu")
		(net 189)
	)
	(arc
		(start 148.000501 160.927)
		(mid 148.177277 160.853777)
		(end 148.354053 160.927)
		(width 0.148)
		(layer "In9.Cu")
		(net 189)
	)
	(arc
		(start 148.202875 160.068712)
		(mid 148.129652 159.891935)
		(end 148.202875 159.715158)
		(width 0.148)
		(layer "In9.Cu")
		(net 189)
	)
	(arc
		(start 148.858788 161.07818)
		(mid 148.932011 160.901403)
		(end 148.858788 160.724626)
		(width 0.148)
		(layer "In9.Cu")
		(net 189)
	)
	(arc
		(start 149.565897 160.371071)
		(mid 149.63912 160.194294)
		(end 149.565897 160.017517)
		(width 0.148)
		(layer "In9.Cu")
		(net 189)
	)
	(arc
		(start 148.202876 159.715158)
		(mid 148.379653 159.641935)
		(end 148.55643 159.715158)
		(width 0.148)
		(layer "In9.Cu")
		(net 189)
	)
	(arc
		(start 149.617093 158.654494)
		(mid 149.54387 158.477717)
		(end 149.617093 158.30094)
		(width 0.148)
		(layer "In9.Cu")
		(net 189)
	)
	(arc
		(start 150.626562 158.956853)
		(mid 150.803339 159.030076)
		(end 150.980116 158.956853)
		(width 0.148)
		(layer "In9.Cu")
		(net 189)
	)
	(arc
		(start 150.980115 158.956853)
		(mid 151.053338 158.780076)
		(end 150.980115 158.603299)
		(width 0.148)
		(layer "In9.Cu")
		(net 189)
	)
	(arc
		(start 148.909984 159.361603)
		(mid 148.836761 159.184826)
		(end 148.909984 159.008049)
		(width 0.148)
		(layer "In9.Cu")
		(net 189)
	)
	(arc
		(start 149.212344 160.371071)
		(mid 149.389121 160.444294)
		(end 149.565898 160.371071)
		(width 0.148)
		(layer "In9.Cu")
		(net 189)
	)
	(arc
		(start 148.505234 161.07818)
		(mid 148.68201 161.151404)
		(end 148.858787 161.078181)
		(width 0.148)
		(layer "In9.Cu")
		(net 189)
	)
	(arc
		(start 149.617094 158.30094)
		(mid 149.793871 158.227717)
		(end 149.970648 158.30094)
		(width 0.148)
		(layer "In9.Cu")
		(net 189)
	)
	(arc
		(start 150.273006 159.663962)
		(mid 150.346229 159.487185)
		(end 150.273006 159.310408)
		(width 0.148)
		(layer "In9.Cu")
		(net 189)
	)
	(arc
		(start 149.919453 159.663962)
		(mid 150.09623 159.737185)
		(end 150.273007 159.663962)
		(width 0.148)
		(layer "In9.Cu")
		(net 189)
	)
	(arc
		(start 148.909985 159.008049)
		(mid 149.086762 158.934826)
		(end 149.263539 159.008049)
		(width 0.148)
		(layer "In9.Cu")
		(net 189)
	)
	(arc
		(start 150.828934 158.452118)
		(mid 150.75571 158.275342)
		(end 150.828933 158.098565)
		(width 0.148)
		(layer "In9.Cu")
		(net 189)
	)
	(segment
		(start 149.92 146.8225)
		(end 149.919999 147.292427)
		(width 0.26)
		(layer "F.Cu")
		(net 190)
	)
	(segment
		(start 149.919999 147.292427)
		(end 149.875 147.337426)
		(width 0.26)
		(layer "F.Cu")
		(net 190)
	)
	(segment
		(start 149.9 146.2025)
		(end 149.9 146.8025)
		(width 0.26)
		(layer "F.Cu")
		(net 190)
	)
	(segment
		(start 149.9 146.8025)
		(end 149.92 146.8225)
		(width 0.26)
		(layer "F.Cu")
		(net 190)
	)
	(segment
		(start 145.375501 162.302)
		(end 145.875001 161.8025)
		(width 0.256)
		(layer "F.Cu")
		(net 190)
	)
	(via
		(at 145.875001 161.8025)
		(size 0.45)
		(drill 0.1)
		(layers "F.Cu" "B.Cu")
		(net 190)
	)
	(via
		(at 149.875 147.337426)
		(size 0.45)
		(drill 0.1)
		(layers "F.Cu" "B.Cu")
		(net 190)
	)
	(segment
		(start 149.495501 153.340501)
		(end 147.89634 153.340501)
		(width 0.13)
		(layer "In9.Cu")
		(net 190)
	)
	(segment
		(start 149.255501 149.095501)
		(end 149.255501 148.552294)
		(width 0.13)
		(layer "In9.Cu")
		(net 190)
	)
	(segment
		(start 149.255501 150.850501)
		(end 150.154662 150.850501)
		(width 0.13)
		(layer "In9.Cu")
		(net 190)
	)
	(segment
		(start 147.89634 152.350501)
		(end 149.255501 152.350501)
		(width 0.13)
		(layer "In9.Cu")
		(net 190)
	)
	(segment
		(start 145.973001 162.202499)
		(end 146.106246 162.202499)
		(width 0.1)
		(layer "In9.Cu")
		(net 190)
	)
	(segment
		(start 147.89634 153.850501)
		(end 149.255501 153.850501)
		(width 0.13)
		(layer "In9.Cu")
		(net 190)
	)
	(segment
		(start 149.255501 156.852294)
		(end 149.255501 155.845501)
		(width 0.13)
		(layer "In9.Cu")
		(net 190)
	)
	(segment
		(start 149.255501 153.850501)
		(end 150.154662 153.850501)
		(width 0.13)
		(layer "In9.Cu")
		(net 190)
	)
	(segment
		(start 150.154662 151.840501)
		(end 149.495501 151.840501)
		(width 0.13)
		(layer "In9.Cu")
		(net 190)
	)
	(segment
		(start 145.875001 161.8025)
		(end 145.875001 162.104499)
		(width 0.1)
		(layer "In9.Cu")
		(net 190)
	)
	(segment
		(start 150.03 147.777795)
		(end 150.03 147.492426)
		(width 0.13)
		(layer "In9.Cu")
		(net 190)
	)
	(segment
		(start 146.250223 159.857572)
		(end 149.255501 156.852294)
		(width 0.13)
		(layer "In9.Cu")
		(net 190)
	)
	(segment
		(start 146.106246 162.202499)
		(end 146.275001 162.033744)
		(width 0.1)
		(layer "In9.Cu")
		(net 190)
	)
	(segment
		(start 146.275001 162.033744)
		(end 146.275001 161.357478)
		(width 0.1)
		(layer "In9.Cu")
		(net 190)
	)
	(segment
		(start 146.275001 161.357478)
		(end 146.250223 161.3327)
		(width 0.1)
		(layer "In9.Cu")
		(net 190)
	)
	(segment
		(start 149.255501 152.350501)
		(end 150.154662 152.350501)
		(width 0.13)
		(layer "In9.Cu")
		(net 190)
	)
	(segment
		(start 150.154662 150.340501)
		(end 149.495501 150.340501)
		(width 0.13)
		(layer "In9.Cu")
		(net 190)
	)
	(segment
		(start 145.875001 162.104499)
		(end 145.973001 162.202499)
		(width 0.1)
		(layer "In9.Cu")
		(net 190)
	)
	(segment
		(start 150.03 147.492426)
		(end 149.875 147.337426)
		(width 0.13)
		(layer "In9.Cu")
		(net 190)
	)
	(segment
		(start 147.89634 150.850501)
		(end 149.255501 150.850501)
		(width 0.13)
		(layer "In9.Cu")
		(net 190)
	)
	(segment
		(start 146.250223 161.3327)
		(end 146.250223 159.857572)
		(width 0.13)
		(layer "In9.Cu")
		(net 190)
	)
	(segment
		(start 150.154662 154.840501)
		(end 149.750501 154.840501)
		(width 0.13)
		(layer "In9.Cu")
		(net 190)
	)
	(segment
		(start 147.89634 149.350501)
		(end 149.000501 149.350501)
		(width 0.13)
		(layer "In9.Cu")
		(net 190)
	)
	(segment
		(start 149.750501 154.840501)
		(end 147.89634 154.840501)
		(width 0.13)
		(layer "In9.Cu")
		(net 190)
	)
	(segment
		(start 149.495501 150.340501)
		(end 147.89634 150.340501)
		(width 0.13)
		(layer "In9.Cu")
		(net 190)
	)
	(segment
		(start 149.750501 155.350501)
		(end 150.154662 155.350501)
		(width 0.13)
		(layer "In9.Cu")
		(net 190)
	)
	(segment
		(start 150.154662 153.340501)
		(end 149.495501 153.340501)
		(width 0.13)
		(layer "In9.Cu")
		(net 190)
	)
	(segment
		(start 149.255501 148.552294)
		(end 150.03 147.777795)
		(width 0.13)
		(layer "In9.Cu")
		(net 190)
	)
	(segment
		(start 149.495501 151.840501)
		(end 147.89634 151.840501)
		(width 0.13)
		(layer "In9.Cu")
		(net 190)
	)
	(arc
		(start 147.89634 153.340501)
		(mid 147.546322 153.195519)
		(end 147.40134 152.845501)
		(width 0.13)
		(layer "In9.Cu")
		(net 190)
	)
	(arc
		(start 150.154662 155.350501)
		(mid 150.334974 155.275813)
		(end 150.409662 155.095501)
		(width 0.13)
		(layer "In9.Cu")
		(net 190)
	)
	(arc
		(start 150.409662 150.595501)
		(mid 150.334974 150.415189)
		(end 150.154662 150.340501)
		(width 0.13)
		(layer "In9.Cu")
		(net 190)
	)
	(arc
		(start 150.409662 155.095501)
		(mid 150.334974 154.915189)
		(end 150.154662 154.840501)
		(width 0.13)
		(layer "In9.Cu")
		(net 190)
	)
	(arc
		(start 147.89634 150.340501)
		(mid 147.546322 150.195519)
		(end 147.40134 149.845501)
		(width 0.13)
		(layer "In9.Cu")
		(net 190)
	)
	(arc
		(start 147.89634 151.840501)
		(mid 147.546322 151.695519)
		(end 147.40134 151.345501)
		(width 0.13)
		(layer "In9.Cu")
		(net 190)
	)
	(arc
		(start 150.409662 153.595501)
		(mid 150.334974 153.415189)
		(end 150.154662 153.340501)
		(width 0.13)
		(layer "In9.Cu")
		(net 190)
	)
	(arc
		(start 147.40134 154.345501)
		(mid 147.546322 153.995483)
		(end 147.89634 153.850501)
		(width 0.13)
		(layer "In9.Cu")
		(net 190)
	)
	(arc
		(start 149.255501 155.845501)
		(mid 149.400483 155.495483)
		(end 149.750501 155.350501)
		(width 0.13)
		(layer "In9.Cu")
		(net 190)
	)
	(arc
		(start 150.154662 152.350501)
		(mid 150.334974 152.275813)
		(end 150.409662 152.095501)
		(width 0.13)
		(layer "In9.Cu")
		(net 190)
	)
	(arc
		(start 147.40134 151.345501)
		(mid 147.546322 150.995483)
		(end 147.89634 150.850501)
		(width 0.13)
		(layer "In9.Cu")
		(net 190)
	)
	(arc
		(start 150.154662 150.850501)
		(mid 150.334974 150.775813)
		(end 150.409662 150.595501)
		(width 0.13)
		(layer "In9.Cu")
		(net 190)
	)
	(arc
		(start 147.40134 152.845501)
		(mid 147.546322 152.495483)
		(end 147.89634 152.350501)
		(width 0.13)
		(layer "In9.Cu")
		(net 190)
	)
	(arc
		(start 147.40134 149.845501)
		(mid 147.546322 149.495483)
		(end 147.89634 149.350501)
		(width 0.13)
		(layer "In9.Cu")
		(net 190)
	)
	(arc
		(start 150.409662 152.095501)
		(mid 150.334974 151.915189)
		(end 150.154662 151.840501)
		(width 0.13)
		(layer "In9.Cu")
		(net 190)
	)
	(arc
		(start 149.000501 149.350501)
		(mid 149.180813 149.275813)
		(end 149.255501 149.095501)
		(width 0.13)
		(layer "In9.Cu")
		(net 190)
	)
	(arc
		(start 147.89634 154.840501)
		(mid 147.546322 154.695519)
		(end 147.40134 154.345501)
		(width 0.13)
		(layer "In9.Cu")
		(net 190)
	)
	(arc
		(start 150.154662 153.850501)
		(mid 150.334974 153.775813)
		(end 150.409662 153.595501)
		(width 0.13)
		(layer "In9.Cu")
		(net 190)
	)
	(segment
		(start 150.38 146.8225)
		(end 150.380001 147.292427)
		(width 0.26)
		(layer "F.Cu")
		(net 191)
	)
	(segment
		(start 150.4 146.8025)
		(end 150.38 146.8225)
		(width 0.26)
		(layer "F.Cu")
		(net 191)
	)
	(segment
		(start 150.380001 147.292427)
		(end 150.425 147.337426)
		(width 0.26)
		(layer "F.Cu")
		(net 191)
	)
	(segment
		(start 150.4 146.2025)
		(end 150.4 146.8025)
		(width 0.26)
		(layer "F.Cu")
		(net 191)
	)
	(segment
		(start 145.375501 163.302)
		(end 145.875001 162.8025)
		(width 0.256)
		(layer "F.Cu")
		(net 191)
	)
	(via
		(at 150.425 147.337426)
		(size 0.45)
		(drill 0.1)
		(layers "F.Cu" "B.Cu")
		(net 191)
	)
	(via
		(at 145.875001 162.8025)
		(size 0.45)
		(drill 0.1)
		(layers "F.Cu" "B.Cu")
		(net 191)
	)
	(segment
		(start 146.490223 161.3327)
		(end 146.490223 159.956984)
		(width 0.13)
		(layer "In9.Cu")
		(net 191)
	)
	(segment
		(start 149.255501 154.090501)
		(end 150.154662 154.090501)
		(width 0.13)
		(layer "In9.Cu")
		(net 191)
	)
	(segment
		(start 149.495501 151.600501)
		(end 147.89634 151.600501)
		(width 0.13)
		(layer "In9.Cu")
		(net 191)
	)
	(segment
		(start 149.750501 154.600501)
		(end 147.89634 154.600501)
		(width 0.13)
		(layer "In9.Cu")
		(net 191)
	)
	(segment
		(start 149.255501 151.090501)
		(end 150.154662 151.090501)
		(width 0.13)
		(layer "In9.Cu")
		(net 191)
	)
	(segment
		(start 146.475001 161.347922)
		(end 146.490223 161.3327)
		(width 0.1)
		(layer "In9.Cu")
		(net 191)
	)
	(segment
		(start 146.189089 162.4025)
		(end 146.475001 162.116588)
		(width 0.1)
		(layer "In9.Cu")
		(net 191)
	)
	(segment
		(start 149.495501 156.951706)
		(end 149.495501 155.845501)
		(width 0.13)
		(layer "In9.Cu")
		(net 191)
	)
	(segment
		(start 147.738906 159.061853)
		(end 147.738907 159.061853)
		(width 0.13)
		(layer "In9.Cu")
		(net 191)
	)
	(segment
		(start 150.27 147.877207)
		(end 150.27 147.492426)
		(width 0.13)
		(layer "In9.Cu")
		(net 191)
	)
	(segment
		(start 149.495501 153.100501)
		(end 147.89634 153.100501)
		(width 0.13)
		(layer "In9.Cu")
		(net 191)
	)
	(segment
		(start 147.89634 154.090501)
		(end 149.255501 154.090501)
		(width 0.13)
		(layer "In9.Cu")
		(net 191)
	)
	(segment
		(start 149.750501 155.590501)
		(end 150.154662 155.590501)
		(width 0.13)
		(layer "In9.Cu")
		(net 191)
	)
	(segment
		(start 149.255501 152.590501)
		(end 150.154662 152.590501)
		(width 0.13)
		(layer "In9.Cu")
		(net 191)
	)
	(segment
		(start 150.154662 151.600501)
		(end 149.495501 151.600501)
		(width 0.13)
		(layer "In9.Cu")
		(net 191)
	)
	(segment
		(start 148.129623 158.745461)
		(end 148.09246 158.708298)
		(width 0.13)
		(layer "In9.Cu")
		(net 191)
	)
	(segment
		(start 150.154662 154.600501)
		(end 149.750501 154.600501)
		(width 0.13)
		(layer "In9.Cu")
		(net 191)
	)
	(segment
		(start 147.89634 152.590501)
		(end 149.255501 152.590501)
		(width 0.13)
		(layer "In9.Cu")
		(net 191)
	)
	(segment
		(start 148.129622 159.099016)
		(end 148.129623 159.099015)
		(width 0.13)
		(layer "In9.Cu")
		(net 191)
	)
	(segment
		(start 148.092459 158.354745)
		(end 149.495501 156.951706)
		(width 0.13)
		(layer "In9.Cu")
		(net 191)
	)
	(segment
		(start 147.89634 151.090501)
		(end 149.255501 151.090501)
		(width 0.13)
		(layer "In9.Cu")
		(net 191)
	)
	(segment
		(start 150.154662 153.100501)
		(end 149.495501 153.100501)
		(width 0.13)
		(layer "In9.Cu")
		(net 191)
	)
	(segment
		(start 150.27 147.492426)
		(end 150.425 147.337426)
		(width 0.13)
		(layer "In9.Cu")
		(net 191)
	)
	(segment
		(start 146.475001 162.116588)
		(end 146.475001 161.347922)
		(width 0.1)
		(layer "In9.Cu")
		(net 191)
	)
	(segment
		(start 146.490223 159.956984)
		(end 147.385354 159.061853)
		(width 0.13)
		(layer "In9.Cu")
		(net 191)
	)
	(segment
		(start 145.875001 162.5045)
		(end 145.977001 162.4025)
		(width 0.1)
		(layer "In9.Cu")
		(net 191)
	)
	(segment
		(start 149.495501 150.100501)
		(end 147.89634 150.100501)
		(width 0.13)
		(layer "In9.Cu")
		(net 191)
	)
	(segment
		(start 150.154662 150.100501)
		(end 149.495501 150.100501)
		(width 0.13)
		(layer "In9.Cu")
		(net 191)
	)
	(segment
		(start 149.495501 148.651706)
		(end 150.27 147.877207)
		(width 0.13)
		(layer "In9.Cu")
		(net 191)
	)
	(segment
		(start 145.875001 162.8025)
		(end 145.875001 162.5045)
		(width 0.1)
		(layer "In9.Cu")
		(net 191)
	)
	(segment
		(start 149.495501 149.095501)
		(end 149.495501 148.651706)
		(width 0.13)
		(layer "In9.Cu")
		(net 191)
	)
	(segment
		(start 147.738907 159.061853)
		(end 147.776069 159.099015)
		(width 0.13)
		(layer "In9.Cu")
		(net 191)
	)
	(segment
		(start 147.89634 149.590501)
		(end 149.000501 149.590501)
		(width 0.13)
		(layer "In9.Cu")
		(net 191)
	)
	(segment
		(start 145.977001 162.4025)
		(end 146.189089 162.4025)
		(width 0.1)
		(layer "In9.Cu")
		(net 191)
	)
	(arc
		(start 150.649662 150.595501)
		(mid 150.50468 150.245483)
		(end 150.154662 150.100501)
		(width 0.13)
		(layer "In9.Cu")
		(net 191)
	)
	(arc
		(start 150.154662 151.090501)
		(mid 150.50468 150.945519)
		(end 150.649662 150.595501)
		(width 0.13)
		(layer "In9.Cu")
		(net 191)
	)
	(arc
		(start 149.495501 155.845501)
		(mid 149.570189 155.665189)
		(end 149.750501 155.590501)
		(width 0.13)
		(layer "In9.Cu")
		(net 191)
	)
	(arc
		(start 147.64134 154.345501)
		(mid 147.716028 154.165189)
		(end 147.89634 154.090501)
		(width 0.13)
		(layer "In9.Cu")
		(net 191)
	)
	(arc
		(start 147.64134 149.845501)
		(mid 147.716028 149.665189)
		(end 147.89634 149.590501)
		(width 0.13)
		(layer "In9.Cu")
		(net 191)
	)
	(arc
		(start 147.385354 159.061853)
		(mid 147.56213 158.98863)
		(end 147.738906 159.061853)
		(width 0.13)
		(layer "In9.Cu")
		(net 191)
	)
	(arc
		(start 147.776069 159.099015)
		(mid 147.952845 159.172239)
		(end 148.129622 159.099016)
		(width 0.13)
		(layer "In9.Cu")
		(net 191)
	)
	(arc
		(start 147.64134 151.345501)
		(mid 147.716028 151.165189)
		(end 147.89634 151.090501)
		(width 0.13)
		(layer "In9.Cu")
		(net 191)
	)
	(arc
		(start 147.89634 151.600501)
		(mid 147.716028 151.525813)
		(end 147.64134 151.345501)
		(width 0.13)
		(layer "In9.Cu")
		(net 191)
	)
	(arc
		(start 150.649662 155.095501)
		(mid 150.50468 154.745483)
		(end 150.154662 154.600501)
		(width 0.13)
		(layer "In9.Cu")
		(net 191)
	)
	(arc
		(start 147.89634 153.100501)
		(mid 147.716028 153.025813)
		(end 147.64134 152.845501)
		(width 0.13)
		(layer "In9.Cu")
		(net 191)
	)
	(arc
		(start 150.154662 154.090501)
		(mid 150.50468 153.945519)
		(end 150.649662 153.595501)
		(width 0.13)
		(layer "In9.Cu")
		(net 191)
	)
	(arc
		(start 150.154662 155.590501)
		(mid 150.50468 155.445519)
		(end 150.649662 155.095501)
		(width 0.13)
		(layer "In9.Cu")
		(net 191)
	)
	(arc
		(start 147.89634 150.100501)
		(mid 147.716028 150.025813)
		(end 147.64134 149.845501)
		(width 0.13)
		(layer "In9.Cu")
		(net 191)
	)
	(arc
		(start 147.64134 152.845501)
		(mid 147.716028 152.665189)
		(end 147.89634 152.590501)
		(width 0.13)
		(layer "In9.Cu")
		(net 191)
	)
	(arc
		(start 148.129623 159.099015)
		(mid 148.202846 158.922238)
		(end 148.129623 158.745461)
		(width 0.13)
		(layer "In9.Cu")
		(net 191)
	)
	(arc
		(start 147.89634 154.600501)
		(mid 147.716028 154.525813)
		(end 147.64134 154.345501)
		(width 0.13)
		(layer "In9.Cu")
		(net 191)
	)
	(arc
		(start 149.000501 149.590501)
		(mid 149.350519 149.445519)
		(end 149.495501 149.095501)
		(width 0.13)
		(layer "In9.Cu")
		(net 191)
	)
	(arc
		(start 150.649662 153.595501)
		(mid 150.50468 153.245483)
		(end 150.154662 153.100501)
		(width 0.13)
		(layer "In9.Cu")
		(net 191)
	)
	(arc
		(start 150.154662 152.590501)
		(mid 150.50468 152.445519)
		(end 150.649662 152.095501)
		(width 0.13)
		(layer "In9.Cu")
		(net 191)
	)
	(arc
		(start 150.649662 152.095501)
		(mid 150.50468 151.745483)
		(end 150.154662 151.600501)
		(width 0.13)
		(layer "In9.Cu")
		(net 191)
	)
	(arc
		(start 148.09246 158.708298)
		(mid 148.019236 158.531522)
		(end 148.092459 158.354745)
		(width 0.13)
		(layer "In9.Cu")
		(net 191)
	)
	(segment
		(start 150.650001 138.8025)
		(end 150.65 137.7275)
		(width 0.201)
		(layer "F.Cu")
		(net 192)
	)
	(segment
		(start 148.375501 171.302)
		(end 148.875001 170.8025)
		(width 0.256)
		(layer "F.Cu")
		(net 192)
	)
	(via
		(at 150.65 137.7275)
		(size 0.45)
		(drill 0.1)
		(layers "F.Cu" "B.Cu")
		(net 192)
	)
	(via
		(at 148.875001 170.8025)
		(size 0.45)
		(drill 0.1)
		(layers "F.Cu" "B.Cu")
		(net 192)
	)
	(segment
		(start 153.375501 145.802)
		(end 153.975501 146.402)
		(width 0.148)
		(layer "In9.Cu")
		(net 192)
	)
	(segment
		(start 149.3775 170.3)
		(end 148.875001 170.8025)
		(width 0.148)
		(layer "In9.Cu")
		(net 192)
	)
	(segment
		(start 149.4 166.926499)
		(end 149.773501 167.3)
		(width 0.148)
		(layer "In9.Cu")
		(net 192)
	)
	(segment
		(start 149.578113 165.321887)
		(end 149.4 165.5)
		(width 0.148)
		(layer "In9.Cu")
		(net 192)
	)
	(segment
		(start 150.4 169.960637)
		(end 150.060637 170.3)
		(width 0.148)
		(layer "In9.Cu")
		(net 192)
	)
	(segment
		(start 150.060637 170.3)
		(end 149.3775 170.3)
		(width 0.148)
		(layer "In9.Cu")
		(net 192)
	)
	(segment
		(start 153.375501 143.951)
		(end 153.375501 145.802)
		(width 0.148)
		(layer "In9.Cu")
		(net 192)
	)
	(segment
		(start 152.105614 165.321887)
		(end 149.578113 165.321887)
		(width 0.148)
		(layer "In9.Cu")
		(net 192)
	)
	(segment
		(start 153.975501 163.452)
		(end 152.105614 165.321887)
		(width 0.148)
		(layer "In9.Cu")
		(net 192)
	)
	(segment
		(start 150.2 167.3)
		(end 150.4 167.5)
		(width 0.148)
		(layer "In9.Cu")
		(net 192)
	)
	(segment
		(start 149.773501 167.3)
		(end 150.2 167.3)
		(width 0.148)
		(layer "In9.Cu")
		(net 192)
	)
	(segment
		(start 150.65 137.7275)
		(end 150.65 141.225499)
		(width 0.148)
		(layer "In9.Cu")
		(net 192)
	)
	(segment
		(start 150.65 141.225499)
		(end 153.375501 143.951)
		(width 0.148)
		(layer "In9.Cu")
		(net 192)
	)
	(segment
		(start 150.4 167.5)
		(end 150.4 169.960637)
		(width 0.148)
		(layer "In9.Cu")
		(net 192)
	)
	(segment
		(start 149.4 165.5)
		(end 149.4 166.926499)
		(width 0.148)
		(layer "In9.Cu")
		(net 192)
	)
	(segment
		(start 153.975501 146.402)
		(end 153.975501 163.452)
		(width 0.148)
		(layer "In9.Cu")
		(net 192)
	)
	(segment
		(start 145.375501 172.302)
		(end 145.875001 171.8025)
		(width 0.256)
		(layer "F.Cu")
		(net 193)
	)
	(segment
		(start 151.400001 146.2025)
		(end 151.400001 147.2775)
		(width 0.201)
		(layer "F.Cu")
		(net 193)
	)
	(via
		(at 151.400001 147.2775)
		(size 0.45)
		(drill 0.1)
		(layers "F.Cu" "B.Cu")
		(net 193)
	)
	(via
		(at 145.875001 171.8025)
		(size 0.45)
		(drill 0.1)
		(layers "F.Cu" "B.Cu")
		(net 193)
	)
	(segment
		(start 151.127501 164.3)
		(end 148.7 164.3)
		(width 0.148)
		(layer "In9.Cu")
		(net 193)
	)
	(segment
		(start 152.297815 156.302)
		(end 152.625501 156.302)
		(width 0.148)
		(layer "In9.Cu")
		(net 193)
	)
	(segment
		(start 152.625501 156.302)
		(end 152.953187 156.302)
		(width 0.148)
		(layer "In9.Cu")
		(net 193)
	)
	(segment
		(start 152.875501 149.802)
		(end 152.297815 149.802)
		(width 0.148)
		(layer "In9.Cu")
		(net 193)
	)
	(segment
		(start 149.157637 169.302)
		(end 147.586751 169.302)
		(width 0.148)
		(layer "In9.Cu")
		(net 193)
	)
	(segment
		(start 152.625501 160.052)
		(end 151.375501 161.302)
		(width 0.148)
		(layer "In9.Cu")
		(net 193)
	)
	(segment
		(start 152.953187 155.802)
		(end 152.625501 155.802)
		(width 0.148)
		(layer "In9.Cu")
		(net 193)
	)
	(segment
		(start 147.1 170.3)
		(end 146.536501 170.3)
		(width 0.148)
		(layer "In9.Cu")
		(net 193)
	)
	(segment
		(start 146.536501 170.3)
		(end 146.328001 170.5085)
		(width 0.148)
		(layer "In9.Cu")
		(net 193)
	)
	(segment
		(start 152.625501 151.802)
		(end 152.297815 151.802)
		(width 0.148)
		(layer "In9.Cu")
		(net 193)
	)
	(segment
		(start 152.625501 153.302)
		(end 152.953187 153.302)
		(width 0.148)
		(layer "In9.Cu")
		(net 193)
	)
	(segment
		(start 152.297815 153.302)
		(end 152.625501 153.302)
		(width 0.148)
		(layer "In9.Cu")
		(net 193)
	)
	(segment
		(start 148.6 167.3)
		(end 149.073501 167.3)
		(width 0.148)
		(layer "In9.Cu")
		(net 193)
	)
	(segment
		(start 149.375501 169.084136)
		(end 149.157637 169.302)
		(width 0.148)
		(layer "In9.Cu")
		(net 193)
	)
	(segment
		(start 152.953187 152.802)
		(end 152.625501 152.802)
		(width 0.148)
		(layer "In9.Cu")
		(net 193)
	)
	(segment
		(start 147.4 169.488751)
		(end 147.4 170)
		(width 0.148)
		(layer "In9.Cu")
		(net 193)
	)
	(segment
		(start 152.625501 150.302)
		(end 152.953187 150.302)
		(width 0.148)
		(layer "In9.Cu")
		(net 193)
	)
	(segment
		(start 151.375501 164.052)
		(end 151.127501 164.3)
		(width 0.148)
		(layer "In9.Cu")
		(net 193)
	)
	(segment
		(start 152.297815 150.302)
		(end 152.625501 150.302)
		(width 0.148)
		(layer "In9.Cu")
		(net 193)
	)
	(segment
		(start 152.625501 155.802)
		(end 152.297815 155.802)
		(width 0.148)
		(layer "In9.Cu")
		(net 193)
	)
	(segment
		(start 152.625501 151.302)
		(end 152.953187 151.302)
		(width 0.148)
		(layer "In9.Cu")
		(net 193)
	)
	(segment
		(start 152.297815 157.302)
		(end 152.625501 157.302)
		(width 0.148)
		(layer "In9.Cu")
		(net 193)
	)
	(segment
		(start 152.297815 155.302)
		(end 152.625501 155.302)
		(width 0.148)
		(layer "In9.Cu")
		(net 193)
	)
	(segment
		(start 152.875501 149.302)
		(end 152.953187 149.302)
		(width 0.148)
		(layer "In9.Cu")
		(net 193)
	)
	(segment
		(start 152.953187 156.802)
		(end 152.625501 156.802)
		(width 0.148)
		(layer "In9.Cu")
		(net 193)
	)
	(segment
		(start 149.073501 167.3)
		(end 149.375501 167.602)
		(width 0.148)
		(layer "In9.Cu")
		(net 193)
	)
	(segment
		(start 147.586751 169.302)
		(end 147.4 169.488751)
		(width 0.148)
		(layer "In9.Cu")
		(net 193)
	)
	(segment
		(start 152.625501 153.802)
		(end 152.297815 153.802)
		(width 0.148)
		(layer "In9.Cu")
		(net 193)
	)
	(segment
		(start 147.4 170)
		(end 147.1 170.3)
		(width 0.148)
		(layer "In9.Cu")
		(net 193)
	)
	(segment
		(start 152.953187 151.802)
		(end 152.625501 151.802)
		(width 0.148)
		(layer "In9.Cu")
		(net 193)
	)
	(segment
		(start 152.625501 156.802)
		(end 152.297815 156.802)
		(width 0.148)
		(layer "In9.Cu")
		(net 193)
	)
	(segment
		(start 152.953187 153.802)
		(end 152.625501 153.802)
		(width 0.148)
		(layer "In9.Cu")
		(net 193)
	)
	(segment
		(start 152.953187 157.802)
		(end 152.875501 157.802)
		(width 0.148)
		(layer "In9.Cu")
		(net 193)
	)
	(segment
		(start 152.953187 149.802)
		(end 152.875501 149.802)
		(width 0.148)
		(layer "In9.Cu")
		(net 193)
	)
	(segment
		(start 152.625501 152.302)
		(end 152.953187 152.302)
		(width 0.148)
		(layer "In9.Cu")
		(net 193)
	)
	(segment
		(start 152.297815 152.302)
		(end 152.625501 152.302)
		(width 0.148)
		(layer "In9.Cu")
		(net 193)
	)
	(segment
		(start 152.297815 151.302)
		(end 152.625501 151.302)
		(width 0.148)
		(layer "In9.Cu")
		(net 193)
	)
	(segment
		(start 152.625501 150.802)
		(end 152.297815 150.802)
		(width 0.148)
		(layer "In9.Cu")
		(net 193)
	)
	(segment
		(start 146.328001 171.3495)
		(end 145.875001 171.8025)
		(width 0.148)
		(layer "In9.Cu")
		(net 193)
	)
	(segment
		(start 152.625501 148.503)
		(end 152.625501 149.052)
		(width 0.148)
		(layer "In9.Cu")
		(net 193)
	)
	(segment
		(start 146.328001 170.5085)
		(end 146.328001 171.3495)
		(width 0.148)
		(layer "In9.Cu")
		(net 193)
	)
	(segment
		(start 152.625501 158.052)
		(end 152.625501 160.052)
		(width 0.148)
		(layer "In9.Cu")
		(net 193)
	)
	(segment
		(start 152.297815 154.302)
		(end 152.625501 154.302)
		(width 0.148)
		(layer "In9.Cu")
		(net 193)
	)
	(segment
		(start 152.625501 155.302)
		(end 152.953187 155.302)
		(width 0.148)
		(layer "In9.Cu")
		(net 193)
	)
	(segment
		(start 152.953187 150.802)
		(end 152.625501 150.802)
		(width 0.148)
		(layer "In9.Cu")
		(net 193)
	)
	(segment
		(start 152.953187 154.802)
		(end 152.625501 154.802)
		(width 0.148)
		(layer "In9.Cu")
		(net 193)
	)
	(segment
		(start 151.400001 147.2775)
		(end 152.625501 148.503)
		(width 0.148)
		(layer "In9.Cu")
		(net 193)
	)
	(segment
		(start 152.625501 154.802)
		(end 152.297815 154.802)
		(width 0.148)
		(layer "In9.Cu")
		(net 193)
	)
	(segment
		(start 149.375501 167.602)
		(end 149.375501 169.084136)
		(width 0.148)
		(layer "In9.Cu")
		(net 193)
	)
	(segment
		(start 152.625501 157.302)
		(end 152.953187 157.302)
		(width 0.148)
		(layer "In9.Cu")
		(net 193)
	)
	(segment
		(start 152.625501 152.802)
		(end 152.297815 152.802)
		(width 0.148)
		(layer "In9.Cu")
		(net 193)
	)
	(segment
		(start 151.375501 161.302)
		(end 151.375501 164.052)
		(width 0.148)
		(layer "In9.Cu")
		(net 193)
	)
	(segment
		(start 148.401002 167.101002)
		(end 148.6 167.3)
		(width 0.148)
		(layer "In9.Cu")
		(net 193)
	)
	(segment
		(start 148.401002 164.598998)
		(end 148.401002 167.101002)
		(width 0.148)
		(layer "In9.Cu")
		(net 193)
	)
	(segment
		(start 152.625501 154.302)
		(end 152.953187 154.302)
		(width 0.148)
		(layer "In9.Cu")
		(net 193)
	)
	(segment
		(start 148.7 164.3)
		(end 148.401002 164.598998)
		(width 0.148)
		(layer "In9.Cu")
		(net 193)
	)
	(arc
		(start 152.297815 150.802)
		(mid 152.121038 150.875223)
		(end 152.047815 151.052)
		(width 0.148)
		(layer "In9.Cu")
		(net 193)
	)
	(arc
		(start 152.047815 153.052)
		(mid 152.121038 153.228777)
		(end 152.297815 153.302)
		(width 0.148)
		(layer "In9.Cu")
		(net 193)
	)
	(arc
		(start 152.953187 155.302)
		(mid 153.129964 155.375223)
		(end 153.203187 155.552)
		(width 0.148)
		(layer "In9.Cu")
		(net 193)
	)
	(arc
		(start 152.953187 151.302)
		(mid 153.129964 151.375223)
		(end 153.203187 151.552)
		(width 0.148)
		(layer "In9.Cu")
		(net 193)
	)
	(arc
		(start 152.297815 151.802)
		(mid 152.121038 151.875223)
		(end 152.047815 152.052)
		(width 0.148)
		(layer "In9.Cu")
		(net 193)
	)
	(arc
		(start 152.047815 151.052)
		(mid 152.121038 151.228777)
		(end 152.297815 151.302)
		(width 0.148)
		(layer "In9.Cu")
		(net 193)
	)
	(arc
		(start 153.203187 156.552)
		(mid 153.129964 156.728777)
		(end 152.953187 156.802)
		(width 0.148)
		(layer "In9.Cu")
		(net 193)
	)
	(arc
		(start 152.297815 155.802)
		(mid 152.121038 155.875223)
		(end 152.047815 156.052)
		(width 0.148)
		(layer "In9.Cu")
		(net 193)
	)
	(arc
		(start 152.953187 150.302)
		(mid 153.129964 150.375223)
		(end 153.203187 150.552)
		(width 0.148)
		(layer "In9.Cu")
		(net 193)
	)
	(arc
		(start 153.203187 150.552)
		(mid 153.129964 150.728777)
		(end 152.953187 150.802)
		(width 0.148)
		(layer "In9.Cu")
		(net 193)
	)
	(arc
		(start 152.953187 154.302)
		(mid 153.129964 154.375223)
		(end 153.203187 154.552)
		(width 0.148)
		(layer "In9.Cu")
		(net 193)
	)
	(arc
		(start 152.047815 155.052)
		(mid 152.121038 155.228777)
		(end 152.297815 155.302)
		(width 0.148)
		(layer "In9.Cu")
		(net 193)
	)
	(arc
		(start 152.297815 154.802)
		(mid 152.121038 154.875223)
		(end 152.047815 155.052)
		(width 0.148)
		(layer "In9.Cu")
		(net 193)
	)
	(arc
		(start 153.203187 154.552)
		(mid 153.129964 154.728777)
		(end 152.953187 154.802)
		(width 0.148)
		(layer "In9.Cu")
		(net 193)
	)
	(arc
		(start 152.047815 156.052)
		(mid 152.121038 156.228777)
		(end 152.297815 156.302)
		(width 0.148)
		(layer "In9.Cu")
		(net 193)
	)
	(arc
		(start 152.297815 152.802)
		(mid 152.121038 152.875223)
		(end 152.047815 153.052)
		(width 0.148)
		(layer "In9.Cu")
		(net 193)
	)
	(arc
		(start 152.047815 150.052)
		(mid 152.121038 150.228777)
		(end 152.297815 150.302)
		(width 0.148)
		(layer "In9.Cu")
		(net 193)
	)
	(arc
		(start 152.297815 149.802)
		(mid 152.121038 149.875223)
		(end 152.047815 150.052)
		(width 0.148)
		(layer "In9.Cu")
		(net 193)
	)
	(arc
		(start 153.203187 157.552)
		(mid 153.129964 157.728777)
		(end 152.953187 157.802)
		(width 0.148)
		(layer "In9.Cu")
		(net 193)
	)
	(arc
		(start 152.047815 154.052)
		(mid 152.121038 154.228777)
		(end 152.297815 154.302)
		(width 0.148)
		(layer "In9.Cu")
		(net 193)
	)
	(arc
		(start 152.953187 152.302)
		(mid 153.129964 152.375223)
		(end 153.203187 152.552)
		(width 0.148)
		(layer "In9.Cu")
		(net 193)
	)
	(arc
		(start 153.203187 149.552)
		(mid 153.129964 149.728777)
		(end 152.953187 149.802)
		(width 0.148)
		(layer "In9.Cu")
		(net 193)
	)
	(arc
		(start 153.203187 151.552)
		(mid 153.129964 151.728777)
		(end 152.953187 151.802)
		(width 0.148)
		(layer "In9.Cu")
		(net 193)
	)
	(arc
		(start 152.047815 157.052)
		(mid 152.121038 157.228777)
		(end 152.297815 157.302)
		(width 0.148)
		(layer "In9.Cu")
		(net 193)
	)
	(arc
		(start 152.625501 149.052)
		(mid 152.698724 149.228777)
		(end 152.875501 149.302)
		(width 0.148)
		(layer "In9.Cu")
		(net 193)
	)
	(arc
		(start 152.297815 153.802)
		(mid 152.121038 153.875223)
		(end 152.047815 154.052)
		(width 0.148)
		(layer "In9.Cu")
		(net 193)
	)
	(arc
		(start 152.953187 149.302)
		(mid 153.129964 149.375223)
		(end 153.203187 149.552)
		(width 0.148)
		(layer "In9.Cu")
		(net 193)
	)
	(arc
		(start 152.953187 157.302)
		(mid 153.129964 157.375223)
		(end 153.203187 157.552)
		(width 0.148)
		(layer "In9.Cu")
		(net 193)
	)
	(arc
		(start 152.953187 156.302)
		(mid 153.129964 156.375223)
		(end 153.203187 156.552)
		(width 0.148)
		(layer "In9.Cu")
		(net 193)
	)
	(arc
		(start 153.203187 155.552)
		(mid 153.129964 155.728777)
		(end 152.953187 155.802)
		(width 0.148)
		(layer "In9.Cu")
		(net 193)
	)
	(arc
		(start 153.203187 153.552)
		(mid 153.129964 153.728777)
		(end 152.953187 153.802)
		(width 0.148)
		(layer "In9.Cu")
		(net 193)
	)
	(arc
		(start 152.047815 152.052)
		(mid 152.121038 152.228777)
		(end 152.297815 152.302)
		(width 0.148)
		(layer "In9.Cu")
		(net 193)
	)
	(arc
		(start 152.875501 157.802)
		(mid 152.698724 157.875223)
		(end 152.625501 158.052)
		(width 0.148)
		(layer "In9.Cu")
		(net 193)
	)
	(arc
		(start 152.297815 156.802)
		(mid 152.121038 156.875223)
		(end 152.047815 157.052)
		(width 0.148)
		(layer "In9.Cu")
		(net 193)
	)
	(arc
		(start 153.203187 152.552)
		(mid 153.129964 152.728777)
		(end 152.953187 152.802)
		(width 0.148)
		(layer "In9.Cu")
		(net 193)
	)
	(arc
		(start 152.953187 153.302)
		(mid 153.129964 153.375223)
		(end 153.203187 153.552)
		(width 0.148)
		(layer "In9.Cu")
		(net 193)
	)
	(segment
		(start 151.649999 138.8025)
		(end 151.65 137.7275)
		(width 0.201)
		(layer "F.Cu")
		(net 194)
	)
	(segment
		(start 149.375501 167.302)
		(end 149.875001 166.8025)
		(width 0.256)
		(layer "F.Cu")
		(net 194)
	)
	(via
		(at 149.875001 166.8025)
		(size 0.45)
		(drill 0.1)
		(layers "F.Cu" "B.Cu")
		(net 194)
	)
	(via
		(at 151.65 137.7275)
		(size 0.45)
		(drill 0.1)
		(layers "F.Cu" "B.Cu")
		(net 194)
	)
	(segment
		(start 154.875501 163.524499)
		(end 152.1 166.3)
		(width 0.148)
		(layer "In9.Cu")
		(net 194)
	)
	(segment
		(start 152.672542 142.022725)
		(end 153.147224 141.54804)
		(width 0.148)
		(layer "In9.Cu")
		(net 194)
	)
	(segment
		(start 154.375501 145.734636)
		(end 154.875501 146.234636)
		(width 0.148)
		(layer "In9.Cu")
		(net 194)
	)
	(segment
		(start 154.207886 142.608702)
		(end 154.207886 142.608701)
		(width 0.148)
		(layer "In9.Cu")
		(net 194)
	)
	(segment
		(start 151.65 140.525499)
		(end 152.026001 140.9015)
		(width 0.148)
		(layer "In9.Cu")
		(net 194)
	)
	(segment
		(start 151.65 137.7275)
		(end 151.65 140.525499)
		(width 0.148)
		(layer "In9.Cu")
		(net 194)
	)
	(segment
		(start 153.026095 142.729831)
		(end 153.026096 142.729832)
		(width 0.148)
		(layer "In9.Cu")
		(net 194)
	)
	(segment
		(start 154.375501 143.251)
		(end 154.375501 145.734636)
		(width 0.148)
		(layer "In9.Cu")
		(net 194)
	)
	(segment
		(start 152.379554 140.901499)
		(end 152.379555 140.901501)
		(width 0.148)
		(layer "In9.Cu")
		(net 194)
	)
	(segment
		(start 152.672542 142.022724)
		(end 152.672542 142.022725)
		(width 0.148)
		(layer "In9.Cu")
		(net 194)
	)
	(segment
		(start 150.377501 166.3)
		(end 149.875001 166.8025)
		(width 0.148)
		(layer "In9.Cu")
		(net 194)
	)
	(segment
		(start 153.500779 141.548041)
		(end 153.50078 141.548042)
		(width 0.148)
		(layer "In9.Cu")
		(net 194)
	)
	(segment
		(start 153.500779 141.901595)
		(end 153.500779 141.901594)
		(width 0.148)
		(layer "In9.Cu")
		(net 194)
	)
	(segment
		(start 153.379649 142.729831)
		(end 153.379649 142.729832)
		(width 0.148)
		(layer "In9.Cu")
		(net 194)
	)
	(segment
		(start 152.379555 140.901501)
		(end 152.440119 140.840934)
		(width 0.148)
		(layer "In9.Cu")
		(net 194)
	)
	(segment
		(start 152.793672 141.194487)
		(end 152.318989 141.669171)
		(width 0.148)
		(layer "In9.Cu")
		(net 194)
	)
	(segment
		(start 152.1 166.3)
		(end 150.377501 166.3)
		(width 0.148)
		(layer "In9.Cu")
		(net 194)
	)
	(segment
		(start 153.500779 141.901594)
		(end 153.026096 142.376278)
		(width 0.148)
		(layer "In9.Cu")
		(net 194)
	)
	(segment
		(start 152.318988 142.022724)
		(end 152.318989 142.022725)
		(width 0.148)
		(layer "In9.Cu")
		(net 194)
	)
	(segment
		(start 152.793672 141.194488)
		(end 152.793672 141.194487)
		(width 0.148)
		(layer "In9.Cu")
		(net 194)
	)
	(segment
		(start 154.875501 146.234636)
		(end 154.875501 163.524499)
		(width 0.148)
		(layer "In9.Cu")
		(net 194)
	)
	(segment
		(start 154.207886 142.608701)
		(end 154.147321 142.669267)
		(width 0.148)
		(layer "In9.Cu")
		(net 194)
	)
	(segment
		(start 154.147322 143.02282)
		(end 154.14732 143.022819)
		(width 0.148)
		(layer "In9.Cu")
		(net 194)
	)
	(segment
		(start 154.14732 143.022819)
		(end 154.375501 143.251)
		(width 0.148)
		(layer "In9.Cu")
		(net 194)
	)
	(segment
		(start 152.793672 140.840935)
		(end 152.793673 140.840935)
		(width 0.148)
		(layer "In9.Cu")
		(net 194)
	)
	(segment
		(start 154.207886 142.255148)
		(end 154.207887 142.255149)
		(width 0.148)
		(layer "In9.Cu")
		(net 194)
	)
	(segment
		(start 153.379649 142.729832)
		(end 153.854331 142.255147)
		(width 0.148)
		(layer "In9.Cu")
		(net 194)
	)
	(arc
		(start 153.50078 141.548042)
		(mid 153.574003 141.724819)
		(end 153.500779 141.901595)
		(width 0.148)
		(layer "In9.Cu")
		(net 194)
	)
	(arc
		(start 153.147224 141.54804)
		(mid 153.324002 141.474818)
		(end 153.500779 141.548041)
		(width 0.148)
		(layer "In9.Cu")
		(net 194)
	)
	(arc
		(start 154.147321 142.669267)
		(mid 154.074098 142.846044)
		(end 154.147322 143.02282)
		(width 0.148)
		(layer "In9.Cu")
		(net 194)
	)
	(arc
		(start 152.318989 142.022725)
		(mid 152.495766 142.095948)
		(end 152.672542 142.022724)
		(width 0.148)
		(layer "In9.Cu")
		(net 194)
	)
	(arc
		(start 153.026096 142.376278)
		(mid 152.952872 142.553054)
		(end 153.026095 142.729831)
		(width 0.148)
		(layer "In9.Cu")
		(net 194)
	)
	(arc
		(start 153.026096 142.729832)
		(mid 153.202873 142.803055)
		(end 153.379649 142.729831)
		(width 0.148)
		(layer "In9.Cu")
		(net 194)
	)
	(arc
		(start 153.854331 142.255147)
		(mid 154.031109 142.181925)
		(end 154.207886 142.255148)
		(width 0.148)
		(layer "In9.Cu")
		(net 194)
	)
	(arc
		(start 152.793673 140.840935)
		(mid 152.866896 141.017712)
		(end 152.793672 141.194488)
		(width 0.148)
		(layer "In9.Cu")
		(net 194)
	)
	(arc
		(start 152.440119 140.840934)
		(mid 152.616896 140.767711)
		(end 152.793672 140.840935)
		(width 0.148)
		(layer "In9.Cu")
		(net 194)
	)
	(arc
		(start 152.026001 140.9015)
		(mid 152.202778 140.974723)
		(end 152.379554 140.901499)
		(width 0.148)
		(layer "In9.Cu")
		(net 194)
	)
	(arc
		(start 154.207887 142.255149)
		(mid 154.28111 142.431926)
		(end 154.207886 142.608702)
		(width 0.148)
		(layer "In9.Cu")
		(net 194)
	)
	(arc
		(start 152.318989 141.669171)
		(mid 152.245765 141.845947)
		(end 152.318988 142.022724)
		(width 0.148)
		(layer "In9.Cu")
		(net 194)
	)
	(segment
		(start 152.400001 146.2025)
		(end 152.400001 147.2775)
		(width 0.201)
		(layer "F.Cu")
		(net 195)
	)
	(segment
		(start 147.375501 163.302)
		(end 147.875001 162.8025)
		(width 0.256)
		(layer "F.Cu")
		(net 195)
	)
	(via
		(at 152.400001 147.2775)
		(size 0.45)
		(drill 0.1)
		(layers "F.Cu" "B.Cu")
		(net 195)
	)
	(via
		(at 147.875001 162.8025)
		(size 0.45)
		(drill 0.1)
		(layers "F.Cu" "B.Cu")
		(net 195)
	)
	(segment
		(start 147.421501 163.256)
		(end 147.875001 162.8025)
		(width 0.148)
		(layer "In6.Cu")
		(net 195)
	)
	(segment
		(start 148.375001 158.521446)
		(end 148.375 158.521448)
		(width 0.148)
		(layer "In6.Cu")
		(net 195)
	)
	(segment
		(start 152.400501 147.278)
		(end 152.400501 148.5)
		(width 0.148)
		(layer "In6.Cu")
		(net 195)
	)
	(segment
		(start 149.68315 156.647612)
		(end 149.683149 156.647613)
		(width 0.148)
		(layer "In6.Cu")
		(net 195)
	)
	(segment
		(start 151.309496 156.506188)
		(end 150.743812 155.940504)
		(width 0.148)
		(layer "In6.Cu")
		(net 195)
	)
	(segment
		(start 149.89528 157.920404)
		(end 149.329596 157.35472)
		(width 0.148)
		(layer "In6.Cu")
		(net 195)
	)
	(segment
		(start 152.25 151.306499)
		(end 152.25 155)
		(width 0.148)
		(layer "In6.Cu")
		(net 195)
	)
	(segment
		(start 148.375 158.875)
		(end 148.25 159)
		(width 0.148)
		(layer "In6.Cu")
		(net 195)
	)
	(segment
		(start 145.764229 163.256)
		(end 147.421501 163.256)
		(width 0.148)
		(layer "In6.Cu")
		(net 195)
	)
	(segment
		(start 151.556987 155.339463)
		(end 151.45092 155.233396)
		(width 0.148)
		(layer "In6.Cu")
		(net 195)
	)
	(segment
		(start 151.097366 155.233396)
		(end 151.097365 155.233397)
		(width 0.148)
		(layer "In6.Cu")
		(net 195)
	)
	(segment
		(start 150.390258 156.294058)
		(end 150.955942 156.859742)
		(width 0.148)
		(layer "In6.Cu")
		(net 195)
	)
	(segment
		(start 148.268934 158.061828)
		(end 148.268936 158.061827)
		(width 0.148)
		(layer "In6.Cu")
		(net 195)
	)
	(segment
		(start 151.66305 156.506188)
		(end 151.663049 156.506189)
		(width 0.148)
		(layer "In6.Cu")
		(net 195)
	)
	(segment
		(start 150.390258 155.940504)
		(end 150.390257 155.940505)
		(width 0.148)
		(layer "In6.Cu")
		(net 195)
	)
	(segment
		(start 150.248834 157.920404)
		(end 150.248833 157.920405)
		(width 0.148)
		(layer "In6.Cu")
		(net 195)
	)
	(segment
		(start 151.782834 149.556499)
		(end 152.717166 149.556499)
		(width 0.148)
		(layer "In6.Cu")
		(net 195)
	)
	(segment
		(start 145.422001 161.277999)
		(end 145.422001 162.913772)
		(width 0.148)
		(layer "In6.Cu")
		(net 195)
	)
	(segment
		(start 152.25 148.650501)
		(end 152.25 148.806499)
		(width 0.148)
		(layer "In6.Cu")
		(net 195)
	)
	(segment
		(start 152.717166 151.056499)
		(end 152.5 151.056499)
		(width 0.148)
		(layer "In6.Cu")
		(net 195)
	)
	(segment
		(start 152.25 155)
		(end 151.91054 155.339462)
		(width 0.148)
		(layer "In6.Cu")
		(net 195)
	)
	(segment
		(start 149.68315 157.001166)
		(end 150.248834 157.56685)
		(width 0.148)
		(layer "In6.Cu")
		(net 195)
	)
	(segment
		(start 152.400001 147.2775)
		(end 152.400501 147.278)
		(width 0.148)
		(layer "In6.Cu")
		(net 195)
	)
	(segment
		(start 150.955942 157.213296)
		(end 150.955941 157.213297)
		(width 0.148)
		(layer "In6.Cu")
		(net 195)
	)
	(segment
		(start 148.976042 157.708274)
		(end 149.541726 158.273958)
		(width 0.148)
		(layer "In6.Cu")
		(net 195)
	)
	(segment
		(start 148.25 159)
		(end 147.7 159)
		(width 0.148)
		(layer "In6.Cu")
		(net 195)
	)
	(segment
		(start 151.097366 155.58695)
		(end 151.66305 156.152634)
		(width 0.148)
		(layer "In6.Cu")
		(net 195)
	)
	(segment
		(start 148.976042 157.35472)
		(end 148.976041 157.354721)
		(width 0.148)
		(layer "In6.Cu")
		(net 195)
	)
	(segment
		(start 150.602388 157.213296)
		(end 150.036704 156.647612)
		(width 0.148)
		(layer "In6.Cu")
		(net 195)
	)
	(segment
		(start 147.7 159)
		(end 145.422001 161.277999)
		(width 0.148)
		(layer "In6.Cu")
		(net 195)
	)
	(segment
		(start 148.268935 158.41538)
		(end 148.375001 158.521446)
		(width 0.148)
		(layer "In6.Cu")
		(net 195)
	)
	(segment
		(start 151.782834 150.556499)
		(end 152.717166 150.556499)
		(width 0.148)
		(layer "In6.Cu")
		(net 195)
	)
	(segment
		(start 145.422001 162.913772)
		(end 145.764229 163.256)
		(width 0.148)
		(layer "In6.Cu")
		(net 195)
	)
	(segment
		(start 149.188172 158.627512)
		(end 148.622488 158.061828)
		(width 0.148)
		(layer "In6.Cu")
		(net 195)
	)
	(segment
		(start 149.541726 158.627512)
		(end 149.541725 158.627513)
		(width 0.148)
		(layer "In6.Cu")
		(net 195)
	)
	(segment
		(start 152 149.056499)
		(end 151.782834 149.056499)
		(width 0.148)
		(layer "In6.Cu")
		(net 195)
	)
	(segment
		(start 152.400501 148.5)
		(end 152.25 148.650501)
		(width 0.148)
		(layer "In6.Cu")
		(net 195)
	)
	(segment
		(start 151.782834 150.056499)
		(end 152.717166 150.056499)
		(width 0.148)
		(layer "In6.Cu")
		(net 195)
	)
	(arc
		(start 150.248833 157.920405)
		(mid 150.072056 157.993628)
		(end 149.89528 157.920404)
		(width 0.148)
		(layer "In6.Cu")
		(net 195)
	)
	(arc
		(start 151.782834 150.056499)
		(mid 151.606057 150.129722)
		(end 151.532834 150.306499)
		(width 0.148)
		(layer "In6.Cu")
		(net 195)
	)
	(arc
		(start 149.541726 158.273958)
		(mid 149.614949 158.450735)
		(end 149.541726 158.627512)
		(width 0.148)
		(layer "In6.Cu")
		(net 195)
	)
	(arc
		(start 150.743812 155.940504)
		(mid 150.567035 155.867281)
		(end 150.390258 155.940504)
		(width 0.148)
		(layer "In6.Cu")
		(net 195)
	)
	(arc
		(start 148.375 158.521448)
		(mid 148.448224 158.698223)
		(end 148.375 158.875)
		(width 0.148)
		(layer "In6.Cu")
		(net 195)
	)
	(arc
		(start 148.268936 158.061827)
		(mid 148.195712 158.238603)
		(end 148.268935 158.41538)
		(width 0.148)
		(layer "In6.Cu")
		(net 195)
	)
	(arc
		(start 151.663049 156.506189)
		(mid 151.486272 156.579412)
		(end 151.309496 156.506188)
		(width 0.148)
		(layer "In6.Cu")
		(net 195)
	)
	(arc
		(start 150.955941 157.213297)
		(mid 150.779164 157.28652)
		(end 150.602388 157.213296)
		(width 0.148)
		(layer "In6.Cu")
		(net 195)
	)
	(arc
		(start 151.532834 149.306499)
		(mid 151.606057 149.483276)
		(end 151.782834 149.556499)
		(width 0.148)
		(layer "In6.Cu")
		(net 195)
	)
	(arc
		(start 149.541725 158.627513)
		(mid 149.364948 158.700736)
		(end 149.188172 158.627512)
		(width 0.148)
		(layer "In6.Cu")
		(net 195)
	)
	(arc
		(start 150.248834 157.56685)
		(mid 150.322057 157.743627)
		(end 150.248834 157.920404)
		(width 0.148)
		(layer "In6.Cu")
		(net 195)
	)
	(arc
		(start 149.329596 157.35472)
		(mid 149.152819 157.281497)
		(end 148.976042 157.35472)
		(width 0.148)
		(layer "In6.Cu")
		(net 195)
	)
	(arc
		(start 148.622488 158.061828)
		(mid 148.445711 157.988605)
		(end 148.268934 158.061828)
		(width 0.148)
		(layer "In6.Cu")
		(net 195)
	)
	(arc
		(start 152.967166 149.806499)
		(mid 152.893943 149.983276)
		(end 152.717166 150.056499)
		(width 0.148)
		(layer "In6.Cu")
		(net 195)
	)
	(arc
		(start 148.976041 157.354721)
		(mid 148.902818 157.531498)
		(end 148.976042 157.708274)
		(width 0.148)
		(layer "In6.Cu")
		(net 195)
	)
	(arc
		(start 151.097365 155.233397)
		(mid 151.024142 155.410174)
		(end 151.097366 155.58695)
		(width 0.148)
		(layer "In6.Cu")
		(net 195)
	)
	(arc
		(start 151.91054 155.339462)
		(mid 151.733764 155.412686)
		(end 151.556987 155.339463)
		(width 0.148)
		(layer "In6.Cu")
		(net 195)
	)
	(arc
		(start 150.036704 156.647612)
		(mid 149.859927 156.574389)
		(end 149.68315 156.647612)
		(width 0.148)
		(layer "In6.Cu")
		(net 195)
	)
	(arc
		(start 151.532834 150.306499)
		(mid 151.606057 150.483276)
		(end 151.782834 150.556499)
		(width 0.148)
		(layer "In6.Cu")
		(net 195)
	)
	(arc
		(start 152.717166 149.556499)
		(mid 152.893943 149.629722)
		(end 152.967166 149.806499)
		(width 0.148)
		(layer "In6.Cu")
		(net 195)
	)
	(arc
		(start 150.390257 155.940505)
		(mid 150.317034 156.117282)
		(end 150.390258 156.294058)
		(width 0.148)
		(layer "In6.Cu")
		(net 195)
	)
	(arc
		(start 149.683149 156.647613)
		(mid 149.609926 156.82439)
		(end 149.68315 157.001166)
		(width 0.148)
		(layer "In6.Cu")
		(net 195)
	)
	(arc
		(start 151.45092 155.233396)
		(mid 151.274143 155.160173)
		(end 151.097366 155.233396)
		(width 0.148)
		(layer "In6.Cu")
		(net 195)
	)
	(arc
		(start 152.25 148.806499)
		(mid 152.176777 148.983276)
		(end 152 149.056499)
		(width 0.148)
		(layer "In6.Cu")
		(net 195)
	)
	(arc
		(start 151.782834 149.056499)
		(mid 151.606057 149.129722)
		(end 151.532834 149.306499)
		(width 0.148)
		(layer "In6.Cu")
		(net 195)
	)
	(arc
		(start 152.717166 150.556499)
		(mid 152.893943 150.629722)
		(end 152.967166 150.806499)
		(width 0.148)
		(layer "In6.Cu")
		(net 195)
	)
	(arc
		(start 151.66305 156.152634)
		(mid 151.736273 156.329411)
		(end 151.66305 156.506188)
		(width 0.148)
		(layer "In6.Cu")
		(net 195)
	)
	(arc
		(start 152.5 151.056499)
		(mid 152.323223 151.129722)
		(end 152.25 151.306499)
		(width 0.148)
		(layer "In6.Cu")
		(net 195)
	)
	(arc
		(start 150.955942 156.859742)
		(mid 151.029165 157.036519)
		(end 150.955942 157.213296)
		(width 0.148)
		(layer "In6.Cu")
		(net 195)
	)
	(arc
		(start 152.967166 150.806499)
		(mid 152.893943 150.983276)
		(end 152.717166 151.056499)
		(width 0.148)
		(layer "In6.Cu")
		(net 195)
	)
	(segment
		(start 148.375501 164.302)
		(end 148.875001 163.8025)
		(width 0.256)
		(layer "F.Cu")
		(net 196)
	)
	(segment
		(start 152.65 138.8025)
		(end 152.65 137.727499)
		(width 0.201)
		(layer "F.Cu")
		(net 196)
	)
	(via
		(at 152.65 137.727499)
		(size 0.45)
		(drill 0.1)
		(layers "F.Cu" "B.Cu")
		(net 196)
	)
	(via
		(at 148.875001 163.8025)
		(size 0.45)
		(drill 0.1)
		(layers "F.Cu" "B.Cu")
		(net 196)
	)
	(segment
		(start 148.371501 164.306)
		(end 148.875001 163.8025)
		(width 0.148)
		(layer "In6.Cu")
		(net 196)
	)
	(segment
		(start 151.920501 147.579499)
		(end 151.25 148.25)
		(width 0.148)
		(layer "In6.Cu")
		(net 196)
	)
	(segment
		(start 144.370501 161.417749)
		(end 144.370501 163.070501)
		(width 0.148)
		(layer "In6.Cu")
		(net 196)
	)
	(segment
		(start 152.410501 141.160501)
		(end 152.410501 145.746)
		(width 0.148)
		(layer "In6.Cu")
		(net 196)
	)
	(segment
		(start 152.410501 145.746)
		(end 151.920501 146.236)
		(width 0.148)
		(layer "In6.Cu")
		(net 196)
	)
	(segment
		(start 145.359005 163.509005)
		(end 145.359005 163.959005)
		(width 0.148)
		(layer "In6.Cu")
		(net 196)
	)
	(segment
		(start 151.920501 146.236)
		(end 151.920501 147.579499)
		(width 0.148)
		(layer "In6.Cu")
		(net 196)
	)
	(segment
		(start 151.25 154.53825)
		(end 144.370501 161.417749)
		(width 0.148)
		(layer "In6.Cu")
		(net 196)
	)
	(segment
		(start 145.359005 163.959005)
		(end 145.706 164.306)
		(width 0.148)
		(layer "In6.Cu")
		(net 196)
	)
	(segment
		(start 144.370501 163.070501)
		(end 144.596 163.296)
		(width 0.148)
		(layer "In6.Cu")
		(net 196)
	)
	(segment
		(start 151.603501 138.773998)
		(end 151.603501 140.353501)
		(width 0.148)
		(layer "In6.Cu")
		(net 196)
	)
	(segment
		(start 145.706 164.306)
		(end 148.371501 164.306)
		(width 0.148)
		(layer "In6.Cu")
		(net 196)
	)
	(segment
		(start 152.65 137.727499)
		(end 151.603501 138.773998)
		(width 0.148)
		(layer "In6.Cu")
		(net 196)
	)
	(segment
		(start 144.596 163.296)
		(end 145.146 163.296)
		(width 0.148)
		(layer "In6.Cu")
		(net 196)
	)
	(segment
		(start 145.146 163.296)
		(end 145.359005 163.509005)
		(width 0.148)
		(layer "In6.Cu")
		(net 196)
	)
	(segment
		(start 151.25 148.25)
		(end 151.25 154.53825)
		(width 0.148)
		(layer "In6.Cu")
		(net 196)
	)
	(segment
		(start 151.603501 140.353501)
		(end 152.410501 141.160501)
		(width 0.148)
		(layer "In6.Cu")
		(net 196)
	)
	(segment
		(start 153.400001 146.2025)
		(end 153.400001 147.277498)
		(width 0.201)
		(layer "F.Cu")
		(net 197)
	)
	(segment
		(start 149.375501 162.302)
		(end 149.875001 161.8025)
		(width 0.256)
		(layer "F.Cu")
		(net 197)
	)
	(via
		(at 153.400001 147.277498)
		(size 0.45)
		(drill 0.1)
		(layers "F.Cu" "B.Cu")
		(net 197)
	)
	(via
		(at 149.875001 161.8025)
		(size 0.45)
		(drill 0.1)
		(layers "F.Cu" "B.Cu")
		(net 197)
	)
	(segment
		(start 153.396867 156.179337)
		(end 153.431989 156.214459)
		(width 0.148)
		(layer "In6.Cu")
		(net 197)
	)
	(segment
		(start 154.5 151.53)
		(end 154.6 151.53)
		(width 0.148)
		(layer "In6.Cu")
		(net 197)
	)
	(segment
		(start 153.785542 156.21446)
		(end 153.785543 156.214459)
		(width 0.148)
		(layer "In6.Cu")
		(net 197)
	)
	(segment
		(start 154.25 149.5)
		(end 153.400001 148.650001)
		(width 0.148)
		(layer "In6.Cu")
		(net 197)
	)
	(segment
		(start 153.043313 156.532891)
		(end 153.467109 156.956687)
		(width 0.148)
		(layer "In6.Cu")
		(net 197)
	)
	(segment
		(start 149.875001 161.8025)
		(end 149.371501 162.306)
		(width 0.148)
		(layer "In6.Cu")
		(net 197)
	)
	(segment
		(start 147.570501 162.306)
		(end 147.380501 162.116)
		(width 0.148)
		(layer "In6.Cu")
		(net 197)
	)
	(segment
		(start 150.25 159.396448)
		(end 150.250001 159.396446)
		(width 0.148)
		(layer "In6.Cu")
		(net 197)
	)
	(segment
		(start 153.400001 148.650001)
		(end 153.400001 147.277498)
		(width 0.148)
		(layer "In6.Cu")
		(net 197)
	)
	(segment
		(start 148.38875 160)
		(end 150 160)
		(width 0.148)
		(layer "In6.Cu")
		(net 197)
	)
	(segment
		(start 152.336204 157.24)
		(end 152.76 157.663796)
		(width 0.148)
		(layer "In6.Cu")
		(net 197)
	)
	(segment
		(start 154.25 155.75)
		(end 154.25 151.78)
		(width 0.148)
		(layer "In6.Cu")
		(net 197)
	)
	(segment
		(start 153.785543 156.214459)
		(end 154.25 155.75)
		(width 0.148)
		(layer "In6.Cu")
		(net 197)
	)
	(segment
		(start 151.982649 157.593555)
		(end 152.406446 158.01735)
		(width 0.148)
		(layer "In6.Cu")
		(net 197)
	)
	(segment
		(start 150.78033 159.21967)
		(end 150.992228 159.431568)
		(width 0.148)
		(layer "In6.Cu")
		(net 197)
	)
	(segment
		(start 150.921986 158.654218)
		(end 151.345782 159.078014)
		(width 0.148)
		(layer "In6.Cu")
		(net 197)
	)
	(segment
		(start 147.380501 162.116)
		(end 147.380501 161.008249)
		(width 0.148)
		(layer "In6.Cu")
		(net 197)
	)
	(segment
		(start 150.250001 159.396446)
		(end 150.21488 159.361325)
		(width 0.148)
		(layer "In6.Cu")
		(net 197)
	)
	(segment
		(start 149.371501 162.306)
		(end 147.570501 162.306)
		(width 0.148)
		(layer "In6.Cu")
		(net 197)
	)
	(segment
		(start 150.214879 159.007772)
		(end 150.21488 159.007771)
		(width 0.148)
		(layer "In6.Cu")
		(net 197)
	)
	(segment
		(start 150.568434 159.007771)
		(end 150.603556 159.042893)
		(width 0.148)
		(layer "In6.Cu")
		(net 197)
	)
	(segment
		(start 153.9 150.53)
		(end 154.6 150.53)
		(width 0.148)
		(layer "In6.Cu")
		(net 197)
	)
	(segment
		(start 150 160)
		(end 150.25 159.75)
		(width 0.148)
		(layer "In6.Cu")
		(net 197)
	)
	(segment
		(start 154.6 150.03)
		(end 154.5 150.03)
		(width 0.148)
		(layer "In6.Cu")
		(net 197)
	)
	(segment
		(start 154.25 149.78)
		(end 154.25 149.5)
		(width 0.148)
		(layer "In6.Cu")
		(net 197)
	)
	(segment
		(start 154.6 151.03)
		(end 153.9 151.03)
		(width 0.148)
		(layer "In6.Cu")
		(net 197)
	)
	(segment
		(start 151.27554 158.300664)
		(end 151.699337 158.724459)
		(width 0.148)
		(layer "In6.Cu")
		(net 197)
	)
	(segment
		(start 147.380501 161.008249)
		(end 148.38875 160)
		(width 0.148)
		(layer "In6.Cu")
		(net 197)
	)
	(segment
		(start 152.689758 156.886446)
		(end 153.113555 157.310241)
		(width 0.148)
		(layer "In6.Cu")
		(net 197)
	)
	(segment
		(start 151.629095 157.947109)
		(end 152.052891 158.370905)
		(width 0.148)
		(layer "In6.Cu")
		(net 197)
	)
	(segment
		(start 150.780333 159.21967)
		(end 150.78033 159.21967)
		(width 0.148)
		(layer "In6.Cu")
		(net 197)
	)
	(segment
		(start 150.603556 159.042893)
		(end 150.780333 159.21967)
		(width 0.148)
		(layer "In6.Cu")
		(net 197)
	)
	(arc
		(start 151.629095 157.947109)
		(mid 151.555872 157.770332)
		(end 151.629095 157.593555)
		(width 0.148)
		(layer "In6.Cu")
		(net 197)
	)
	(arc
		(start 153.113555 157.310241)
		(mid 153.290332 157.383464)
		(end 153.467109 157.310241)
		(width 0.148)
		(layer "In6.Cu")
		(net 197)
	)
	(arc
		(start 152.406446 158.01735)
		(mid 152.583223 158.090573)
		(end 152.76 158.01735)
		(width 0.148)
		(layer "In6.Cu")
		(net 197)
	)
	(arc
		(start 151.345782 159.431568)
		(mid 151.419005 159.254791)
		(end 151.345782 159.078014)
		(width 0.148)
		(layer "In6.Cu")
		(net 197)
	)
	(arc
		(start 154.6 151.53)
		(mid 154.776777 151.456777)
		(end 154.85 151.28)
		(width 0.148)
		(layer "In6.Cu")
		(net 197)
	)
	(arc
		(start 150.25 159.75)
		(mid 150.323224 159.573223)
		(end 150.25 159.396448)
		(width 0.148)
		(layer "In6.Cu")
		(net 197)
	)
	(arc
		(start 152.336204 157.24)
		(mid 152.262981 157.063223)
		(end 152.336204 156.886446)
		(width 0.148)
		(layer "In6.Cu")
		(net 197)
	)
	(arc
		(start 154.85 151.28)
		(mid 154.776777 151.103223)
		(end 154.6 151.03)
		(width 0.148)
		(layer "In6.Cu")
		(net 197)
	)
	(arc
		(start 150.992228 159.431568)
		(mid 151.169005 159.504791)
		(end 151.345782 159.431568)
		(width 0.148)
		(layer "In6.Cu")
		(net 197)
	)
	(arc
		(start 150.21488 159.007771)
		(mid 150.391657 158.934548)
		(end 150.568434 159.007771)
		(width 0.148)
		(layer "In6.Cu")
		(net 197)
	)
	(arc
		(start 150.921986 158.654218)
		(mid 150.848763 158.477441)
		(end 150.921986 158.300664)
		(width 0.148)
		(layer "In6.Cu")
		(net 197)
	)
	(arc
		(start 153.9 151.03)
		(mid 153.723223 150.956777)
		(end 153.65 150.78)
		(width 0.148)
		(layer "In6.Cu")
		(net 197)
	)
	(arc
		(start 153.043313 156.532891)
		(mid 152.97009 156.356114)
		(end 153.043313 156.179337)
		(width 0.148)
		(layer "In6.Cu")
		(net 197)
	)
	(arc
		(start 153.467109 157.310241)
		(mid 153.540332 157.133464)
		(end 153.467109 156.956687)
		(width 0.148)
		(layer "In6.Cu")
		(net 197)
	)
	(arc
		(start 154.85 150.28)
		(mid 154.776777 150.103223)
		(end 154.6 150.03)
		(width 0.148)
		(layer "In6.Cu")
		(net 197)
	)
	(arc
		(start 151.629095 157.593555)
		(mid 151.805872 157.520332)
		(end 151.982649 157.593555)
		(width 0.148)
		(layer "In6.Cu")
		(net 197)
	)
	(arc
		(start 152.336204 156.886446)
		(mid 152.512981 156.813223)
		(end 152.689758 156.886446)
		(width 0.148)
		(layer "In6.Cu")
		(net 197)
	)
	(arc
		(start 152.052891 158.724459)
		(mid 152.126114 158.547682)
		(end 152.052891 158.370905)
		(width 0.148)
		(layer "In6.Cu")
		(net 197)
	)
	(arc
		(start 150.21488 159.361325)
		(mid 150.141656 159.184549)
		(end 150.214879 159.007772)
		(width 0.148)
		(layer "In6.Cu")
		(net 197)
	)
	(arc
		(start 154.5 150.03)
		(mid 154.323223 149.956777)
		(end 154.25 149.78)
		(width 0.148)
		(layer "In6.Cu")
		(net 197)
	)
	(arc
		(start 151.699337 158.724459)
		(mid 151.876114 158.797682)
		(end 152.052891 158.724459)
		(width 0.148)
		(layer "In6.Cu")
		(net 197)
	)
	(arc
		(start 150.921986 158.300664)
		(mid 151.098763 158.227441)
		(end 151.27554 158.300664)
		(width 0.148)
		(layer "In6.Cu")
		(net 197)
	)
	(arc
		(start 152.76 158.01735)
		(mid 152.833223 157.840573)
		(end 152.76 157.663796)
		(width 0.148)
		(layer "In6.Cu")
		(net 197)
	)
	(arc
		(start 153.043313 156.179337)
		(mid 153.22009 156.106114)
		(end 153.396867 156.179337)
		(width 0.148)
		(layer "In6.Cu")
		(net 197)
	)
	(arc
		(start 153.431989 156.214459)
		(mid 153.608765 156.287683)
		(end 153.785542 156.21446)
		(width 0.148)
		(layer "In6.Cu")
		(net 197)
	)
	(arc
		(start 154.6 150.53)
		(mid 154.776777 150.456777)
		(end 154.85 150.28)
		(width 0.148)
		(layer "In6.Cu")
		(net 197)
	)
	(arc
		(start 153.65 150.78)
		(mid 153.723223 150.603223)
		(end 153.9 150.53)
		(width 0.148)
		(layer "In6.Cu")
		(net 197)
	)
	(arc
		(start 154.25 151.78)
		(mid 154.323223 151.603223)
		(end 154.5 151.53)
		(width 0.148)
		(layer "In6.Cu")
		(net 197)
	)
	(segment
		(start 153.650001 138.8025)
		(end 153.650001 137.727499)
		(width 0.201)
		(layer "F.Cu")
		(net 198)
	)
	(segment
		(start 146.375501 163.302)
		(end 146.875 162.8025)
		(width 0.256)
		(layer "F.Cu")
		(net 198)
	)
	(via
		(at 153.650001 137.727499)
		(size 0.45)
		(drill 0.1)
		(layers "F.Cu" "B.Cu")
		(net 198)
	)
	(via
		(at 146.875 162.8025)
		(size 0.45)
		(drill 0.1)
		(layers "F.Cu" "B.Cu")
		(net 198)
	)
	(segment
		(start 152.900501 146.456)
		(end 152.900501 148.900501)
		(width 0.148)
		(layer "In6.Cu")
		(net 198)
	)
	(segment
		(start 153 152.06)
		(end 153.574599 152.06)
		(width 0.148)
		(layer "In6.Cu")
		(net 198)
	)
	(segment
		(start 153.420501 141.056)
		(end 153.420501 145.936)
		(width 0.148)
		(layer "In6.Cu")
		(net 198)
	)
	(segment
		(start 146.375001 162.302501)
		(end 146.875 162.8025)
		(width 0.148)
		(layer "In6.Cu")
		(net 198)
	)
	(segment
		(start 153.25 154.81)
		(end 153.25 155.5)
		(width 0.148)
		(layer "In6.Cu")
		(net 198)
	)
	(segment
		(start 153.420501 145.936)
		(end 152.900501 146.456)
		(width 0.148)
		(layer "In6.Cu")
		(net 198)
	)
	(segment
		(start 153.650001 137.727499)
		(end 153.649002 137.727499)
		(width 0.148)
		(layer "In6.Cu")
		(net 198)
	)
	(segment
		(start 152.900501 148.900501)
		(end 153.25 149.25)
		(width 0.148)
		(layer "In6.Cu")
		(net 198)
	)
	(segment
		(start 153.649002 137.727499)
		(end 152.700501 138.676)
		(width 0.148)
		(layer "In6.Cu")
		(net 198)
	)
	(segment
		(start 148 159.5)
		(end 146.375001 161.124999)
		(width 0.148)
		(layer "In6.Cu")
		(net 198)
	)
	(segment
		(start 152.700501 140.336)
		(end 153.420501 141.056)
		(width 0.148)
		(layer "In6.Cu")
		(net 198)
	)
	(segment
		(start 153.574599 154.56)
		(end 153.5 154.56)
		(width 0.148)
		(layer "In6.Cu")
		(net 198)
	)
	(segment
		(start 152.925401 152.56)
		(end 153.574599 152.56)
		(width 0.148)
		(layer "In6.Cu")
		(net 198)
	)
	(segment
		(start 146.375001 161.124999)
		(end 146.375001 162.302501)
		(width 0.148)
		(layer "In6.Cu")
		(net 198)
	)
	(segment
		(start 153.25 155.5)
		(end 149.25 159.5)
		(width 0.148)
		(layer "In6.Cu")
		(net 198)
	)
	(segment
		(start 149.25 159.5)
		(end 148 159.5)
		(width 0.148)
		(layer "In6.Cu")
		(net 198)
	)
	(segment
		(start 152.700501 138.676)
		(end 152.700501 140.336)
		(width 0.148)
		(layer "In6.Cu")
		(net 198)
	)
	(segment
		(start 152.925401 153.56)
		(end 153.574599 153.56)
		(width 0.148)
		(layer "In6.Cu")
		(net 198)
	)
	(segment
		(start 152.925401 152.06)
		(end 153 152.06)
		(width 0.148)
		(layer "In6.Cu")
		(net 198)
	)
	(segment
		(start 152.925401 153.06)
		(end 153.574599 153.06)
		(width 0.148)
		(layer "In6.Cu")
		(net 198)
	)
	(segment
		(start 152.925401 154.06)
		(end 153.574599 154.06)
		(width 0.148)
		(layer "In6.Cu")
		(net 198)
	)
	(segment
		(start 153 151.56)
		(end 152.925401 151.56)
		(width 0.148)
		(layer "In6.Cu")
		(net 198)
	)
	(segment
		(start 153.25 149.25)
		(end 153.25 151.31)
		(width 0.148)
		(layer "In6.Cu")
		(net 198)
	)
	(arc
		(start 152.925401 151.56)
		(mid 152.748624 151.633223)
		(end 152.675401 151.81)
		(width 0.148)
		(layer "In6.Cu")
		(net 198)
	)
	(arc
		(start 152.925401 152.56)
		(mid 152.748624 152.633223)
		(end 152.675401 152.81)
		(width 0.148)
		(layer "In6.Cu")
		(net 198)
	)
	(arc
		(start 153.574599 152.06)
		(mid 153.751376 152.133223)
		(end 153.824599 152.31)
		(width 0.148)
		(layer "In6.Cu")
		(net 198)
	)
	(arc
		(start 153.824599 152.31)
		(mid 153.751376 152.486777)
		(end 153.574599 152.56)
		(width 0.148)
		(layer "In6.Cu")
		(net 198)
	)
	(arc
		(start 153.574599 154.06)
		(mid 153.751376 154.133223)
		(end 153.824599 154.31)
		(width 0.148)
		(layer "In6.Cu")
		(net 198)
	)
	(arc
		(start 153.574599 153.06)
		(mid 153.751376 153.133223)
		(end 153.824599 153.31)
		(width 0.148)
		(layer "In6.Cu")
		(net 198)
	)
	(arc
		(start 152.675401 151.81)
		(mid 152.748624 151.986777)
		(end 152.925401 152.06)
		(width 0.148)
		(layer "In6.Cu")
		(net 198)
	)
	(arc
		(start 153.5 154.56)
		(mid 153.323223 154.633223)
		(end 153.25 154.81)
		(width 0.148)
		(layer "In6.Cu")
		(net 198)
	)
	(arc
		(start 153.824599 153.31)
		(mid 153.751376 153.486777)
		(end 153.574599 153.56)
		(width 0.148)
		(layer "In6.Cu")
		(net 198)
	)
	(arc
		(start 152.925401 153.56)
		(mid 152.748624 153.633223)
		(end 152.675401 153.81)
		(width 0.148)
		(layer "In6.Cu")
		(net 198)
	)
	(arc
		(start 152.675401 152.81)
		(mid 152.748624 152.986777)
		(end 152.925401 153.06)
		(width 0.148)
		(layer "In6.Cu")
		(net 198)
	)
	(arc
		(start 153.824599 154.31)
		(mid 153.751376 154.486777)
		(end 153.574599 154.56)
		(width 0.148)
		(layer "In6.Cu")
		(net 198)
	)
	(arc
		(start 153.25 151.31)
		(mid 153.176777 151.486777)
		(end 153 151.56)
		(width 0.148)
		(layer "In6.Cu")
		(net 198)
	)
	(arc
		(start 152.675401 153.81)
		(mid 152.748624 153.986777)
		(end 152.925401 154.06)
		(width 0.148)
		(layer "In6.Cu")
		(net 198)
	)
	(segment
		(start 90.911829 156.783157)
		(end 90.648978 157.046008)
		(width 0.15)
		(layer "F.Cu")
		(net 199)
	)
	(segment
		(start 90.648978 157.046008)
		(end 90.11468 157.046008)
		(width 0.15)
		(layer "F.Cu")
		(net 199)
	)
	(segment
		(start 100.406829 158.968859)
		(end 100.406829 157.968859)
		(width 0.2)
		(layer "F.Cu")
		(net 199)
	)
	(segment
		(start 98.53753 156.568858)
		(end 99.296829 157.328157)
		(width 0.2)
		(layer "F.Cu")
		(net 199)
	)
	(segment
		(start 99.937531 157.968859)
		(end 100.406829 157.968859)
		(width 0.2)
		(layer "F.Cu")
		(net 199)
	)
	(segment
		(start 96.991828 156.568858)
		(end 98.53753 156.568858)
		(width 0.2)
		(layer "F.Cu")
		(net 199)
	)
	(segment
		(start 90.11468 157.046008)
		(end 87.453978 157.046008)
		(width 0.15)
		(layer "F.Cu")
		(net 199)
	)
	(segment
		(start 93.300501 158.213149)
		(end 93.300501 159.113149)
		(width 0.256)
		(layer "F.Cu")
		(net 199)
	)
	(segment
		(start 99.296829 157.328157)
		(end 99.937531 157.968859)
		(width 0.2)
		(layer "F.Cu")
		(net 199)
	)
	(segment
		(start 90.911829 156.313157)
		(end 90.911829 156.783157)
		(width 0.15)
		(layer "F.Cu")
		(net 199)
	)
	(segment
		(start 166.040668 152.6)
		(end 177.8 164.359332)
		(width 2)
		(layer "F.Cu")
		(net 199)
	)
	(segment
		(start 177.8 164.359332)
		(end 177.8 170.8)
		(width 2)
		(layer "F.Cu")
		(net 199)
	)
	(segment
		(start 90.11468 152.546008)
		(end 89.531 152.546008)
		(width 0.2)
		(layer "F.Cu")
		(net 199)
	)
	(segment
		(start 110.8 152.6)
		(end 166.040668 152.6)
		(width 2)
		(layer "F.Cu")
		(net 199)
	)
	(segment
		(start 177.8 170.8)
		(end 181.1 174.1)
		(width 2)
		(layer "F.Cu")
		(net 199)
	)
	(segment
		(start 90.11468 154.546008)
		(end 90.654692 154.546008)
		(width 0.15)
		(layer "F.Cu")
		(net 199)
	)
	(segment
		(start 91.279001 159.2)
		(end 91.291829 159.187172)
		(width 0.15)
		(layer "F.Cu")
		(net 199)
	)
	(segment
		(start 88.581135 152.243165)
		(end 88.491829 152.153859)
		(width 0.2)
		(layer "F.Cu")
		(net 199)
	)
	(segment
		(start 181.1 174.1)
		(end 197.5385 174.1)
		(width 2)
		(layer "F.Cu")
		(net 199)
	)
	(segment
		(start 91.291829 159.187172)
		(end 91.291829 158.223157)
		(width 0.256)
		(layer "F.Cu")
		(net 199)
	)
	(segment
		(start 105.388501 156.223149)
		(end 107.176851 156.223149)
		(width 0.256)
		(layer "F.Cu")
		(net 199)
	)
	(segment
		(start 89.531 152.546008)
		(end 89.228157 152.243165)
		(width 0.2)
		(layer "F.Cu")
		(net 199)
	)
	(segment
		(start 197.5385 174.1)
		(end 197.6635 173.975)
		(width 1.7)
		(layer "F.Cu")
		(net 199)
	)
	(segment
		(start 88.491829 152.153859)
		(end 87.391829 152.153859)
		(width 0.2)
		(layer "F.Cu")
		(net 199)
	)
	(segment
		(start 107.176851 156.223149)
		(end 110.8 152.6)
		(width 2)
		(layer "F.Cu")
		(net 199)
	)
	(segment
		(start 90.654692 154.546008)
		(end 90.911829 154.803145)
		(width 0.15)
		(layer "F.Cu")
		(net 199)
	)
	(segment
		(start 89.228157 152.243165)
		(end 88.581135 152.243165)
		(width 0.2)
		(layer "F.Cu")
		(net 199)
	)
	(via
		(at 93.3 159.2)
		(size 0.45)
		(drill 0.1)
		(layers "F.Cu" "B.Cu")
		(net 199)
	)
	(via
		(at 91.279001 159.2)
		(size 0.45)
		(drill 0.1)
		(layers "F.Cu" "B.Cu")
		(net 199)
	)
	(via
		(at 89.228157 152.243165)
		(size 0.45)
		(drill 0.1)
		(layers "F.Cu" "B.Cu")
		(net 199)
	)
	(via
		(at 91.375322 152.846)
		(size 0.45)
		(drill 0.1)
		(layers "F.Cu" "B.Cu")
		(net 199)
	)
	(via
		(at 106.5 156.45)
		(size 0.45)
		(drill 0.1)
		(layers "F.Cu" "B.Cu")
		(net 199)
	)
	(via
		(at 90.911829 154.803145)
		(size 0.45)
		(drill 0.1)
		(layers "F.Cu" "B.Cu")
		(net 199)
	)
	(via
		(at 106.9 155.95)
		(size 0.45)
		(drill 0.1)
		(layers "F.Cu" "B.Cu")
		(net 199)
	)
	(via
		(at 91.527596 152.134441)
		(size 0.45)
		(drill 0.1)
		(layers "F.Cu" "B.Cu")
		(net 199)
	)
	(via
		(at 99.296829 157.328157)
		(size 0.45)
		(drill 0.1)
		(layers "F.Cu" "B.Cu")
		(net 199)
	)
	(via
		(at 90.911829 156.313157)
		(size 0.45)
		(drill 0.1)
		(layers "F.Cu" "B.Cu")
		(net 199)
	)
	(via
		(at 194.6 174.1)
		(size 0.45)
		(drill 0.1)
		(layers "F.Cu" "B.Cu")
		(net 199)
	)
	(segment
		(start 90.108672 158.488992)
		(end 91.15 158.488992)
		(width 0.4)
		(layer "B.Cu")
		(net 199)
	)
	(segment
		(start 91.3 159.179001)
		(end 91.279001 159.2)
		(width 0.256)
		(layer "B.Cu")
		(net 199)
	)
	(segment
		(start 93.308672 158.488992)
		(end 93.308672 159.191328)
		(width 0.256)
		(layer "B.Cu")
		(net 199)
	)
	(segment
		(start 91.527596 152.693726)
		(end 91.527596 152.134441)
		(width 0.4)
		(layer "B.Cu")
		(net 199)
	)
	(segment
		(start 92.308672 158.488992)
		(end 93.308672 158.488992)
		(width 0.4)
		(layer "B.Cu")
		(net 199)
	)
	(segment
		(start 93.308672 159.191328)
		(end 93.3 159.2)
		(width 0.256)
		(layer "B.Cu")
		(net 199)
	)
	(segment
		(start 194.6 174.1)
		(end 193.6 174.1)
		(width 0.15)
		(layer "B.Cu")
		(net 199)
	)
	(segment
		(start 91.653157 152.568165)
		(end 92.378157 152.568165)
		(width 0.4)
		(layer "B.Cu")
		(net 199)
	)
	(segment
		(start 91.375322 152.846)
		(end 91.527596 152.693726)
		(width 0.4)
		(layer "B.Cu")
		(net 199)
	)
	(segment
		(start 91.3 158.638992)
		(end 91.3 159.179001)
		(width 0.256)
		(layer "B.Cu")
		(net 199)
	)
	(segment
		(start 91.15 158.488992)
		(end 91.3 158.638992)
		(width 0.256)
		(layer "B.Cu")
		(net 199)
	)
	(segment
		(start 91.375322 152.846)
		(end 91.653157 152.568165)
		(width 0.4)
		(layer "B.Cu")
		(net 199)
	)
	(segment
		(start 88.500501 153.573851)
		(end 87.400501 153.573851)
		(width 0.2)
		(layer "F.Cu")
		(net 200)
	)
	(segment
		(start 134.130501 191.199501)
		(end 134.130501 193.225)
		(width 0.256)
		(layer "F.Cu")
		(net 200)
	)
	(segment
		(start 87.400501 153.573851)
		(end 86.561203 153.573851)
		(width 0.2)
		(layer "F.Cu")
		(net 200)
	)
	(segment
		(start 83.45 171.35)
		(end 82.054501 171.35)
		(width 0.256)
		(layer "F.Cu")
		(net 200)
	)
	(segment
		(start 100.262501 144.814)
		(end 100.260501 144.816)
		(width 0.4)
		(layer "F.Cu")
		(net 200)
	)
	(segment
		(start 179.649336 184.453959)
		(end 179.859377 184.664)
		(width 0.256)
		(layer "F.Cu")
		(net 200)
	)
	(segment
		(start 182.636107 181.1555)
		(end 182.635107 181.1545)
		(width 0.256)
		(layer "F.Cu")
		(net 200)
	)
	(segment
		(start 182.636108 163.651)
		(end 182.636109 163.013501)
		(width 0.256)
		(layer "F.Cu")
		(net 200)
	)
	(segment
		(start 94.450501 115.676)
		(end 94.450501 114.926)
		(width 0.15)
		(layer "F.Cu")
		(net 200)
	)
	(segment
		(start 105.59 170.970157)
		(end 105.68 170.880157)
		(width 0.15)
		(layer "F.Cu")
		(net 200)
	)
	(segment
		(start 96.55 182.284)
		(end 97.184 182.284)
		(width 0.15)
		(layer "F.Cu")
		(net 200)
	)
	(segment
		(start 185 182.63)
		(end 185 182.087)
		(width 0.4)
		(layer "F.Cu")
		(net 200)
	)
	(segment
		(start 133.73 190.799)
		(end 134.130501 191.199501)
		(width 0.256)
		(layer "F.Cu")
		(net 200)
	)
	(segment
		(start 90.28 181.23)
		(end 90.25 181.2)
		(width 0.15)
		(layer "F.Cu")
		(net 200)
	)
	(segment
		(start 97.83765 156.036)
		(end 96.97765 156.036)
		(width 0.2)
		(layer "F.Cu")
		(net 200)
	)
	(segment
		(start 183.191 150.825)
		(end 183.191 150.518)
		(width 0.256)
		(layer "F.Cu")
		(net 200)
	)
	(segment
		(start 131.376501 177.301)
		(end 130.877001 177.8005)
		(width 0.256)
		(layer "F.Cu")
		(net 200)
	)
	(segment
		(start 105.24 175.009)
		(end 105.431 175.009)
		(width 0.15)
		(layer "F.Cu")
		(net 200)
	)
	(segment
		(start 182.637107 181.816)
		(end 182.636107 181.815)
		(width 0.256)
		(layer "F.Cu")
		(net 200)
	)
	(segment
		(start 134.1 190.429)
		(end 133.73 190.799)
		(width 0.4)
		(layer "F.Cu")
		(net 200)
	)
	(segment
		(start 100.745501 146.556)
		(end 101.430501 146.556)
		(width 0.4)
		(layer "F.Cu")
		(net 200)
	)
	(segment
		(start 86.350501 115.676)
		(end 86.350501 114.926)
		(width 0.15)
		(layer "F.Cu")
		(net 200)
	)
	(segment
		(start 128.376501 168.302)
		(end 127.877001 167.8025)
		(width 0.256)
		(layer "F.Cu")
		(net 200)
	)
	(segment
		(start 129.376501 181.301)
		(end 128.877001 181.8005)
		(width 0.256)
		(layer "F.Cu")
		(net 200)
	)
	(segment
		(start 82.054501 171.35)
		(end 82.039501 171.365)
		(width 0.256)
		(layer "F.Cu")
		(net 200)
	)
	(segment
		(start 114.6505 183.835499)
		(end 113.665001 183.8355)
		(width 0.256)
		(layer "F.Cu")
		(net 200)
	)
	(segment
		(start 72.970501 125.576)
		(end 73.240501 125.306)
		(width 0.15)
		(layer "F.Cu")
		(net 200)
	)
	(segment
		(start 86.561203 153.573851)
		(end 86.500501 153.513149)
		(width 0.2)
		(layer "F.Cu")
		(net 200)
	)
	(segment
		(start 131.376501 167.302)
		(end 130.877001 166.8025)
		(width 0.256)
		(layer "F.Cu")
		(net 200)
	)
	(segment
		(start 182.636107 181.805)
		(end 182.636107 181.1555)
		(width 0.256)
		(layer "F.Cu")
		(net 200)
	)
	(segment
		(start 142.3755 180.301)
		(end 142.875001 180.8005)
		(width 0.256)
		(layer "F.Cu")
		(net 200)
	)
	(segment
		(start 179.085 179.115)
		(end 179.1 179.1)
		(width 0.182)
		(layer "F.Cu")
		(net 200)
	)
	(segment
		(start 91 181.23)
		(end 90.28 181.23)
		(width 0.15)
		(layer "F.Cu")
		(net 200)
	)
	(segment
		(start 95.291829 159.291829)
		(end 95.3 159.3)
		(width 0.15)
		(layer "F.Cu")
		(net 200)
	)
	(segment
		(start 77.849 125.549)
		(end 77.8 125.5)
		(width 0.15)
		(layer "F.Cu")
		(net 200)
	)
	(segment
		(start 75.510501 126.276)
		(end 75.510501 125.556)
		(width 0.15)
		(layer "F.Cu")
		(net 200)
	)
	(segment
		(start 183.191 150.518)
		(end 184.034 149.675)
		(width 0.256)
		(layer "F.Cu")
		(net 200)
	)
	(segment
		(start 105.67 174.77)
		(end 105.67 174.63)
		(width 0.15)
		(layer "F.Cu")
		(net 200)
	)
	(segment
		(start 130.376501 184.301)
		(end 129.877 184.8005)
		(width 0.256)
		(layer "F.Cu")
		(net 200)
	)
	(segment
		(start 185 182.087)
		(end 184.997 182.084)
		(width 0.4)
		(layer "F.Cu")
		(net 200)
	)
	(segment
		(start 113.665001 183.8355)
		(end 113.650501 183.85)
		(width 0.256)
		(layer "F.Cu")
		(net 200)
	)
	(segment
		(start 93.738501 126.236921)
		(end 93.003964 126.236921)
		(width 0.15)
		(layer "F.Cu")
		(net 200)
	)
	(segment
		(start 140.375501 184.301)
		(end 140.875001 184.8005)
		(width 0.256)
		(layer "F.Cu")
		(net 200)
	)
	(segment
		(start 178.385 179.115)
		(end 179.085 179.115)
		(width 0.182)
		(layer "F.Cu")
		(net 200)
	)
	(segment
		(start 127.3765 165.302)
		(end 126.877001 164.802501)
		(width 0.256)
		(layer "F.Cu")
		(net 200)
	)
	(segment
		(start 89.050501 115.676)
		(end 89.050501 114.926)
		(width 0.15)
		(layer "F.Cu")
		(net 200)
	)
	(segment
		(start 77.849 126.299)
		(end 77.849 125.549)
		(width 0.15)
		(layer "F.Cu")
		(net 200)
	)
	(segment
		(start 105.431 171.309)
		(end 105.59 171.15)
		(width 0.15)
		(layer "F.Cu")
		(net 200)
	)
	(segment
		(start 132.376501 170.302)
		(end 131.877 169.8025)
		(width 0.256)
		(layer "F.Cu")
		(net 200)
	)
	(segment
		(start 105.431 175.009)
		(end 105.67 174.77)
		(width 0.15)
		(layer "F.Cu")
		(net 200)
	)
	(segment
		(start 139.375501 181.301)
		(end 139.875001 181.800501)
		(width 0.256)
		(layer "F.Cu")
		(net 200)
	)
	(segment
		(start 182.637107 183.45)
		(end 182.637107 181.816)
		(width 0.256)
		(layer "F.Cu")
		(net 200)
	)
	(segment
		(start 180.429999 128.2)
		(end 179.694999 128.2)
		(width 0.256)
		(layer "F.Cu")
		(net 200)
	)
	(segment
		(start 105.59 171.15)
		(end 105.59 170.970157)
		(width 0.15)
		(layer "F.Cu")
		(net 200)
	)
	(segment
		(start 143.375501 183.301)
		(end 143.875001 183.8005)
		(width 0.256)
		(layer "F.Cu")
		(net 200)
	)
	(segment
		(start 73.240501 125.306)
		(end 74.360501 125.306)
		(width 0.15)
		(layer "F.Cu")
		(net 200)
	)
	(segment
		(start 182.636109 163.013501)
		(end 182.637608 163.012)
		(width 0.256)
		(layer "F.Cu")
		(net 200)
	)
	(segment
		(start 88.539352 153.536)
		(end 88.500501 153.574851)
		(width 0.256)
		(layer "F.Cu")
		(net 200)
	)
	(segment
		(start 184.034 149.675)
		(end 184.674999 149.675)
		(width 0.256)
		(layer "F.Cu")
		(net 200)
	)
	(segment
		(start 184.025 148.650001)
		(end 184.025 149.666)
		(width 0.256)
		(layer "F.Cu")
		(net 200)
	)
	(segment
		(start 168.67 180.4)
		(end 167.7 180.4)
		(width 0.4)
		(layer "F.Cu")
		(net 200)
	)
	(segment
		(start 97.875501 146.556)
		(end 97.350501 146.556)
		(width 0.4)
		(layer "F.Cu")
		(net 200)
	)
	(segment
		(start 185 163.884501)
		(end 184.9975 163.882001)
		(width 0.4)
		(layer "F.Cu")
		(net 200)
	)
	(segment
		(start 116.651501 175.925)
		(end 116.150501 176.426)
		(width 0.4)
		(layer "F.Cu")
		(net 200)
	)
	(segment
		(start 184.025 148.650001)
		(end 184.665999 148.650001)
		(width 0.256)
		(layer "F.Cu")
		(net 200)
	)
	(segment
		(start 182.636108 163.651)
		(end 182.636108 165.284999)
		(width 0.256)
		(layer "F.Cu")
		(net 200)
	)
	(segment
		(start 90.748501 126.246921)
		(end 90.013964 126.246921)
		(width 0.15)
		(layer "F.Cu")
		(net 200)
	)
	(segment
		(start 97.849501 115.552)
		(end 97.849501 114.9285)
		(width 0.15)
		(layer "F.Cu")
		(net 200)
	)
	(segment
		(start 97.350501 146.556)
		(end 97.340501 146.546)
		(width 0.4)
		(layer "F.Cu")
		(net 200)
	)
	(segment
		(start 127.376501 185.301)
		(end 126.877001 185.8005)
		(width 0.256)
		(layer "F.Cu")
		(net 200)
	)
	(segment
		(start 145.375501 177.301)
		(end 145.875001 177.8005)
		(width 0.256)
		(layer "F.Cu")
		(net 200)
	)
	(segment
		(start 184.025 149.666)
		(end 184.034 149.675)
		(width 0.256)
		(layer "F.Cu")
		(net 200)
	)
	(segment
		(start 100.260501 145.236)
		(end 100.745501 145.721)
		(width 0.4)
		(layer "F.Cu")
		(net 200)
	)
	(segment
		(start 131.376501 187.300999)
		(end 130.877001 187.8005)
		(width 0.256)
		(layer "F.Cu")
		(net 200)
	)
	(segment
		(start 100.260501 144.816)
		(end 100.260501 145.236)
		(width 0.4)
		(layer "F.Cu")
		(net 200)
	)
	(segment
		(start 90.051501 153.536)
		(end 88.539352 153.536)
		(width 0.256)
		(layer "F.Cu")
		(net 200)
	)
	(segment
		(start 185 164.466001)
		(end 185 163.884501)
		(width 0.4)
		(layer "F.Cu")
		(net 200)
	)
	(segment
		(start 119.650501 175.926)
		(end 120.150501 176.426)
		(width 0.4)
		(layer "F.Cu")
		(net 200)
	)
	(segment
		(start 72.970501 126.296)
		(end 72.970501 125.576)
		(width 0.15)
		(layer "F.Cu")
		(net 200)
	)
	(segment
		(start 100.262501 143.727)
		(end 100.262501 144.814)
		(width 0.4)
		(layer "F.Cu")
		(net 200)
	)
	(segment
		(start 105.24 171.309)
		(end 105.431 171.309)
		(width 0.15)
		(layer "F.Cu")
		(net 200)
	)
	(segment
		(start 91.750501 115.676)
		(end 91.750501 114.926)
		(width 0.15)
		(layer "F.Cu")
		(net 200)
	)
	(segment
		(start 144.375501 186.301)
		(end 144.875 186.8005)
		(width 0.256)
		(layer "F.Cu")
		(net 200)
	)
	(segment
		(start 179.859377 184.664)
		(end 180.926107 184.664)
		(width 0.256)
		(layer "F.Cu")
		(net 200)
	)
	(segment
		(start 97.911825 155.961825)
		(end 97.83765 156.036)
		(width 0.2)
		(layer "F.Cu")
		(net 200)
	)
	(segment
		(start 182.636108 165.284999)
		(end 182.637109 165.286)
		(width 0.256)
		(layer "F.Cu")
		(net 200)
	)
	(segment
		(start 167.7 180.4)
		(end 166.8 181.3)
		(width 0.4)
		(layer "F.Cu")
		(net 200)
	)
	(segment
		(start 96.278 181.944)
		(end 96.55 182.216)
		(width 0.256)
		(layer "F.Cu")
		(net 200)
	)
	(segment
		(start 100.745501 145.721)
		(end 100.745501 146.556)
		(width 0.4)
		(layer "F.Cu")
		(net 200)
	)
	(segment
		(start 134.1 189.7745)
		(end 134.1 190.429)
		(width 0.4)
		(layer "F.Cu")
		(net 200)
	)
	(segment
		(start 126.376502 182.301)
		(end 125.877001 182.8005)
		(width 0.256)
		(layer "F.Cu")
		(net 200)
	)
	(segment
		(start 126.376501 162.302)
		(end 125.877001 161.8025)
		(width 0.256)
		(layer "F.Cu")
		(net 200)
	)
	(segment
		(start 141.375501 187.301)
		(end 141.875001 187.8005)
		(width 0.256)
		(layer "F.Cu")
		(net 200)
	)
	(segment
		(start 137.376501 185.301)
		(end 136.877001 185.8005)
		(width 0.256)
		(layer "F.Cu")
		(net 200)
	)
	(segment
		(start 129.376501 171.302001)
		(end 128.877001 170.8025)
		(width 0.256)
		(layer "F.Cu")
		(net 200)
	)
	(segment
		(start 95.291829 158.223157)
		(end 95.291829 159.291829)
		(width 0.256)
		(layer "F.Cu")
		(net 200)
	)
	(segment
		(start 176.749999 189.35)
		(end 176.75 188.75)
		(width 0.256)
		(layer "F.Cu")
		(net 200)
	)
	(segment
		(start 146.375501 172.301999)
		(end 146.875 171.8025)
		(width 0.256)
		(layer "F.Cu")
		(net 200)
	)
	(segment
		(start 117.650501 172.926)
		(end 117.150501 173.426)
		(width 0.4)
		(layer "F.Cu")
		(net 200)
	)
	(segment
		(start 130.376501 164.302)
		(end 129.877001 163.8025)
		(width 0.256)
		(layer "F.Cu")
		(net 200)
	)
	(segment
		(start 97.849501 114.9285)
		(end 97.851001 114.927)
		(width 0.15)
		(layer "F.Cu")
		(net 200)
	)
	(segment
		(start 95.4 181.944)
		(end 96.278 181.944)
		(width 0.256)
		(layer "F.Cu")
		(net 200)
	)
	(segment
		(start 83.650501 115.676)
		(end 83.650501 114.926)
		(width 0.15)
		(layer "F.Cu")
		(net 200)
	)
	(via
		(at 75.75 139.1)
		(size 0.45)
		(drill 0.1)
		(layers "F.Cu" "B.Cu")
		(net 200)
	)
	(via
		(at 83.900501 154.313149)
		(size 0.45)
		(drill 0.1)
		(layers "F.Cu" "B.Cu")
		(net 200)
	)
	(via
		(at 83.900501 152.813149)
		(size 0.45)
		(drill 0.1)
		(layers "F.Cu" "B.Cu")
		(net 200)
	)
	(via
		(at 86.500501 153.513149)
		(size 0.45)
		(drill 0.1)
		(layers "F.Cu" "B.Cu")
		(net 200)
	)
	(via
		(at 95.3 159.3)
		(size 0.45)
		(drill 0.1)
		(layers "F.Cu" "B.Cu")
		(net 200)
	)
	(via
		(at 113.650501 183.85)
		(size 0.45)
		(drill 0.1)
		(layers "F.Cu" "B.Cu")
		(net 200)
	)
	(via
		(at 138.900501 186.776)
		(size 0.45)
		(drill 0.1)
		(layers "F.Cu" "B.Cu")
		(net 200)
	)
	(via
		(at 179.1 179.1)
		(size 0.45)
		(drill 0.1)
		(layers "F.Cu" "B.Cu")
		(net 200)
	)
	(via
		(at 83.45 166.65)
		(size 0.45)
		(drill 0.1)
		(layers "F.Cu" "B.Cu")
		(net 200)
	)
	(via
		(at 188.3 169.4)
		(size 0.45)
		(drill 0.1)
		(layers "F.Cu" "B.Cu")
		(net 200)
	)
	(via
		(at 128.877001 181.8005)
		(size 0.45)
		(drill 0.1)
		(layers "F.Cu" "B.Cu")
		(net 200)
	)
	(via
		(at 101.430501 146.556)
		(size 0.45)
		(drill 0.1)
		(layers "F.Cu" "B.Cu")
		(net 200)
	)
	(via
		(at 83.45 171.35)
		(size 0.45)
		(drill 0.1)
		(layers "F.Cu" "B.Cu")
		(net 200)
	)
	(via
		(at 94.450501 114.926)
		(size 0.45)
		(drill 0.1)
		(layers "F.Cu" "B.Cu")
		(net 200)
	)
	(via
		(at 102.350501 161.126)
		(size 0.45)
		(drill 0.1)
		(layers "F.Cu" "B.Cu")
		(net 200)
	)
	(via
		(at 148.875501 174.801)
		(size 0.45)
		(drill 0.1)
		(layers "F.Cu" "B.Cu")
		(net 200)
	)
	(via
		(at 141.875001 187.8005)
		(size 0.45)
		(drill 0.1)
		(layers "F.Cu" "B.Cu")
		(net 200)
	)
	(via
		(at 142.875001 180.8005)
		(size 0.45)
		(drill 0.1)
		(layers "F.Cu" "B.Cu")
		(net 200)
	)
	(via
		(at 95.95 154)
		(size 0.45)
		(drill 0.1)
		(layers "F.Cu" "B.Cu")
		(net 200)
	)
	(via
		(at 130.900501 174.776)
		(size 0.45)
		(drill 0.1)
		(layers "F.Cu" "B.Cu")
		(net 200)
	)
	(via
		(at 123.1 188.6745)
		(size 0.45)
		(drill 0.1)
		(layers "F.Cu" "B.Cu")
		(net 200)
	)
	(via
		(at 105.67 174.63)
		(size 0.45)
		(drill 0.1)
		(layers "F.Cu" "B.Cu")
		(net 200)
	)
	(via
		(at 179.649336 184.453959)
		(size 0.45)
		(drill 0.1)
		(layers "F.Cu" "B.Cu")
		(net 200)
	)
	(via
		(at 186.1 172.3)
		(size 0.45)
		(drill 0.1)
		(layers "F.Cu" "B.Cu")
		(net 200)
	)
	(via
		(at 77.8 125.5)
		(size 0.45)
		(drill 0.1)
		(layers "F.Cu" "B.Cu")
		(net 200)
	)
	(via
		(at 182.635107 181.1545)
		(size 0.45)
		(drill 0.1)
		(layers "F.Cu" "B.Cu")
		(net 200)
	)
	(via
		(at 184.674999 149.675)
		(size 0.45)
		(drill 0.1)
		(layers "F.Cu" "B.Cu")
		(net 200)
	)
	(via
		(at 139.875001 181.800501)
		(size 0.45)
		(drill 0.1)
		(layers "F.Cu" "B.Cu")
		(net 200)
	)
	(via
		(at 74.360501 125.306)
		(size 0.45)
		(drill 0.1)
		(layers "F.Cu" "B.Cu")
		(net 200)
	)
	(via
		(at 133.75 143.5)
		(size 0.45)
		(drill 0.1)
		(layers "F.Cu" "B.Cu")
		(net 200)
	)
	(via
		(at 130.877001 166.8025)
		(size 0.45)
		(drill 0.1)
		(layers "F.Cu" "B.Cu")
		(net 200)
	)
	(via
		(at 75.510501 125.556)
		(size 0.45)
		(drill 0.1)
		(layers "F.Cu" "B.Cu")
		(net 200)
	)
	(via
		(at 83.650501 114.926)
		(size 0.45)
		(drill 0.1)
		(layers "F.Cu" "B.Cu")
		(net 200)
	)
	(via
		(at 130.877001 177.8005)
		(size 0.45)
		(drill 0.1)
		(layers "F.Cu" "B.Cu")
		(net 200)
	)
	(via
		(at 100.280501 144.796)
		(size 0.45)
		(drill 0.1)
		(layers "F.Cu" "B.Cu")
		(net 200)
	)
	(via
		(at 126.877001 185.8005)
		(size 0.45)
		(drill 0.1)
		(layers "F.Cu" "B.Cu")
		(net 200)
	)
	(via
		(at 103.2 160.4)
		(size 0.45)
		(drill 0.1)
		(layers "F.Cu" "B.Cu")
		(net 200)
	)
	(via
		(at 131.877 169.8025)
		(size 0.45)
		(drill 0.1)
		(layers "F.Cu" "B.Cu")
		(net 200)
	)
	(via
		(at 144.875 186.8005)
		(size 0.45)
		(drill 0.1)
		(layers "F.Cu" "B.Cu")
		(net 200)
	)
	(via
		(at 136.877001 185.8005)
		(size 0.45)
		(drill 0.1)
		(layers "F.Cu" "B.Cu")
		(net 200)
	)
	(via
		(at 123.4 175.9)
		(size 0.45)
		(drill 0.1)
		(layers "F.Cu" "B.Cu")
		(net 200)
	)
	(via
		(at 184.9975 163.882001)
		(size 0.45)
		(drill 0.1)
		(layers "F.Cu" "B.Cu")
		(net 200)
	)
	(via
		(at 176.75 188.75)
		(size 0.45)
		(drill 0.1)
		(layers "F.Cu" "B.Cu")
		(net 200)
	)
	(via
		(at 125.877001 161.8025)
		(size 0.45)
		(drill 0.1)
		(layers "F.Cu" "B.Cu")
		(net 200)
	)
	(via
		(at 186.1 171.625)
		(size 0.45)
		(drill 0.1)
		(layers "F.Cu" "B.Cu")
		(net 200)
	)
	(via
		(at 123.4 174.9)
		(size 0.45)
		(drill 0.1)
		(layers "F.Cu" "B.Cu")
		(net 200)
	)
	(via
		(at 93.003964 126.236921)
		(size 0.45)
		(drill 0.1)
		(layers "F.Cu" "B.Cu")
		(net 200)
	)
	(via
		(at 166.8 181.3)
		(size 0.45)
		(drill 0.1)
		(layers "F.Cu" "B.Cu")
		(net 200)
	)
	(via
		(at 97.2 182.3)
		(size 0.45)
		(drill 0.1)
		(layers "F.Cu" "B.Cu")
		(net 200)
	)
	(via
		(at 140.875001 184.8005)
		(size 0.45)
		(drill 0.1)
		(layers "F.Cu" "B.Cu")
		(net 200)
	)
	(via
		(at 187 170.3)
		(size 0.45)
		(drill 0.1)
		(layers "F.Cu" "B.Cu")
		(net 200)
	)
	(via
		(at 126.877001 164.802501)
		(size 0.45)
		(drill 0.1)
		(layers "F.Cu" "B.Cu")
		(net 200)
	)
	(via
		(at 117.150501 173.426)
		(size 0.45)
		(drill 0.1)
		(layers "F.Cu" "B.Cu")
		(net 200)
	)
	(via
		(at 129.877001 163.8025)
		(size 0.45)
		(drill 0.1)
		(layers "F.Cu" "B.Cu")
		(net 200)
	)
	(via
		(at 145.875001 177.8005)
		(size 0.45)
		(drill 0.1)
		(layers "F.Cu" "B.Cu")
		(net 200)
	)
	(via
		(at 91.750501 114.926)
		(size 0.45)
		(drill 0.1)
		(layers "F.Cu" "B.Cu")
		(net 200)
	)
	(via
		(at 184.665999 148.650001)
		(size 0.45)
		(drill 0.1)
		(layers "F.Cu" "B.Cu")
		(net 200)
	)
	(via
		(at 92.7 164.4515)
		(size 0.45)
		(drill 0.1)
		(layers "F.Cu" "B.Cu")
		(net 200)
	)
	(via
		(at 134.1 189.7745)
		(size 0.45)
		(drill 0.1)
		(layers "F.Cu" "B.Cu")
		(net 200)
	)
	(via
		(at 90.25 181.2)
		(size 0.45)
		(drill 0.1)
		(layers "F.Cu" "B.Cu")
		(net 200)
	)
	(via
		(at 84.25 175.2)
		(size 0.45)
		(drill 0.1)
		(layers "F.Cu" "B.Cu")
		(net 200)
	)
	(via
		(at 97.911825 155.961825)
		(size 0.45)
		(drill 0.1)
		(layers "F.Cu" "B.Cu")
		(net 200)
	)
	(via
		(at 160.900501 180.676)
		(size 0.45)
		(drill 0.1)
		(layers "F.Cu" "B.Cu")
		(net 200)
	)
	(via
		(at 128.877001 170.8025)
		(size 0.45)
		(drill 0.1)
		(layers "F.Cu" "B.Cu")
		(net 200)
	)
	(via
		(at 127.877001 167.8025)
		(size 0.45)
		(drill 0.1)
		(layers "F.Cu" "B.Cu")
		(net 200)
	)
	(via
		(at 181.285 196.735)
		(size 0.45)
		(drill 0.1)
		(layers "F.Cu" "B.Cu")
		(net 200)
	)
	(via
		(at 90.013964 126.246921)
		(size 0.45)
		(drill 0.1)
		(layers "F.Cu" "B.Cu")
		(net 200)
	)
	(via
		(at 137 143.5)
		(size 0.45)
		(drill 0.1)
		(layers "F.Cu" "B.Cu")
		(net 200)
	)
	(via
		(at 75.75 135.125)
		(size 0.45)
		(drill 0.1)
		(layers "F.Cu" "B.Cu")
		(net 200)
	)
	(via
		(at 154.875001 175.800501)
		(size 0.45)
		(drill 0.1)
		(layers "F.Cu" "B.Cu")
		(net 200)
	)
	(via
		(at 89.050501 114.926)
		(size 0.45)
		(drill 0.1)
		(layers "F.Cu" "B.Cu")
		(net 200)
	)
	(via
		(at 186.1 170.275)
		(size 0.45)
		(drill 0.1)
		(layers "F.Cu" "B.Cu")
		(net 200)
	)
	(via
		(at 179.694999 128.2)
		(size 0.45)
		(drill 0.1)
		(layers "F.Cu" "B.Cu")
		(net 200)
	)
	(via
		(at 186.1 169.6)
		(size 0.45)
		(drill 0.1)
		(layers "F.Cu" "B.Cu")
		(net 200)
	)
	(via
		(at 86.350501 114.926)
		(size 0.45)
		(drill 0.1)
		(layers "F.Cu" "B.Cu")
		(net 200)
	)
	(via
		(at 116.150501 176.426)
		(size 0.45)
		(drill 0.1)
		(layers "F.Cu" "B.Cu")
		(net 200)
	)
	(via
		(at 125.877001 182.8005)
		(size 0.45)
		(drill 0.1)
		(layers "F.Cu" "B.Cu")
		(net 200)
	)
	(via
		(at 105.68 170.880157)
		(size 0.45)
		(drill 0.1)
		(layers "F.Cu" "B.Cu")
		(net 200)
	)
	(via
		(at 125.95 144.05)
		(size 0.45)
		(drill 0.1)
		(layers "F.Cu" "B.Cu")
		(net 200)
	)
	(via
		(at 121.650001 183.100001)
		(size 0.45)
		(drill 0.1)
		(layers "F.Cu" "B.Cu")
		(net 200)
	)
	(via
		(at 188.3 170.25)
		(size 0.45)
		(drill 0.1)
		(layers "F.Cu" "B.Cu")
		(net 200)
	)
	(via
		(at 125.875501 174.801)
		(size 0.45)
		(drill 0.1)
		(layers "F.Cu" "B.Cu")
		(net 200)
	)
	(via
		(at 187 169.4)
		(size 0.45)
		(drill 0.1)
		(layers "F.Cu" "B.Cu")
		(net 200)
	)
	(via
		(at 99.491829 149.583157)
		(size 0.45)
		(drill 0.1)
		(layers "F.Cu" "B.Cu")
		(net 200)
	)
	(via
		(at 97.340501 146.546)
		(size 0.45)
		(drill 0.1)
		(layers "F.Cu" "B.Cu")
		(net 200)
	)
	(via
		(at 84.4 170.4)
		(size 0.45)
		(drill 0.1)
		(layers "F.Cu" "B.Cu")
		(net 200)
	)
	(via
		(at 146.875 171.8025)
		(size 0.45)
		(drill 0.1)
		(layers "F.Cu" "B.Cu")
		(net 200)
	)
	(via
		(at 181.3 195.65)
		(size 0.45)
		(drill 0.1)
		(layers "F.Cu" "B.Cu")
		(net 200)
	)
	(via
		(at 182.637608 163.012)
		(size 0.45)
		(drill 0.1)
		(layers "F.Cu" "B.Cu")
		(net 200)
	)
	(via
		(at 99.35 154.15)
		(size 0.45)
		(drill 0.1)
		(layers "F.Cu" "B.Cu")
		(net 200)
	)
	(via
		(at 143.875001 183.8005)
		(size 0.45)
		(drill 0.1)
		(layers "F.Cu" "B.Cu")
		(net 200)
	)
	(via
		(at 130.877001 187.8005)
		(size 0.45)
		(drill 0.1)
		(layers "F.Cu" "B.Cu")
		(net 200)
	)
	(via
		(at 126.175 202.85)
		(size 0.45)
		(drill 0.1)
		(layers "F.Cu" "B.Cu")
		(net 200)
	)
	(via
		(at 131.900501 174.776)
		(size 0.45)
		(drill 0.1)
		(layers "F.Cu" "B.Cu")
		(net 200)
	)
	(via
		(at 121.650001 182)
		(size 0.45)
		(drill 0.1)
		(layers "F.Cu" "B.Cu")
		(net 200)
	)
	(via
		(at 186.1 170.95)
		(size 0.45)
		(drill 0.1)
		(layers "F.Cu" "B.Cu")
		(net 200)
	)
	(via
		(at 120.150501 176.426)
		(size 0.45)
		(drill 0.1)
		(layers "F.Cu" "B.Cu")
		(net 200)
	)
	(via
		(at 184.997 182.084)
		(size 0.45)
		(drill 0.1)
		(layers "F.Cu" "B.Cu")
		(net 200)
	)
	(via
		(at 126.875501 174.801)
		(size 0.45)
		(drill 0.1)
		(layers "F.Cu" "B.Cu")
		(net 200)
	)
	(via
		(at 129.877 184.8005)
		(size 0.45)
		(drill 0.1)
		(layers "F.Cu" "B.Cu")
		(net 200)
	)
	(via
		(at 97.851001 114.927)
		(size 0.45)
		(drill 0.1)
		(layers "F.Cu" "B.Cu")
		(net 200)
	)
	(segment
		(start 84.715501 154.313149)
		(end 83.900501 154.313149)
		(width 0.2)
		(layer "B.Cu")
		(net 200)
	)
	(segment
		(start 84.715501 152.813149)
		(end 83.900501 152.813149)
		(width 0.2)
		(layer "B.Cu")
		(net 200)
	)
	(segment
		(start 102.474 161.126)
		(end 103.2 160.4)
		(width 0.256)
		(layer "B.Cu")
		(net 200)
	)
	(segment
		(start 84.35 170.45)
		(end 84.35 171.315)
		(width 0.256)
		(layer "B.Cu")
		(net 200)
	)
	(segment
		(start 84.35 171.315)
		(end 84.265 171.4)
		(width 0.256)
		(layer "B.Cu")
		(net 200)
	)
	(segment
		(start 131.375501 187.302)
		(end 130.877001 187.8005)
		(width 0.4)
		(layer "B.Cu")
		(net 200)
	)
	(segment
		(start 113.700502 183.799999)
		(end 113.650501 183.85)
		(width 0.256)
		(layer "B.Cu")
		(net 200)
	)
	(segment
		(start 142.375501 180.301)
		(end 142.875001 180.8005)
		(width 0.4)
		(layer "B.Cu")
		(net 200)
	)
	(segment
		(start 102.584 159.55)
		(end 102.584 159.684)
		(width 0.256)
		(layer "B.Cu")
		(net 200)
	)
	(segment
		(start 154.760502 175.800501)
		(end 154.875001 175.800501)
		(width 0.201)
		(layer "B.Cu")
		(net 200)
	)
	(segment
		(start 142.373501 180.301)
		(end 142.375501 180.301)
		(width 0.4)
		(layer "B.Cu")
		(net 200)
	)
	(segment
		(start 160.1855 180.676001)
		(end 160.900501 180.676)
		(width 0.256)
		(layer "B.Cu")
		(net 200)
	)
	(segment
		(start 144.375501 183.3)
		(end 143.875001 183.8005)
		(width 0.4)
		(layer "B.Cu")
		(net 200)
	)
	(segment
		(start 123.7 188.335)
		(end 123.7 188.35)
		(width 0.4)
		(layer "B.Cu")
		(net 200)
	)
	(segment
		(start 96.400501 161.116)
		(end 96.375501 161.091)
		(width 0.256)
		(layer "B.Cu")
		(net 200)
	)
	(segment
		(start 140.375 182.3005)
		(end 139.875001 181.800501)
		(width 0.4)
		(layer "B.Cu")
		(net 200)
	)
	(segment
		(start 84.35 169)
		(end 84.275 168.925)
		(width 0.256)
		(layer "B.Cu")
		(net 200)
	)
	(segment
		(start 84.4 170.4)
		(end 84.35 170.45)
		(width 0.256)
		(layer "B.Cu")
		(net 200)
	)
	(segment
		(start 105.96 171.5)
		(end 105.96 171.160157)
		(width 0.15)
		(layer "B.Cu")
		(net 200)
	)
	(segment
		(start 140.375501 185.303)
		(end 140.375501 185.3)
		(width 0.4)
		(layer "B.Cu")
		(net 200)
	)
	(segment
		(start 133.2 144.05)
		(end 125.95 144.05)
		(width 0.256)
		(layer "B.Cu")
		(net 200)
	)
	(segment
		(start 140.375501 185.3)
		(end 140.875001 184.8005)
		(width 0.4)
		(layer "B.Cu")
		(net 200)
	)
	(segment
		(start 131.375501 170.303)
		(end 131.3765 170.303)
		(width 0.4)
		(layer "B.Cu")
		(net 200)
	)
	(segment
		(start 75.75 135.125)
		(end 75.780501 135.094499)
		(width 0.2)
		(layer "B.Cu")
		(net 200)
	)
	(segment
		(start 145.875001 177.8005)
		(end 145.875001 177.8035)
		(width 0.4)
		(layer "B.Cu")
		(net 200)
	)
	(segment
		(start 137 142.885)
		(end 137 143.5)
		(width 0.256)
		(layer "B.Cu")
		(net 200)
	)
	(segment
		(start 114.316502 183.799999)
		(end 113.700502 183.799999)
		(width 0.256)
		(layer "B.Cu")
		(net 200)
	)
	(segment
		(start 105.67 175.426)
		(end 105.96 175.716)
		(width 0.15)
		(layer "B.Cu")
		(net 200)
	)
	(segment
		(start 133.75 142.885)
		(end 133.75 143.5)
		(width 0.256)
		(layer "B.Cu")
		(net 200)
	)
	(segment
		(start 131.375501 166.299)
		(end 131.375501 166.304)
		(width 0.4)
		(layer "B.Cu")
		(net 200)
	)
	(segment
		(start 102.350501 161.126)
		(end 102.474 161.126)
		(width 0.256)
		(layer "B.Cu")
		(net 200)
	)
	(segment
		(start 99 153.8)
		(end 99.35 154.15)
		(width 0.256)
		(layer "B.Cu")
		(net 200)
	)
	(segment
		(start 115.580501 176.442)
		(end 114.691501 176.442)
		(width 0.4)
		(layer "B.Cu")
		(net 200)
	)
	(segment
		(start 138.900501 185.976)
		(end 138.900501 186.776)
		(width 0.256)
		(layer "B.Cu")
		(net 200)
	)
	(segment
		(start 125.875501 174.801)
		(end 126.875501 174.801)
		(width 0.4)
		(layer "B.Cu")
		(net 200)
	)
	(segment
		(start 105.67 174.63)
		(end 105.67 175.426)
		(width 0.15)
		(layer "B.Cu")
		(net 200)
	)
	(segment
		(start 102.584 159.684)
		(end 103.2 160.3)
		(width 0.256)
		(layer "B.Cu")
		(net 200)
	)
	(segment
		(start 126.375501 162.301)
		(end 125.877001 161.8025)
		(width 0.4)
		(layer "B.Cu")
		(net 200)
	)
	(segment
		(start 130.375501 184.2985)
		(end 130.375501 184.301999)
		(width 0.4)
		(layer "B.Cu")
		(net 200)
	)
	(segment
		(start 145.875001 177.8035)
		(end 145.375501 178.303)
		(width 0.4)
		(layer "B.Cu")
		(net 200)
	)
	(segment
		(start 117.150501 173.426)
		(end 117.150501 172.882)
		(width 0.4)
		(layer "B.Cu")
		(net 200)
	)
	(segment
		(start 84.35 170.35)
		(end 84.35 169)
		(width 0.256)
		(layer "B.Cu")
		(net 200)
	)
	(segment
		(start 127.3755 165.301)
		(end 126.877001 164.802501)
		(width 0.4)
		(layer "B.Cu")
		(net 200)
	)
	(segment
		(start 97.616 155.666)
		(end 97.911825 155.961825)
		(width 0.256)
		(layer "B.Cu")
		(net 200)
	)
	(segment
		(start 82.75 170.734)
		(end 82.834 170.734)
		(width 0.4)
		(layer "B.Cu")
		(net 200)
	)
	(segment
		(start 83.45 166.65)
		(end 83.5 166.7)
		(width 0.256)
		(layer "B.Cu")
		(net 200)
	)
	(segment
		(start 144.379001 186.304501)
		(end 144.875 186.8005)
		(width 0.4)
		(layer "B.Cu")
		(net 200)
	)
	(segment
		(start 126.377501 162.301)
		(end 126.375501 162.301)
		(width 0.4)
		(layer "B.Cu")
		(net 200)
	)
	(segment
		(start 128.375501 168.301)
		(end 127.877001 167.8025)
		(width 0.4)
		(layer "B.Cu")
		(net 200)
	)
	(segment
		(start 126.375501 182.302)
		(end 125.877001 182.8005)
		(width 0.4)
		(layer "B.Cu")
		(net 200)
	)
	(segment
		(start 131.375501 166.304)
		(end 130.877001 166.8025)
		(width 0.4)
		(layer "B.Cu")
		(net 200)
	)
	(segment
		(start 82.834 170.734)
		(end 83.45 171.35)
		(width 0.4)
		(layer "B.Cu")
		(net 200)
	)
	(segment
		(start 127.375501 185.299)
		(end 127.375501 185.302)
		(width 0.4)
		(layer "B.Cu")
		(net 200)
	)
	(segment
		(start 160.185501 179.676)
		(end 160.185501 181.676)
		(width 0.256)
		(layer "B.Cu")
		(net 200)
	)
	(segment
		(start 125.377001 173.3005)
		(end 125.352001 173.3255)
		(width 0.256)
		(layer "B.Cu")
		(net 200)
	)
	(segment
		(start 134.116501 189.757999)
		(end 134.116501 189.276)
		(width 0.4)
		(layer "B.Cu")
		(net 200)
	)
	(segment
		(start 140.377001 182.3005)
		(end 140.375 182.3005)
		(width 0.4)
		(layer "B.Cu")
		(net 200)
	)
	(segment
		(start 123.4 175.9)
		(end 123.4 175.911501)
		(width 0.256)
		(layer "B.Cu")
		(net 200)
	)
	(segment
		(start 98.585 153.8)
		(end 99 153.8)
		(width 0.256)
		(layer "B.Cu")
		(net 200)
	)
	(segment
		(start 75.780501 135.094499)
		(end 75.780501 134.406)
		(width 0.2)
		(layer "B.Cu")
		(net 200)
	)
	(segment
		(start 97.616 155.2)
		(end 97.616 155.666)
		(width 0.256)
		(layer "B.Cu")
		(net 200)
	)
	(segment
		(start 102.340501 161.116)
		(end 102.350501 161.126)
		(width 0.256)
		(layer "B.Cu")
		(net 200)
	)
	(segment
		(start 101.625501 161.116)
		(end 102.340501 161.116)
		(width 0.256)
		(layer "B.Cu")
		(net 200)
	)
	(segment
		(start 126.175 202.85)
		(end 125.485 202.85)
		(width 0.177)
		(layer "B.Cu")
		(net 200)
	)
	(segment
		(start 147.375001 174.1005)
		(end 148.075501 174.801)
		(width 0.256)
		(layer "B.Cu")
		(net 200)
	)
	(segment
		(start 95.485 154.465)
		(end 95.95 154)
		(width 0.256)
		(layer "B.Cu")
		(net 200)
	)
	(segment
		(start 135.375 186.3)
		(end 136.377501 186.3)
		(width 0.256)
		(layer "B.Cu")
		(net 200)
	)
	(segment
		(start 144.379001 186.3005)
		(end 144.379001 186.304501)
		(width 0.4)
		(layer "B.Cu")
		(net 200)
	)
	(segment
		(start 114.691501 176.442)
		(end 114.275501 176.026)
		(width 0.4)
		(layer "B.Cu")
		(net 200)
	)
	(segment
		(start 144.375501 183.299)
		(end 144.375501 183.3)
		(width 0.4)
		(layer "B.Cu")
		(net 200)
	)
	(segment
		(start 95.308672 159.291328)
		(end 95.3 159.3)
		(width 0.256)
		(layer "B.Cu")
		(net 200)
	)
	(segment
		(start 131.375501 187.299)
		(end 131.375501 187.302)
		(width 0.4)
		(layer "B.Cu")
		(net 200)
	)
	(segment
		(start 84.25 171.415)
		(end 84.265 171.4)
		(width 0.256)
		(layer "B.Cu")
		(net 200)
	)
	(segment
		(start 100.280501 144.03)
		(end 100.280501 144.796)
		(width 0.4)
		(layer "B.Cu")
		(net 200)
	)
	(segment
		(start 95.308672 154.465)
		(end 95.485 154.465)
		(width 0.256)
		(layer "B.Cu")
		(net 200)
	)
	(segment
		(start 131.3765 170.303)
		(end 131.877 169.8025)
		(width 0.4)
		(layer "B.Cu")
		(net 200)
	)
	(segment
		(start 120.134501 176.41)
		(end 120.150501 176.426)
		(width 0.4)
		(layer "B.Cu")
		(net 200)
	)
	(segment
		(start 123.1 188.6745)
		(end 123.3755 188.6745)
		(width 0.256)
		(layer "B.Cu")
		(net 200)
	)
	(segment
		(start 115.285501 182.6)
		(end 115.285501 182.831)
		(width 0.256)
		(layer "B.Cu")
		(net 200)
	)
	(segment
		(start 146.375001 178.3025)
		(end 146.375001 178.3005)
		(width 0.4)
		(layer "B.Cu")
		(net 200)
	)
	(segment
		(start 147.375001 173.3025)
		(end 147.375001 174.1005)
		(width 0.256)
		(layer "B.Cu")
		(net 200)
	)
	(segment
		(start 142.375501 187.299)
		(end 142.375501 187.3)
		(width 0.4)
		(layer "B.Cu")
		(net 200)
	)
	(segment
		(start 97.615 158.1)
		(end 97.615 156.25865)
		(width 0.2)
		(layer "B.Cu")
		(net 200)
	)
	(segment
		(start 122.665001 183.1)
		(end 121.650001 183.100001)
		(width 0.256)
		(layer "B.Cu")
		(net 200)
	)
	(segment
		(start 127.377501 165.301)
		(end 127.3755 165.301)
		(width 0.4)
		(layer "B.Cu")
		(net 200)
	)
	(segment
		(start 147.375001 171.2985)
		(end 147.375001 171.302499)
		(width 0.4)
		(layer "B.Cu")
		(net 200)
	)
	(segment
		(start 181.285 197.4)
		(end 181.285 196.735)
		(width 0.177)
		(layer "B.Cu")
		(net 200)
	)
	(segment
		(start 179.595377 184.4)
		(end 179.649336 184.453959)
		(width 0.256)
		(layer "B.Cu")
		(net 200)
	)
	(segment
		(start 94.308672 158.488992)
		(end 95.308672 158.488992)
		(width 0.4)
		(layer "B.Cu")
		(net 200)
	)
	(segment
		(start 101.625501 161.116)
		(end 96.400501 161.116)
		(width 0.256)
		(layer "B.Cu")
		(net 200)
	)
	(segment
		(start 125.352001 173.3255)
		(end 125.352001 174.2775)
		(width 0.256)
		(layer "B.Cu")
		(net 200)
	)
	(segment
		(start 75.75 139.1)
		(end 75.75 139.815)
		(width 0.2)
		(layer "B.Cu")
		(net 200)
	)
	(segment
		(start 128.376501 171.303)
		(end 128.877001 170.8025)
		(width 0.4)
		(layer "B.Cu")
		(net 200)
	)
	(segment
		(start 134.1 189.7745)
		(end 134.116501 189.757999)
		(width 0.4)
		(layer "B.Cu")
		(net 200)
	)
	(segment
		(start 129.375501 181.302)
		(end 128.877001 181.8005)
		(width 0.4)
		(layer "B.Cu")
		(net 200)
	)
	(segment
		(start 148.075501 174.801)
		(end 148.875501 174.801)
		(width 0.4)
		(layer "B.Cu")
		(net 200)
	)
	(segment
		(start 181.285 195.635)
		(end 181.3 195.65)
		(width 0.177)
		(layer "B.Cu")
		(net 200)
	)
	(segment
		(start 105.96 171.160157)
		(end 105.68 170.880157)
		(width 0.15)
		(layer "B.Cu")
		(net 200)
	)
	(segment
		(start 131.375501 177.299)
		(end 131.375501 177.302)
		(width 0.4)
		(layer "B.Cu")
		(net 200)
	)
	(segment
		(start 130.375501 184.301999)
		(end 129.877 184.8005)
		(width 0.4)
		(layer "B.Cu")
		(net 200)
	)
	(segment
		(start 115.285501 182.831)
		(end 114.316502 183.799999)
		(width 0.256)
		(layer "B.Cu")
		(net 200)
	)
	(segment
		(start 130.375501 163.299)
		(end 130.375501 163.304)
		(width 0.4)
		(layer "B.Cu")
		(net 200)
	)
	(segment
		(start 129.375501 181.299)
		(end 129.375501 181.302)
		(width 0.4)
		(layer "B.Cu")
		(net 200)
	)
	(segment
		(start 84.25 175.2)
		(end 84.25 171.415)
		(width 0.256)
		(layer "B.Cu")
		(net 200)
	)
	(segment
		(start 83.5 166.7)
		(end 84.076499 166.7)
		(width 0.256)
		(layer "B.Cu")
		(net 200)
	)
	(segment
		(start 123.4 174.9)
		(end 123.361501 174.9)
		(width 0.256)
		(layer "B.Cu")
		(net 200)
	)
	(segment
		(start 130.375501 163.304)
		(end 129.877001 163.8025)
		(width 0.4)
		(layer "B.Cu")
		(net 200)
	)
	(segment
		(start 146.375001 178.3005)
		(end 145.875001 177.8005)
		(width 0.4)
		(layer "B.Cu")
		(net 200)
	)
	(segment
		(start 123.4 175.911501)
		(end 122.835501 176.476)
		(width 0.256)
		(layer "B.Cu")
		(net 200)
	)
	(segment
		(start 122.665001 182.000001)
		(end 121.650001 182)
		(width 0.256)
		(layer "B.Cu")
		(net 200)
	)
	(segment
		(start 95.308672 158.488992)
		(end 95.308672 159.291328)
		(width 0.256)
		(layer "B.Cu")
		(net 200)
	)
	(segment
		(start 116.150501 176.426)
		(end 115.596501 176.426)
		(width 0.4)
		(layer "B.Cu")
		(net 200)
	)
	(segment
		(start 84.076499 166.7)
		(end 84.260499 166.884)
		(width 0.256)
		(layer "B.Cu")
		(net 200)
	)
	(segment
		(start 137.375501 185.299)
		(end 137.375501 185.302)
		(width 0.4)
		(layer "B.Cu")
		(net 200)
	)
	(segment
		(start 103.2 160.3)
		(end 103.2 160.4)
		(width 0.256)
		(layer "B.Cu")
		(net 200)
	)
	(segment
		(start 126.375501 182.299)
		(end 126.375501 182.302)
		(width 0.4)
		(layer "B.Cu")
		(net 200)
	)
	(segment
		(start 128.375501 171.303)
		(end 128.376501 171.303)
		(width 0.4)
		(layer "B.Cu")
		(net 200)
	)
	(segment
		(start 131.375501 177.302)
		(end 130.877001 177.8005)
		(width 0.4)
		(layer "B.Cu")
		(net 200)
	)
	(segment
		(start 117.150501 172.882)
		(end 117.166501 172.866)
		(width 0.4)
		(layer "B.Cu")
		(net 200)
	)
	(segment
		(start 137.375501 185.302)
		(end 136.877001 185.8005)
		(width 0.4)
		(layer "B.Cu")
		(net 200)
	)
	(segment
		(start 136.377501 186.3)
		(end 136.877001 185.8005)
		(width 0.256)
		(layer "B.Cu")
		(net 200)
	)
	(segment
		(start 84.4 170.4)
		(end 84.35 170.35)
		(width 0.256)
		(layer "B.Cu")
		(net 200)
	)
	(segment
		(start 123.361501 174.9)
		(end 122.835501 175.426)
		(width 0.256)
		(layer "B.Cu")
		(net 200)
	)
	(segment
		(start 128.377501 168.301)
		(end 128.375501 168.301)
		(width 0.4)
		(layer "B.Cu")
		(net 200)
	)
	(segment
		(start 125.352001 174.2775)
		(end 125.875501 174.801)
		(width 0.256)
		(layer "B.Cu")
		(net 200)
	)
	(segment
		(start 115.596501 176.426)
		(end 115.580501 176.442)
		(width 0.4)
		(layer "B.Cu")
		(net 200)
	)
	(segment
		(start 154.260001 175.3)
		(end 154.760502 175.800501)
		(width 0.201)
		(layer "B.Cu")
		(net 200)
	)
	(segment
		(start 84.260499 166.884)
		(end 84.260499 168.910499)
		(width 0.256)
		(layer "B.Cu")
		(net 200)
	)
	(segment
		(start 99.491829 149.583157)
		(end 98.906127 149.583157)
		(width 0.2)
		(layer "B.Cu")
		(net 200)
	)
	(segment
		(start 133.75 143.5)
		(end 133.2 144.05)
		(width 0.256)
		(layer "B.Cu")
		(net 200)
	)
	(segment
		(start 123.3755 188.6745)
		(end 123.7 188.35)
		(width 0.256)
		(layer "B.Cu")
		(net 200)
	)
	(segment
		(start 130.900501 174.776)
		(end 131.900501 174.776)
		(width 0.4)
		(layer "B.Cu")
		(net 200)
	)
	(segment
		(start 187 168.05)
		(end 186.4 167.45)
		(width 0.15)
		(layer "B.Cu")
		(net 200)
	)
	(segment
		(start 127.375501 185.302)
		(end 126.877001 185.8005)
		(width 0.4)
		(layer "B.Cu")
		(net 200)
	)
	(segment
		(start 147.375001 171.302499)
		(end 146.875 171.8025)
		(width 0.4)
		(layer "B.Cu")
		(net 200)
	)
	(segment
		(start 142.375501 187.3)
		(end 141.875001 187.8005)
		(width 0.4)
		(layer "B.Cu")
		(net 200)
	)
	(segment
		(start 84.260499 168.910499)
		(end 84.275 168.925)
		(width 0.256)
		(layer "B.Cu")
		(net 200)
	)
	(segment
		(start 119.580501 176.41)
		(end 120.134501 176.41)
		(width 0.4)
		(layer "B.Cu")
		(net 200)
	)
	(segment
		(start 181.285 194.05)
		(end 181.285 195.635)
		(width 0.177)
		(layer "B.Cu")
		(net 200)
	)
	(segment
		(start 97.615 156.25865)
		(end 97.911825 155.961825)
		(width 0.2)
		(layer "B.Cu")
		(net 200)
	)
	(segment
		(start 187 169.4)
		(end 187 168.05)
		(width 0.15)
		(layer "B.Cu")
		(net 200)
	)
	(segment
		(start 93.316 164.4515)
		(end 92.7 164.4515)
		(width 0.256)
		(layer "B.Cu")
		(net 200)
	)
	(segment
		(start 134.35 144.1)
		(end 133.75 143.5)
		(width 0.256)
		(layer "In9.Cu")
		(net 200)
	)
	(segment
		(start 137 143.5)
		(end 136.4 144.1)
		(width 0.256)
		(layer "In9.Cu")
		(net 200)
	)
	(segment
		(start 136.4 144.1)
		(end 134.35 144.1)
		(width 0.256)
		(layer "In9.Cu")
		(net 200)
	)
	(segment
		(start 157.3985 175.578001)
		(end 157.000501 175.976)
		(width 0.4)
		(layer "F.Cu")
		(net 201)
	)
	(segment
		(start 106.400001 146.2025)
		(end 106.400001 147.5275)
		(width 0.201)
		(layer "F.Cu")
		(net 201)
	)
	(segment
		(start 106.400001 147.5275)
		(end 106.475001 147.6025)
		(width 0.201)
		(layer "F.Cu")
		(net 201)
	)
	(segment
		(start 106.400001 147.7775)
		(end 106.277001 147.9005)
		(width 0.201)
		(layer "F.Cu")
		(net 201)
	)
	(segment
		(start 185.3 162.15)
		(end 186.1 162.15)
		(width 0.4)
		(layer "F.Cu")
		(net 201)
	)
	(segment
		(start 106.900001 147.5775)
		(end 106.900001 146.2025)
		(width 0.201)
		(layer "F.Cu")
		(net 201)
	)
	(segment
		(start 85.435501 187.2)
		(end 85.686001 187.4505)
		(width 0.4)
		(layer "F.Cu")
		(net 201)
	)
	(segment
		(start 84.85 187.2)
		(end 85.435501 187.2)
		(width 0.4)
		(layer "F.Cu")
		(net 201)
	)
	(segment
		(start 106.475001 147.6025)
		(end 106.875001 147.6025)
		(width 0.201)
		(layer "F.Cu")
		(net 201)
	)
	(segment
		(start 106.277001 147.9005)
		(end 105.659001 147.9005)
		(width 0.201)
		(layer "F.Cu")
		(net 201)
	)
	(segment
		(start 106.875001 147.6025)
		(end 106.900001 147.5775)
		(width 0.201)
		(layer "F.Cu")
		(net 201)
	)
	(segment
		(start 157.3985 174.4265)
		(end 157.3985 175.578001)
		(width 0.4)
		(layer "F.Cu")
		(net 201)
	)
	(segment
		(start 106.400001 147.5275)
		(end 106.400001 147.7775)
		(width 0.201)
		(layer "F.Cu")
		(net 201)
	)
	(via
		(at 188.2 163.525)
		(size 0.45)
		(drill 0.1)
		(layers "F.Cu" "B.Cu")
		(net 201)
	)
	(via
		(at 106.675001 148.4025)
		(size 0.45)
		(drill 0.1)
		(layers "F.Cu" "B.Cu")
		(net 201)
	)
	(via
		(at 186.1 161.475)
		(size 0.45)
		(drill 0.1)
		(layers "F.Cu" "B.Cu")
		(net 201)
	)
	(via
		(at 186.1 162.15)
		(size 0.45)
		(drill 0.1)
		(layers "F.Cu" "B.Cu")
		(net 201)
	)
	(via
		(at 186.1 163.5)
		(size 0.45)
		(drill 0.1)
		(layers "F.Cu" "B.Cu")
		(net 201)
	)
	(via
		(at 106.675001 150.2025)
		(size 0.45)
		(drill 0.1)
		(layers "F.Cu" "B.Cu")
		(net 201)
	)
	(via
		(at 186.1 162.825)
		(size 0.45)
		(drill 0.1)
		(layers "F.Cu" "B.Cu")
		(net 201)
	)
	(via
		(at 106.675001 149.0025)
		(size 0.45)
		(drill 0.1)
		(layers "F.Cu" "B.Cu")
		(net 201)
	)
	(via
		(at 105.475001 150.2025)
		(size 0.45)
		(drill 0.1)
		(layers "F.Cu" "B.Cu")
		(net 201)
	)
	(via
		(at 157.000501 175.976)
		(size 0.45)
		(drill 0.1)
		(layers "F.Cu" "B.Cu")
		(net 201)
	)
	(via
		(at 185.3 162.15)
		(size 0.45)
		(drill 0.1)
		(layers "F.Cu" "B.Cu")
		(net 201)
	)
	(via
		(at 187.2 163.525)
		(size 0.45)
		(drill 0.1)
		(layers "F.Cu" "B.Cu")
		(net 201)
	)
	(via
		(at 106.675001 149.6025)
		(size 0.45)
		(drill 0.1)
		(layers "F.Cu" "B.Cu")
		(net 201)
	)
	(via
		(at 106.075001 150.2025)
		(size 0.45)
		(drill 0.1)
		(layers "F.Cu" "B.Cu")
		(net 201)
	)
	(via
		(at 105.459001 149.6025)
		(size 0.45)
		(drill 0.1)
		(layers "F.Cu" "B.Cu")
		(net 201)
	)
	(via
		(at 84.85 187.2)
		(size 0.45)
		(drill 0.1)
		(layers "F.Cu" "B.Cu")
		(net 201)
	)
	(via
		(at 188.2 164.8)
		(size 0.45)
		(drill 0.1)
		(layers "F.Cu" "B.Cu")
		(net 201)
	)
	(via
		(at 187.225 164.8)
		(size 0.45)
		(drill 0.1)
		(layers "F.Cu" "B.Cu")
		(net 201)
	)
	(via
		(at 106.059001 149.6025)
		(size 0.45)
		(drill 0.1)
		(layers "F.Cu" "B.Cu")
		(net 201)
	)
	(via
		(at 99.6 128.65)
		(size 0.45)
		(drill 0.1)
		(layers "F.Cu" "B.Cu")
		(net 201)
	)
	(segment
		(start 157.000501 175.976)
		(end 157.000501 175.292)
		(width 0.4)
		(layer "B.Cu")
		(net 201)
	)
	(segment
		(start 84.85 186.7)
		(end 77.05 178.9)
		(width 0.4)
		(layer "B.Cu")
		(net 201)
	)
	(segment
		(start 186.4 164.5845)
		(end 186.4 163.8)
		(width 0.15)
		(layer "B.Cu")
		(net 201)
	)
	(segment
		(start 77.05 166.75)
		(end 79.75 164.05)
		(width 0.4)
		(layer "B.Cu")
		(net 201)
	)
	(segment
		(start 156.984501 174.515499)
		(end 156.984501 175.276)
		(width 0.4)
		(layer "B.Cu")
		(net 201)
	)
	(segment
		(start 77.05 178.9)
		(end 77.05 166.75)
		(width 0.4)
		(layer "B.Cu")
		(net 201)
	)
	(segment
		(start 186.4 163.8)
		(end 186.1 163.5)
		(width 0.15)
		(layer "B.Cu")
		(net 201)
	)
	(segment
		(start 81.175 148.325)
		(end 84.325 148.325)
		(width 0.4)
		(layer "B.Cu")
		(net 201)
	)
	(segment
		(start 179.9 163)
		(end 178.3 163)
		(width 0.4)
		(layer "B.Cu")
		(net 201)
	)
	(segment
		(start 93.3 128.65)
		(end 99.6 128.65)
		(width 0.4)
		(layer "B.Cu")
		(net 201)
	)
	(segment
		(start 91.55 141.1)
		(end 91.55 130.4)
		(width 0.4)
		(layer "B.Cu")
		(net 201)
	)
	(segment
		(start 84.85 187.2)
		(end 84.85 186.7)
		(width 0.4)
		(layer "B.Cu")
		(net 201)
	)
	(segment
		(start 157.000501 175.292)
		(end 156.984501 175.276)
		(width 0.4)
		(layer "B.Cu")
		(net 201)
	)
	(segment
		(start 169.7 171.6)
		(end 159.9 171.6)
		(width 0.4)
		(layer "B.Cu")
		(net 201)
	)
	(segment
		(start 84.325 148.325)
		(end 91.55 141.1)
		(width 0.4)
		(layer "B.Cu")
		(net 201)
	)
	(segment
		(start 156.984501 175.276)
		(end 158.015501 175.276)
		(width 0.4)
		(layer "B.Cu")
		(net 201)
	)
	(segment
		(start 79.75 149.75)
		(end 81.175 148.325)
		(width 0.4)
		(layer "B.Cu")
		(net 201)
	)
	(segment
		(start 185.3 162.15)
		(end 180.75 162.15)
		(width 0.4)
		(layer "B.Cu")
		(net 201)
	)
	(segment
		(start 180.75 162.15)
		(end 179.9 163)
		(width 0.4)
		(layer "B.Cu")
		(net 201)
	)
	(segment
		(start 159.9 171.6)
		(end 156.984501 174.515499)
		(width 0.4)
		(layer "B.Cu")
		(net 201)
	)
	(segment
		(start 91.55 130.4)
		(end 93.3 128.65)
		(width 0.4)
		(layer "B.Cu")
		(net 201)
	)
	(segment
		(start 178.3 163)
		(end 169.7 171.6)
		(width 0.4)
		(layer "B.Cu")
		(net 201)
	)
	(segment
		(start 79.75 164.05)
		(end 79.75 149.75)
		(width 0.4)
		(layer "B.Cu")
		(net 201)
	)
	(segment
		(start 154.399999 146.2025)
		(end 154.399999 147.277498)
		(width 0.201)
		(layer "F.Cu")
		(net 202)
	)
	(segment
		(start 149.375501 163.302)
		(end 149.875001 162.8025)
		(width 0.256)
		(layer "F.Cu")
		(net 202)
	)
	(via
		(at 154.399999 147.277498)
		(size 0.45)
		(drill 0.1)
		(layers "F.Cu" "B.Cu")
		(net 202)
	)
	(via
		(at 149.875001 162.8025)
		(size 0.45)
		(drill 0.1)
		(layers "F.Cu" "B.Cu")
		(net 202)
	)
	(segment
		(start 156.280304 157.840965)
		(end 156.280304 157.840964)
		(width 0.148)
		(layer "In6.Cu")
		(net 202)
	)
	(segment
		(start 153.891272 158.633908)
		(end 153.891271 158.633909)
		(width 0.148)
		(layer "In6.Cu")
		(net 202)
	)
	(segment
		(start 153.141246 160.358757)
		(end 153.141246 160.358754)
		(width 0.148)
		(layer "In6.Cu")
		(net 202)
	)
	(segment
		(start 155.305484 157.219696)
		(end 155.305483 157.219697)
		(width 0.148)
		(layer "In6.Cu")
		(net 202)
	)
	(segment
		(start 155.305483 157.573249)
		(end 155.305483 157.57325)
		(width 0.148)
		(layer "In6.Cu")
		(net 202)
	)
	(segment
		(start 154.399999 147.277498)
		(end 156.5 149.377499)
		(width 0.148)
		(layer "In6.Cu")
		(net 202)
	)
	(segment
		(start 154.158986 159.962282)
		(end 154.158984 159.962283)
		(width 0.148)
		(layer "In6.Cu")
		(net 202)
	)
	(segment
		(start 154.86609 159.255177)
		(end 154.555458 158.944545)
		(width 0.148)
		(layer "In6.Cu")
		(net 202)
	)
	(segment
		(start 152.25 161.25)
		(end 150.556615 161.25)
		(width 0.148)
		(layer "In6.Cu")
		(net 202)
	)
	(segment
		(start 153.805433 160.669387)
		(end 153.805432 160.669388)
		(width 0.148)
		(layer "In6.Cu")
		(net 202)
	)
	(segment
		(start 154.598377 158.280356)
		(end 155.219644 158.901622)
		(width 0.148)
		(layer "In6.Cu")
		(net 202)
	)
	(segment
		(start 152.477059 160.401673)
		(end 152.477059 160.401674)
		(width 0.148)
		(layer "In6.Cu")
		(net 202)
	)
	(segment
		(start 154.512539 159.962281)
		(end 154.512538 159.962282)
		(width 0.148)
		(layer "In6.Cu")
		(net 202)
	)
	(segment
		(start 152.610915 160.889083)
		(end 152.25 161.25)
		(width 0.148)
		(layer "In6.Cu")
		(net 202)
	)
	(segment
		(start 155.262564 158.237439)
		(end 155.262564 158.237436)
		(width 0.148)
		(layer "In6.Cu")
		(net 202)
	)
	(segment
		(start 156.5 157.353554)
		(end 156.633857 157.487411)
		(width 0.148)
		(layer "In6.Cu")
		(net 202)
	)
	(segment
		(start 154.158984 159.962283)
		(end 153.848352 159.651651)
		(width 0.148)
		(layer "In6.Cu")
		(net 202)
	)
	(segment
		(start 150.556615 161.25)
		(end 150.380501 161.426114)
		(width 0.148)
		(layer "In6.Cu")
		(net 202)
	)
	(segment
		(start 150.380501 162.297)
		(end 149.875001 162.8025)
		(width 0.148)
		(layer "In6.Cu")
		(net 202)
	)
	(segment
		(start 153.451878 160.669389)
		(end 153.141246 160.358757)
		(width 0.148)
		(layer "In6.Cu")
		(net 202)
	)
	(segment
		(start 153.891271 158.987462)
		(end 154.512538 159.608728)
		(width 0.148)
		(layer "In6.Cu")
		(net 202)
	)
	(segment
		(start 153.184165 159.694567)
		(end 153.184165 159.694568)
		(width 0.148)
		(layer "In6.Cu")
		(net 202)
	)
	(segment
		(start 154.598377 158.280355)
		(end 154.598377 158.280356)
		(width 0.148)
		(layer "In6.Cu")
		(net 202)
	)
	(segment
		(start 153.184165 159.694568)
		(end 153.805432 160.315834)
		(width 0.148)
		(layer "In6.Cu")
		(net 202)
	)
	(segment
		(start 154.555458 158.944545)
		(end 154.555458 158.944542)
		(width 0.148)
		(layer "In6.Cu")
		(net 202)
	)
	(segment
		(start 155.262564 158.237436)
		(end 154.951931 157.926803)
		(width 0.148)
		(layer "In6.Cu")
		(net 202)
	)
	(segment
		(start 152.610914 160.889083)
		(end 152.610915 160.889083)
		(width 0.148)
		(layer "In6.Cu")
		(net 202)
	)
	(segment
		(start 155.219645 159.255175)
		(end 155.219644 159.255176)
		(width 0.148)
		(layer "In6.Cu")
		(net 202)
	)
	(segment
		(start 150.380501 161.426114)
		(end 150.380501 162.297)
		(width 0.148)
		(layer "In6.Cu")
		(net 202)
	)
	(segment
		(start 154.555458 158.944542)
		(end 154.244825 158.633909)
		(width 0.148)
		(layer "In6.Cu")
		(net 202)
	)
	(segment
		(start 156.5 149.377499)
		(end 156.5 157)
		(width 0.148)
		(layer "In6.Cu")
		(net 202)
	)
	(segment
		(start 152.47706 160.04812)
		(end 152.477059 160.048121)
		(width 0.148)
		(layer "In6.Cu")
		(net 202)
	)
	(segment
		(start 156.633856 157.840964)
		(end 156.633856 157.840965)
		(width 0.148)
		(layer "In6.Cu")
		(net 202)
	)
	(segment
		(start 155.573196 158.548071)
		(end 155.262564 158.237439)
		(width 0.148)
		(layer "In6.Cu")
		(net 202)
	)
	(segment
		(start 156.280304 157.840964)
		(end 155.659037 157.219697)
		(width 0.148)
		(layer "In6.Cu")
		(net 202)
	)
	(segment
		(start 154.866092 159.255176)
		(end 154.86609 159.255177)
		(width 0.148)
		(layer "In6.Cu")
		(net 202)
	)
	(segment
		(start 155.573198 158.54807)
		(end 155.573196 158.548071)
		(width 0.148)
		(layer "In6.Cu")
		(net 202)
	)
	(segment
		(start 153.848352 159.651648)
		(end 153.537719 159.341015)
		(width 0.148)
		(layer "In6.Cu")
		(net 202)
	)
	(segment
		(start 152.477059 160.401674)
		(end 152.610915 160.53553)
		(width 0.148)
		(layer "In6.Cu")
		(net 202)
	)
	(segment
		(start 153.45188 160.669388)
		(end 153.451878 160.669389)
		(width 0.148)
		(layer "In6.Cu")
		(net 202)
	)
	(segment
		(start 155.305483 157.57325)
		(end 155.92675 158.194516)
		(width 0.148)
		(layer "In6.Cu")
		(net 202)
	)
	(segment
		(start 155.926751 158.548069)
		(end 155.92675 158.54807)
		(width 0.148)
		(layer "In6.Cu")
		(net 202)
	)
	(segment
		(start 154.598378 157.926802)
		(end 154.598377 157.926803)
		(width 0.148)
		(layer "In6.Cu")
		(net 202)
	)
	(segment
		(start 153.184166 159.341014)
		(end 153.184165 159.341015)
		(width 0.148)
		(layer "In6.Cu")
		(net 202)
	)
	(segment
		(start 153.141246 160.358754)
		(end 152.830613 160.048121)
		(width 0.148)
		(layer "In6.Cu")
		(net 202)
	)
	(segment
		(start 153.891271 158.987461)
		(end 153.891271 158.987462)
		(width 0.148)
		(layer "In6.Cu")
		(net 202)
	)
	(segment
		(start 153.848352 159.651651)
		(end 153.848352 159.651648)
		(width 0.148)
		(layer "In6.Cu")
		(net 202)
	)
	(arc
		(start 156.633857 157.487411)
		(mid 156.70708 157.664188)
		(end 156.633856 157.840964)
		(width 0.148)
		(layer "In6.Cu")
		(net 202)
	)
	(arc
		(start 153.891271 158.633909)
		(mid 153.818048 158.810685)
		(end 153.891271 158.987461)
		(width 0.148)
		(layer "In6.Cu")
		(net 202)
	)
	(arc
		(start 153.537719 159.341015)
		(mid 153.360943 159.267791)
		(end 153.184166 159.341014)
		(width 0.148)
		(layer "In6.Cu")
		(net 202)
	)
	(arc
		(start 152.830613 160.048121)
		(mid 152.653837 159.974897)
		(end 152.47706 160.04812)
		(width 0.148)
		(layer "In6.Cu")
		(net 202)
	)
	(arc
		(start 156.633856 157.840965)
		(mid 156.457081 157.914187)
		(end 156.280304 157.840965)
		(width 0.148)
		(layer "In6.Cu")
		(net 202)
	)
	(arc
		(start 152.477059 160.048121)
		(mid 152.403836 160.224897)
		(end 152.477059 160.401673)
		(width 0.148)
		(layer "In6.Cu")
		(net 202)
	)
	(arc
		(start 153.184165 159.341015)
		(mid 153.110942 159.517791)
		(end 153.184165 159.694567)
		(width 0.148)
		(layer "In6.Cu")
		(net 202)
	)
	(arc
		(start 154.951931 157.926803)
		(mid 154.775155 157.853579)
		(end 154.598378 157.926802)
		(width 0.148)
		(layer "In6.Cu")
		(net 202)
	)
	(arc
		(start 156.5 157)
		(mid 156.426777 157.176777)
		(end 156.5 157.353554)
		(width 0.148)
		(layer "In6.Cu")
		(net 202)
	)
	(arc
		(start 155.92675 158.54807)
		(mid 155.749973 158.621294)
		(end 155.573198 158.54807)
		(width 0.148)
		(layer "In6.Cu")
		(net 202)
	)
	(arc
		(start 152.610915 160.53553)
		(mid 152.684138 160.712307)
		(end 152.610914 160.889083)
		(width 0.148)
		(layer "In6.Cu")
		(net 202)
	)
	(arc
		(start 153.805432 160.669388)
		(mid 153.628655 160.742612)
		(end 153.45188 160.669388)
		(width 0.148)
		(layer "In6.Cu")
		(net 202)
	)
	(arc
		(start 155.92675 158.194516)
		(mid 155.999974 158.371292)
		(end 155.926751 158.548069)
		(width 0.148)
		(layer "In6.Cu")
		(net 202)
	)
	(arc
		(start 155.219644 158.901622)
		(mid 155.292868 159.078398)
		(end 155.219645 159.255175)
		(width 0.148)
		(layer "In6.Cu")
		(net 202)
	)
	(arc
		(start 155.305483 157.219697)
		(mid 155.23226 157.396473)
		(end 155.305483 157.573249)
		(width 0.148)
		(layer "In6.Cu")
		(net 202)
	)
	(arc
		(start 155.219644 159.255176)
		(mid 155.042867 159.3284)
		(end 154.866092 159.255176)
		(width 0.148)
		(layer "In6.Cu")
		(net 202)
	)
	(arc
		(start 154.598377 157.926803)
		(mid 154.525154 158.103579)
		(end 154.598377 158.280355)
		(width 0.148)
		(layer "In6.Cu")
		(net 202)
	)
	(arc
		(start 154.244825 158.633909)
		(mid 154.068049 158.560685)
		(end 153.891272 158.633908)
		(width 0.148)
		(layer "In6.Cu")
		(net 202)
	)
	(arc
		(start 154.512538 159.962282)
		(mid 154.335761 160.035506)
		(end 154.158986 159.962282)
		(width 0.148)
		(layer "In6.Cu")
		(net 202)
	)
	(arc
		(start 153.805432 160.315834)
		(mid 153.878656 160.49261)
		(end 153.805433 160.669387)
		(width 0.148)
		(layer "In6.Cu")
		(net 202)
	)
	(arc
		(start 154.512538 159.608728)
		(mid 154.585762 159.785504)
		(end 154.512539 159.962281)
		(width 0.148)
		(layer "In6.Cu")
		(net 202)
	)
	(arc
		(start 155.659037 157.219697)
		(mid 155.482261 157.146473)
		(end 155.305484 157.219696)
		(width 0.148)
		(layer "In6.Cu")
		(net 202)
	)
	(segment
		(start 154.650001 139.4025)
		(end 154.670001 139.4225)
		(width 0.26)
		(layer "F.Cu")
		(net 203)
	)
	(segment
		(start 154.650001 138.8025)
		(end 154.650001 139.4025)
		(width 0.26)
		(layer "F.Cu")
		(net 203)
	)
	(segment
		(start 154.67 139.892427)
		(end 154.625001 139.937426)
		(width 0.26)
		(layer "F.Cu")
		(net 203)
	)
	(segment
		(start 154.670001 139.4225)
		(end 154.67 139.892427)
		(width 0.26)
		(layer "F.Cu")
		(net 203)
	)
	(segment
		(start 148.375501 162.302)
		(end 148.875001 161.8025)
		(width 0.256)
		(layer "F.Cu")
		(net 203)
	)
	(via
		(at 154.625001 139.937426)
		(size 0.45)
		(drill 0.1)
		(layers "F.Cu" "B.Cu")
		(net 203)
	)
	(via
		(at 148.875001 161.8025)
		(size 0.45)
		(drill 0.1)
		(layers "F.Cu" "B.Cu")
		(net 203)
	)
	(segment
		(start 154.758732 141.53)
		(end 154.68 141.53)
		(width 0.1)
		(layer "In6.Cu")
		(net 203)
	)
	(segment
		(start 154.725 142.845)
		(end 156.359965 142.845)
		(width 0.1)
		(layer "In6.Cu")
		(net 203)
	)
	(segment
		(start 156.359965 143.705)
		(end 154.725 143.705)
		(width 0.1)
		(layer "In6.Cu")
		(net 203)
	)
	(segment
		(start 154.758732 142.23)
		(end 154.68 142.23)
		(width 0.1)
		(layer "In6.Cu")
		(net 203)
	)
	(segment
		(start 154.558161 139.245)
		(end 154.293494 139.245)
		(width 0.1)
		(layer "In6.Cu")
		(net 203)
	)
	(segment
		(start 154.022935 148.103229)
		(end 154.022935 148.006608)
		(width 0.13)
		(layer "In6.Cu")
		(net 203)
	)
	(segment
		(start 154.293494 139.245)
		(end 154.135 139.403494)
		(width 0.1)
		(layer "In6.Cu")
		(net 203)
	)
	(segment
		(start 149.050207 160.696)
		(end 151.063706 160.696)
		(width 0.13)
		(layer "In6.Cu")
		(net 203)
	)
	(segment
		(start 148.495001 161.251206)
		(end 149.050207 160.696)
		(width 0.13)
		(layer "In6.Cu")
		(net 203)
	)
	(segment
		(start 154.005 146.443494)
		(end 154.005 147.988673)
		(width 0.1)
		(layer "In6.Cu")
		(net 203)
	)
	(segment
		(start 154.505 143.925)
		(end 154.505 145.943494)
		(width 0.1)
		(layer "In6.Cu")
		(net 203)
	)
	(segment
		(start 154.795001 139.767426)
		(end 154.795001 139.48184)
		(width 0.1)
		(layer "In6.Cu")
		(net 203)
	)
	(segment
		(start 154.505 142.405)
		(end 154.505 142.625)
		(width 0.1)
		(layer "In6.Cu")
		(net 203)
	)
	(segment
		(start 154.005 147.988673)
		(end 154.022935 148.006608)
		(width 0.1)
		(layer "In6.Cu")
		(net 203)
	)
	(segment
		(start 154.505 145.943494)
		(end 154.005 146.443494)
		(width 0.1)
		(layer "In6.Cu")
		(net 203)
	)
	(segment
		(start 155.62 149.700294)
		(end 154.022935 148.103229)
		(width 0.13)
		(layer "In6.Cu")
		(net 203)
	)
	(segment
		(start 151.063706 160.696)
		(end 155.62 156.139706)
		(width 0.13)
		(layer "In6.Cu")
		(net 203)
	)
	(segment
		(start 154.68 141.18)
		(end 154.758732 141.18)
		(width 0.1)
		(layer "In6.Cu")
		(net 203)
	)
	(segment
		(start 155.62 156.139706)
		(end 155.62 149.700294)
		(width 0.13)
		(layer "In6.Cu")
		(net 203)
	)
	(segment
		(start 148.577001 161.8025)
		(end 148.495001 161.7205)
		(width 0.13)
		(layer "In6.Cu")
		(net 203)
	)
	(segment
		(start 148.495001 161.7205)
		(end 148.495001 161.251206)
		(width 0.13)
		(layer "In6.Cu")
		(net 203)
	)
	(segment
		(start 154.135 139.403494)
		(end 154.135 140.516506)
		(width 0.1)
		(layer "In6.Cu")
		(net 203)
	)
	(segment
		(start 148.875001 161.8025)
		(end 148.577001 161.8025)
		(width 0.13)
		(layer "In6.Cu")
		(net 203)
	)
	(segment
		(start 154.135 140.516506)
		(end 154.505 140.886506)
		(width 0.1)
		(layer "In6.Cu")
		(net 203)
	)
	(segment
		(start 154.505 140.886506)
		(end 154.505 141.005)
		(width 0.1)
		(layer "In6.Cu")
		(net 203)
	)
	(segment
		(start 154.68 141.88)
		(end 154.758732 141.88)
		(width 0.1)
		(layer "In6.Cu")
		(net 203)
	)
	(segment
		(start 154.625001 139.937426)
		(end 154.795001 139.767426)
		(width 0.1)
		(layer "In6.Cu")
		(net 203)
	)
	(segment
		(start 154.795001 139.48184)
		(end 154.558161 139.245)
		(width 0.1)
		(layer "In6.Cu")
		(net 203)
	)
	(arc
		(start 154.505 142.625)
		(mid 154.569437 142.780563)
		(end 154.725 142.845)
		(width 0.1)
		(layer "In6.Cu")
		(net 203)
	)
	(arc
		(start 154.933732 141.355)
		(mid 154.882476 141.478744)
		(end 154.758732 141.53)
		(width 0.1)
		(layer "In6.Cu")
		(net 203)
	)
	(arc
		(start 156.359965 142.845)
		(mid 156.664021 142.970944)
		(end 156.789965 143.275)
		(width 0.1)
		(layer "In6.Cu")
		(net 203)
	)
	(arc
		(start 154.758732 141.18)
		(mid 154.882476 141.231256)
		(end 154.933732 141.355)
		(width 0.1)
		(layer "In6.Cu")
		(net 203)
	)
	(arc
		(start 154.758732 141.88)
		(mid 154.882476 141.931256)
		(end 154.933732 142.055)
		(width 0.1)
		(layer "In6.Cu")
		(net 203)
	)
	(arc
		(start 154.505 141.705)
		(mid 154.556256 141.828744)
		(end 154.68 141.88)
		(width 0.1)
		(layer "In6.Cu")
		(net 203)
	)
	(arc
		(start 154.505 141.005)
		(mid 154.556256 141.128744)
		(end 154.68 141.18)
		(width 0.1)
		(layer "In6.Cu")
		(net 203)
	)
	(arc
		(start 154.68 141.53)
		(mid 154.556256 141.581256)
		(end 154.505 141.705)
		(width 0.1)
		(layer "In6.Cu")
		(net 203)
	)
	(arc
		(start 154.68 142.23)
		(mid 154.556256 142.281256)
		(end 154.505 142.405)
		(width 0.1)
		(layer "In6.Cu")
		(net 203)
	)
	(arc
		(start 154.933732 142.055)
		(mid 154.882476 142.178744)
		(end 154.758732 142.23)
		(width 0.1)
		(layer "In6.Cu")
		(net 203)
	)
	(arc
		(start 156.789965 143.275)
		(mid 156.664021 143.579056)
		(end 156.359965 143.705)
		(width 0.1)
		(layer "In6.Cu")
		(net 203)
	)
	(arc
		(start 154.725 143.705)
		(mid 154.569437 143.769437)
		(end 154.505 143.925)
		(width 0.1)
		(layer "In6.Cu")
		(net 203)
	)
	(segment
		(start 155.150001 138.8025)
		(end 155.150001 139.4025)
		(width 0.26)
		(layer "F.Cu")
		(net 204)
	)
	(segment
		(start 155.150001 139.4025)
		(end 155.130001 139.4225)
		(width 0.26)
		(layer "F.Cu")
		(net 204)
	)
	(segment
		(start 155.130002 139.892427)
		(end 155.175001 139.937426)
		(width 0.26)
		(layer "F.Cu")
		(net 204)
	)
	(segment
		(start 147.3755 162.302)
		(end 147.875001 161.8025)
		(width 0.256)
		(layer "F.Cu")
		(net 204)
	)
	(segment
		(start 155.130001 139.4225)
		(end 155.130002 139.892427)
		(width 0.26)
		(layer "F.Cu")
		(net 204)
	)
	(via
		(at 147.875001 161.8025)
		(size 0.45)
		(drill 0.1)
		(layers "F.Cu" "B.Cu")
		(net 204)
	)
	(via
		(at 155.175001 139.937426)
		(size 0.45)
		(drill 0.1)
		(layers "F.Cu" "B.Cu")
		(net 204)
	)
	(segment
		(start 153.925 140.603494)
		(end 154.295 140.973494)
		(width 0.1)
		(layer "In6.Cu")
		(net 204)
	)
	(segment
		(start 155.005001 139.394852)
		(end 154.645149 139.035)
		(width 0.1)
		(layer "In6.Cu")
		(net 204)
	)
	(segment
		(start 154.295 140.973494)
		(end 154.295 142.625)
		(width 0.1)
		(layer "In6.Cu")
		(net 204)
	)
	(segment
		(start 155.005001 139.767426)
		(end 155.005001 139.394852)
		(width 0.1)
		(layer "In6.Cu")
		(net 204)
	)
	(segment
		(start 153.795 146.356506)
		(end 153.795 147.994543)
		(width 0.1)
		(layer "In6.Cu")
		(net 204)
	)
	(segment
		(start 155.38 149.799706)
		(end 153.782935 148.202641)
		(width 0.13)
		(layer "In6.Cu")
		(net 204)
	)
	(segment
		(start 155.175001 139.937426)
		(end 155.005001 139.767426)
		(width 0.1)
		(layer "In6.Cu")
		(net 204)
	)
	(segment
		(start 147.875001 161.8025)
		(end 148.174001 161.8025)
		(width 0.13)
		(layer "In6.Cu")
		(net 204)
	)
	(segment
		(start 153.925 139.316506)
		(end 153.925 140.603494)
		(width 0.1)
		(layer "In6.Cu")
		(net 204)
	)
	(segment
		(start 154.295 143.925)
		(end 154.295 145.856506)
		(width 0.1)
		(layer "In6.Cu")
		(net 204)
	)
	(segment
		(start 154.206506 139.035)
		(end 153.925 139.316506)
		(width 0.1)
		(layer "In6.Cu")
		(net 204)
	)
	(segment
		(start 155.38 156.040294)
		(end 155.38 149.799706)
		(width 0.13)
		(layer "In6.Cu")
		(net 204)
	)
	(segment
		(start 153.795 147.994543)
		(end 153.782935 148.006608)
		(width 0.1)
		(layer "In6.Cu")
		(net 204)
	)
	(segment
		(start 148.255001 161.7215)
		(end 148.255001 161.151794)
		(width 0.13)
		(layer "In6.Cu")
		(net 204)
	)
	(segment
		(start 154.645149 139.035)
		(end 154.206506 139.035)
		(width 0.1)
		(layer "In6.Cu")
		(net 204)
	)
	(segment
		(start 156.359965 143.495)
		(end 154.725 143.495)
		(width 0.1)
		(layer "In6.Cu")
		(net 204)
	)
	(segment
		(start 150.964294 160.456)
		(end 155.38 156.040294)
		(width 0.13)
		(layer "In6.Cu")
		(net 204)
	)
	(segment
		(start 154.295 145.856506)
		(end 153.795 146.356506)
		(width 0.1)
		(layer "In6.Cu")
		(net 204)
	)
	(segment
		(start 148.255001 161.151794)
		(end 148.950795 160.456)
		(width 0.13)
		(layer "In6.Cu")
		(net 204)
	)
	(segment
		(start 154.725 143.055)
		(end 156.359965 143.055)
		(width 0.1)
		(layer "In6.Cu")
		(net 204)
	)
	(segment
		(start 148.174001 161.8025)
		(end 148.255001 161.7215)
		(width 0.13)
		(layer "In6.Cu")
		(net 204)
	)
	(segment
		(start 148.950795 160.456)
		(end 150.964294 160.456)
		(width 0.13)
		(layer "In6.Cu")
		(net 204)
	)
	(segment
		(start 153.782935 148.202641)
		(end 153.782935 148.006608)
		(width 0.13)
		(layer "In6.Cu")
		(net 204)
	)
	(arc
		(start 156.359965 143.055)
		(mid 156.515528 143.119437)
		(end 156.579965 143.275)
		(width 0.1)
		(layer "In6.Cu")
		(net 204)
	)
	(arc
		(start 154.725 143.495)
		(mid 154.420944 143.620944)
		(end 154.295 143.925)
		(width 0.1)
		(layer "In6.Cu")
		(net 204)
	)
	(arc
		(start 156.579965 143.275)
		(mid 156.515528 143.430563)
		(end 156.359965 143.495)
		(width 0.1)
		(layer "In6.Cu")
		(net 204)
	)
	(arc
		(start 154.295 142.625)
		(mid 154.420944 142.929056)
		(end 154.725 143.055)
		(width 0.1)
		(layer "In6.Cu")
		(net 204)
	)
	(segment
		(start 155.4 146.2025)
		(end 155.4 147.2775)
		(width 0.201)
		(layer "F.Cu")
		(net 205)
	)
	(segment
		(start 150.375501 162.302)
		(end 150.875001 161.8025)
		(width 0.256)
		(layer "F.Cu")
		(net 205)
	)
	(via
		(at 150.875001 161.8025)
		(size 0.45)
		(drill 0.1)
		(layers "F.Cu" "B.Cu")
		(net 205)
	)
	(via
		(at 155.4 147.2775)
		(size 0.45)
		(drill 0.1)
		(layers "F.Cu" "B.Cu")
		(net 205)
	)
	(segment
		(start 157.838855 150.75)
		(end 157.75 150.75)
		(width 0.148)
		(layer "In6.Cu")
		(net 205)
	)
	(segment
		(start 157.5 149.3775)
		(end 155.4 147.2775)
		(width 0.148)
		(layer "In6.Cu")
		(net 205)
	)
	(segment
		(start 157.5 157.6)
		(end 157.5 157)
		(width 0.148)
		(layer "In6.Cu")
		(net 205)
	)
	(segment
		(start 151.358501 162.286)
		(end 152.814 162.286)
		(width 0.148)
		(layer "In6.Cu")
		(net 205)
	)
	(segment
		(start 157.161145 153.75)
		(end 157.838855 153.75)
		(width 0.148)
		(layer "In6.Cu")
		(net 205)
	)
	(segment
		(start 150.875001 161.8025)
		(end 151.358501 162.286)
		(width 0.148)
		(layer "In6.Cu")
		(net 205)
	)
	(segment
		(start 157.161145 154.25)
		(end 157.838855 154.25)
		(width 0.148)
		(layer "In6.Cu")
		(net 205)
	)
	(segment
		(start 157.161145 155.75)
		(end 157.838855 155.75)
		(width 0.148)
		(layer "In6.Cu")
		(net 205)
	)
	(segment
		(start 157.25 156.75)
		(end 157.161145 156.75)
		(width 0.148)
		(layer "In6.Cu")
		(net 205)
	)
	(segment
		(start 157.161145 156.25)
		(end 157.25 156.25)
		(width 0.148)
		(layer "In6.Cu")
		(net 205)
	)
	(segment
		(start 157.161145 154.75)
		(end 157.838855 154.75)
		(width 0.148)
		(layer "In6.Cu")
		(net 205)
	)
	(segment
		(start 157.161145 153.25)
		(end 157.838855 153.25)
		(width 0.148)
		(layer "In6.Cu")
		(net 205)
	)
	(segment
		(start 157.25 156.25)
		(end 157.838855 156.25)
		(width 0.148)
		(layer "In6.Cu")
		(net 205)
	)
	(segment
		(start 152.814 162.286)
		(end 157.5 157.6)
		(width 0.148)
		(layer "In6.Cu")
		(net 205)
	)
	(segment
		(start 157.161145 152.75)
		(end 157.838855 152.75)
		(width 0.148)
		(layer "In6.Cu")
		(net 205)
	)
	(segment
		(start 157.161145 155.25)
		(end 157.838855 155.25)
		(width 0.148)
		(layer "In6.Cu")
		(net 205)
	)
	(segment
		(start 157.5 150.5)
		(end 157.5 149.3775)
		(width 0.148)
		(layer "In6.Cu")
		(net 205)
	)
	(segment
		(start 157.161145 151.75)
		(end 157.838855 151.75)
		(width 0.148)
		(layer "In6.Cu")
		(net 205)
	)
	(segment
		(start 157.161145 152.25)
		(end 157.838855 152.25)
		(width 0.148)
		(layer "In6.Cu")
		(net 205)
	)
	(segment
		(start 157.161145 151.25)
		(end 157.838855 151.25)
		(width 0.148)
		(layer "In6.Cu")
		(net 205)
	)
	(arc
		(start 157.838855 156.25)
		(mid 158.015632 156.176777)
		(end 158.088855 156)
		(width 0.148)
		(layer "In6.Cu")
		(net 205)
	)
	(arc
		(start 158.088855 151)
		(mid 158.015632 150.823223)
		(end 157.838855 150.75)
		(width 0.148)
		(layer "In6.Cu")
		(net 205)
	)
	(arc
		(start 157.838855 152.25)
		(mid 158.015632 152.176777)
		(end 158.088855 152)
		(width 0.148)
		(layer "In6.Cu")
		(net 205)
	)
	(arc
		(start 157.5 157)
		(mid 157.426777 156.823223)
		(end 157.25 156.75)
		(width 0.148)
		(layer "In6.Cu")
		(net 205)
	)
	(arc
		(start 156.911145 154.5)
		(mid 156.984368 154.323223)
		(end 157.161145 154.25)
		(width 0.148)
		(layer "In6.Cu")
		(net 205)
	)
	(arc
		(start 158.088855 155)
		(mid 158.015632 154.823223)
		(end 157.838855 154.75)
		(width 0.148)
		(layer "In6.Cu")
		(net 205)
	)
	(arc
		(start 158.088855 152)
		(mid 158.015632 151.823223)
		(end 157.838855 151.75)
		(width 0.148)
		(layer "In6.Cu")
		(net 205)
	)
	(arc
		(start 157.161145 155.75)
		(mid 156.984368 155.676777)
		(end 156.911145 155.5)
		(width 0.148)
		(layer "In6.Cu")
		(net 205)
	)
	(arc
		(start 156.911145 156.5)
		(mid 156.984368 156.323223)
		(end 157.161145 156.25)
		(width 0.148)
		(layer "In6.Cu")
		(net 205)
	)
	(arc
		(start 156.911145 153.5)
		(mid 156.984368 153.323223)
		(end 157.161145 153.25)
		(width 0.148)
		(layer "In6.Cu")
		(net 205)
	)
	(arc
		(start 157.161145 151.75)
		(mid 156.984368 151.676777)
		(end 156.911145 151.5)
		(width 0.148)
		(layer "In6.Cu")
		(net 205)
	)
	(arc
		(start 158.088855 153)
		(mid 158.015632 152.823223)
		(end 157.838855 152.75)
		(width 0.148)
		(layer "In6.Cu")
		(net 205)
	)
	(arc
		(start 158.088855 156)
		(mid 158.015632 155.823223)
		(end 157.838855 155.75)
		(width 0.148)
		(layer "In6.Cu")
		(net 205)
	)
	(arc
		(start 157.75 150.75)
		(mid 157.573223 150.676777)
		(end 157.5 150.5)
		(width 0.148)
		(layer "In6.Cu")
		(net 205)
	)
	(arc
		(start 157.161145 156.75)
		(mid 156.984368 156.676777)
		(end 156.911145 156.5)
		(width 0.148)
		(layer "In6.Cu")
		(net 205)
	)
	(arc
		(start 156.911145 155.5)
		(mid 156.984368 155.323223)
		(end 157.161145 155.25)
		(width 0.148)
		(layer "In6.Cu")
		(net 205)
	)
	(arc
		(start 157.838855 153.25)
		(mid 158.015632 153.176777)
		(end 158.088855 153)
		(width 0.148)
		(layer "In6.Cu")
		(net 205)
	)
	(arc
		(start 156.911145 151.5)
		(mid 156.984368 151.323223)
		(end 157.161145 151.25)
		(width 0.148)
		(layer "In6.Cu")
		(net 205)
	)
	(arc
		(start 157.838855 154.25)
		(mid 158.015632 154.176777)
		(end 158.088855 154)
		(width 0.148)
		(layer "In6.Cu")
		(net 205)
	)
	(arc
		(start 157.161145 152.75)
		(mid 156.984368 152.676777)
		(end 156.911145 152.5)
		(width 0.148)
		(layer "In6.Cu")
		(net 205)
	)
	(arc
		(start 157.838855 151.25)
		(mid 158.015632 151.176777)
		(end 158.088855 151)
		(width 0.148)
		(layer "In6.Cu")
		(net 205)
	)
	(arc
		(start 158.088855 154)
		(mid 158.015632 153.823223)
		(end 157.838855 153.75)
		(width 0.148)
		(layer "In6.Cu")
		(net 205)
	)
	(arc
		(start 157.838855 155.25)
		(mid 158.015632 155.176777)
		(end 158.088855 155)
		(width 0.148)
		(layer "In6.Cu")
		(net 205)
	)
	(arc
		(start 157.161145 153.75)
		(mid 156.984368 153.676777)
		(end 156.911145 153.5)
		(width 0.148)
		(layer "In6.Cu")
		(net 205)
	)
	(arc
		(start 156.911145 152.5)
		(mid 156.984368 152.323223)
		(end 157.161145 152.25)
		(width 0.148)
		(layer "In6.Cu")
		(net 205)
	)
	(arc
		(start 157.161145 154.75)
		(mid 156.984368 154.676777)
		(end 156.911145 154.5)
		(width 0.148)
		(layer "In6.Cu")
		(net 205)
	)
	(segment
		(start 138.376501 168.302)
		(end 137.877002 167.8025)
		(width 0.256)
		(layer "F.Cu")
		(net 206)
	)
	(segment
		(start 182.05 155.074999)
		(end 182.05 155.7)
		(width 0.256)
		(layer "F.Cu")
		(net 206)
	)
	(segment
		(start 149.375501 171.302)
		(end 149.875001 170.8025)
		(width 0.256)
		(layer "F.Cu")
		(net 206)
	)
	(segment
		(start 182.05 155.074999)
		(end 182.724999 155.074999)
		(width 0.256)
		(layer "F.Cu")
		(net 206)
	)
	(segment
		(start 148.375501 168.302)
		(end 148.875001 167.8025)
		(width 0.256)
		(layer "F.Cu")
		(net 206)
	)
	(segment
		(start 136.376501 162.302)
		(end 135.877001 161.8025)
		(width 0.256)
		(layer "F.Cu")
		(net 206)
	)
	(segment
		(start 181.889 153.889)
		(end 182.05 154.05)
		(width 0.256)
		(layer "F.Cu")
		(net 206)
	)
	(segment
		(start 144.375501 166.302)
		(end 144.875001 165.8025)
		(width 0.256)
		(layer "F.Cu")
		(net 206)
	)
	(segment
		(start 134.376501 166.302)
		(end 133.877001 165.8025)
		(width 0.256)
		(layer "F.Cu")
		(net 206)
	)
	(segment
		(start 142.375501 170.302)
		(end 142.875001 169.8025)
		(width 0.256)
		(layer "F.Cu")
		(net 206)
	)
	(segment
		(start 182.05 154.05)
		(end 182.05 155.074999)
		(width 0.256)
		(layer "F.Cu")
		(net 206)
	)
	(segment
		(start 145.375501 169.302)
		(end 145.875001 168.8025)
		(width 0.256)
		(layer "F.Cu")
		(net 206)
	)
	(segment
		(start 182.724999 155.074999)
		(end 182.75 155.1)
		(width 0.256)
		(layer "F.Cu")
		(net 206)
	)
	(segment
		(start 140.375501 164.302001)
		(end 140.875001 163.8025)
		(width 0.256)
		(layer "F.Cu")
		(net 206)
	)
	(segment
		(start 146.375502 162.302)
		(end 146.875001 161.8025)
		(width 0.256)
		(layer "F.Cu")
		(net 206)
	)
	(segment
		(start 181.889 152.926)
		(end 181.889 153.889)
		(width 0.256)
		(layer "F.Cu")
		(net 206)
	)
	(segment
		(start 150.375501 164.302)
		(end 150.875001 163.8025)
		(width 0.256)
		(layer "F.Cu")
		(net 206)
	)
	(segment
		(start 137.376501 165.302)
		(end 136.877001 164.8025)
		(width 0.256)
		(layer "F.Cu")
		(net 206)
	)
	(segment
		(start 133.376501 163.302)
		(end 132.877001 162.8025)
		(width 0.256)
		(layer "F.Cu")
		(net 206)
	)
	(segment
		(start 147.375501 165.302)
		(end 147.875001 164.8025)
		(width 0.256)
		(layer "F.Cu")
		(net 206)
	)
	(segment
		(start 151.375501 167.301999)
		(end 151.875001 166.8025)
		(width 0.256)
		(layer "F.Cu")
		(net 206)
	)
	(segment
		(start 143.375501 163.302)
		(end 143.875001 162.8025)
		(width 0.256)
		(layer "F.Cu")
		(net 206)
	)
	(segment
		(start 135.376502 169.302)
		(end 134.877001 168.8025)
		(width 0.256)
		(layer "F.Cu")
		(net 206)
	)
	(segment
		(start 141.375501 167.302)
		(end 141.875001 166.802501)
		(width 0.256)
		(layer "F.Cu")
		(net 206)
	)
	(via
		(at 141.875001 166.802501)
		(size 0.45)
		(drill 0.1)
		(layers "F.Cu" "B.Cu")
		(net 206)
	)
	(via
		(at 144.875001 165.8025)
		(size 0.45)
		(drill 0.1)
		(layers "F.Cu" "B.Cu")
		(net 206)
	)
	(via
		(at 132.877001 162.8025)
		(size 0.45)
		(drill 0.1)
		(layers "F.Cu" "B.Cu")
		(net 206)
	)
	(via
		(at 182.05 155.7)
		(size 0.45)
		(drill 0.1)
		(layers "F.Cu" "B.Cu")
		(net 206)
	)
	(via
		(at 135.877001 161.8025)
		(size 0.45)
		(drill 0.1)
		(layers "F.Cu" "B.Cu")
		(net 206)
	)
	(via
		(at 189.525 160.375)
		(size 0.45)
		(drill 0.1)
		(layers "F.Cu" "B.Cu")
		(net 206)
	)
	(via
		(at 149.875001 170.8025)
		(size 0.45)
		(drill 0.1)
		(layers "F.Cu" "B.Cu")
		(net 206)
	)
	(via
		(at 188.675 159.7)
		(size 0.45)
		(drill 0.1)
		(layers "F.Cu" "B.Cu")
		(net 206)
	)
	(via
		(at 150.875001 163.8025)
		(size 0.45)
		(drill 0.1)
		(layers "F.Cu" "B.Cu")
		(net 206)
	)
	(via
		(at 158.109 142.884)
		(size 0.45)
		(drill 0.1)
		(layers "F.Cu" "B.Cu")
		(net 206)
	)
	(via
		(at 142.875001 169.8025)
		(size 0.45)
		(drill 0.1)
		(layers "F.Cu" "B.Cu")
		(net 206)
	)
	(via
		(at 143.875001 162.8025)
		(size 0.45)
		(drill 0.1)
		(layers "F.Cu" "B.Cu")
		(net 206)
	)
	(via
		(at 136.877001 164.8025)
		(size 0.45)
		(drill 0.1)
		(layers "F.Cu" "B.Cu")
		(net 206)
	)
	(via
		(at 145.875001 168.8025)
		(size 0.45)
		(drill 0.1)
		(layers "F.Cu" "B.Cu")
		(net 206)
	)
	(via
		(at 138.877001 167.8025)
		(size 0.45)
		(drill 0.1)
		(layers "F.Cu" "B.Cu")
		(free yes)
		(net 206)
	)
	(via
		(at 134.877001 168.8025)
		(size 0.45)
		(drill 0.1)
		(layers "F.Cu" "B.Cu")
		(net 206)
	)
	(via
		(at 151.8 143.3)
		(size 0.45)
		(drill 0.1)
		(layers "F.Cu" "B.Cu")
		(net 206)
	)
	(via
		(at 190.9 159.05)
		(size 0.45)
		(drill 0.1)
		(layers "F.Cu" "B.Cu")
		(net 206)
	)
	(via
		(at 140.875001 163.8025)
		(size 0.45)
		(drill 0.1)
		(layers "F.Cu" "B.Cu")
		(net 206)
	)
	(via
		(at 182.75 155.1)
		(size 0.45)
		(drill 0.1)
		(layers "F.Cu" "B.Cu")
		(net 206)
	)
	(via
		(at 137.877002 167.8025)
		(size 0.45)
		(drill 0.1)
		(layers "F.Cu" "B.Cu")
		(net 206)
	)
	(via
		(at 189.525 159.05)
		(size 0.45)
		(drill 0.1)
		(layers "F.Cu" "B.Cu")
		(net 206)
	)
	(via
		(at 187.2755 159)
		(size 0.45)
		(drill 0.1)
		(layers "F.Cu" "B.Cu")
		(net 206)
	)
	(via
		(at 190.9 160.375)
		(size 0.45)
		(drill 0.1)
		(layers "F.Cu" "B.Cu")
		(net 206)
	)
	(via
		(at 189.925 159.7)
		(size 0.45)
		(drill 0.1)
		(layers "F.Cu" "B.Cu")
		(net 206)
	)
	(via
		(at 151.875001 166.8025)
		(size 0.45)
		(drill 0.1)
		(layers "F.Cu" "B.Cu")
		(net 206)
	)
	(via
		(at 148.875001 167.8025)
		(size 0.45)
		(drill 0.1)
		(layers "F.Cu" "B.Cu")
		(net 206)
	)
	(via
		(at 132.55 143.4)
		(size 0.45)
		(drill 0.1)
		(layers "F.Cu" "B.Cu")
		(net 206)
	)
	(via
		(at 188.35 160.375)
		(size 0.45)
		(drill 0.1)
		(layers "F.Cu" "B.Cu")
		(net 206)
	)
	(via
		(at 188.35 159.05)
		(size 0.45)
		(drill 0.1)
		(layers "F.Cu" "B.Cu")
		(net 206)
	)
	(via
		(at 147.875001 164.8025)
		(size 0.45)
		(drill 0.1)
		(layers "F.Cu" "B.Cu")
		(net 206)
	)
	(via
		(at 133.877001 165.8025)
		(size 0.45)
		(drill 0.1)
		(layers "F.Cu" "B.Cu")
		(net 206)
	)
	(via
		(at 146.875001 161.8025)
		(size 0.45)
		(drill 0.1)
		(layers "F.Cu" "B.Cu")
		(net 206)
	)
	(segment
		(start 138.877001 168.2025)
		(end 138.877001 167.8025)
		(width 0.4)
		(layer "B.Cu")
		(net 206)
	)
	(segment
		(start 151 142.884)
		(end 151.084 142.884)
		(width 0.256)
		(layer "B.Cu")
		(net 206)
	)
	(segment
		(start 145.375501 169.303)
		(end 145.375501 169.302)
		(width 0.4)
		(layer "B.Cu")
		(net 206)
	)
	(segment
		(start 138.477001 167.8025)
		(end 138.877001 168.2025)
		(width 0.4)
		(layer "B.Cu")
		(net 206)
	)
	(segment
		(start 138.177001 167.8025)
		(end 137.877002 167.8025)
		(width 0.4)
		(layer "B.Cu")
		(net 206)
	)
	(segment
		(start 134.375501 169.304)
		(end 134.877001 168.8025)
		(width 0.4)
		(layer "B.Cu")
		(net 206)
	)
	(segment
		(start 186.94 159.3355)
		(end 187.2755 159)
		(width 0.15)
		(layer "B.Cu")
		(net 206)
	)
	(segment
		(start 152.475001 166.8025)
		(end 151.875001 166.8025)
		(width 0.4)
		(layer "B.Cu")
		(net 206)
	)
	(segment
		(start 142.377501 167.301)
		(end 142.3735 167.301)
		(width 0.4)
		(layer "B.Cu")
		(net 206)
	)
	(segment
		(start 144.373501 165.301)
		(end 144.875001 165.8025)
		(width 0.4)
		(layer "B.Cu")
		(net 206)
	)
	(segment
		(start 147.373501 164.301)
		(end 147.875001 164.8025)
		(width 0.4)
		(layer "B.Cu")
		(net 206)
	)
	(segment
		(start 142.3735 167.301)
		(end 141.875001 166.802501)
		(width 0.4)
		(layer "B.Cu")
		(net 206)
	)
	(segment
		(start 146.875001 161.8025)
		(end 146.879001 161.8025)
		(width 0.4)
		(layer "B.Cu")
		(net 206)
	)
	(segment
		(start 137.376502 168.303)
		(end 137.877002 167.8025)
		(width 0.4)
		(layer "B.Cu")
		(net 206)
	)
	(segment
		(start 132.05 142.9)
		(end 132.55 143.4)
		(width 0.256)
		(layer "B.Cu")
		(net 206)
	)
	(segment
		(start 151.084 142.884)
		(end 151.5 143.3)
		(width 0.256)
		(layer "B.Cu")
		(net 206)
	)
	(segment
		(start 136.375501 162.301)
		(end 135.877001 161.8025)
		(width 0.4)
		(layer "B.Cu")
		(net 206)
	)
	(segment
		(start 136.177501 160.8)
		(end 136.075001 160.9025)
		(width 0.4)
		(layer "B.Cu")
		(net 206)
	)
	(segment
		(start 143.375001 170.3025)
		(end 142.875001 169.8025)
		(width 0.256)
		(layer "B.Cu")
		(net 206)
	)
	(segment
		(start 150.375501 170.302)
		(end 149.875001 170.8025)
		(width 0.4)
		(layer "B.Cu")
		(net 206)
	)
	(segment
		(start 136.075001 160.9025)
		(end 135.875001 161.1025)
		(width 0.4)
		(layer "B.Cu")
		(net 206)
	)
	(segment
		(start 136.375501 165.303)
		(end 136.376501 165.303)
		(width 0.4)
		(layer "B.Cu")
		(net 206)
	)
	(segment
		(start 140.875001 163.8025)
		(end 140.875001 163.8035)
		(width 0.4)
		(layer "B.Cu")
		(net 206)
	)
	(segment
		(start 133.377501 163.301)
		(end 133.375501 163.301)
		(width 0.4)
		(layer "B.Cu")
		(net 206)
	)
	(segment
		(start 138.877001 168.7025)
		(end 138.877001 168.2025)
		(width 0.4)
		(layer "B.Cu")
		(net 206)
	)
	(segment
		(start 143.875001 162.8025)
		(end 143.373501 162.301)
		(width 0.4)
		(layer "B.Cu")
		(net 206)
	)
	(segment
		(start 140.875001 163.8035)
		(end 140.375501 164.303)
		(width 0.4)
		(layer "B.Cu")
		(net 206)
	)
	(segment
		(start 135.875001 161.1025)
		(end 135.875001 161.8005)
		(width 0.4)
		(layer "B.Cu")
		(net 206)
	)
	(segment
		(start 145.375501 169.302)
		(end 145.875001 168.8025)
		(width 0.4)
		(layer "B.Cu")
		(net 206)
	)
	(segment
		(start 186.94 160.03)
		(end 186.94 159.3355)
		(width 0.15)
		(layer "B.Cu")
		(net 206)
	)
	(segment
		(start 136.377501 162.301)
		(end 136.375501 162.301)
		(width 0.4)
		(layer "B.Cu")
		(net 206)
	)
	(segment
		(start 136.376501 165.303)
		(end 136.877001 164.8025)
		(width 0.4)
		(layer "B.Cu")
		(net 206)
	)
	(segment
		(start 137.375501 168.303)
		(end 137.376502 168.303)
		(width 0.4)
		(layer "B.Cu")
		(net 206)
	)
	(segment
		(start 137.291501 160.8)
		(end 136.177501 160.8)
		(width 0.4)
		(layer "B.Cu")
		(net 206)
	)
	(segment
		(start 138.877001 167.8025)
		(end 138.177001 167.8025)
		(width 0.4)
		(layer "B.Cu")
		(net 206)
	)
	(segment
		(start 151.373501 166.301)
		(end 151.875001 166.8025)
		(width 0.4)
		(layer "B.Cu")
		(net 206)
	)
	(segment
		(start 142.373501 169.301)
		(end 142.875001 169.8025)
		(width 0.4)
		(layer "B.Cu")
		(net 206)
	)
	(segment
		(start 133.375501 166.303)
		(end 133.376501 166.303)
		(width 0.4)
		(layer "B.Cu")
		(net 206)
	)
	(segment
		(start 138.177001 167.8025)
		(end 138.477001 167.8025)
		(width 0.4)
		(layer "B.Cu")
		(net 206)
	)
	(segment
		(start 133.376501 166.303)
		(end 133.877001 165.8025)
		(width 0.4)
		(layer "B.Cu")
		(net 206)
	)
	(segment
		(start 135.875001 161.8005)
		(end 135.877001 161.8025)
		(width 0.4)
		(layer "B.Cu")
		(net 206)
	)
	(segment
		(start 150.375501 170.3005)
		(end 150.375501 170.302)
		(width 0.4)
		(layer "B.Cu")
		(net 206)
	)
	(segment
		(start 151.5 143.3)
		(end 151.8 143.3)
		(width 0.256)
		(layer "B.Cu")
		(net 206)
	)
	(segment
		(start 151.375501 163.302)
		(end 150.875001 163.8025)
		(width 0.4)
		(layer "B.Cu")
		(net 206)
	)
	(segment
		(start 146.879001 161.8025)
		(end 147.377501 162.301)
		(width 0.4)
		(layer "B.Cu")
		(net 206)
	)
	(segment
		(start 133.375501 163.301)
		(end 132.877001 162.8025)
		(width 0.4)
		(layer "B.Cu")
		(net 206)
	)
	(segment
		(start 151.375501 163.299)
		(end 151.375501 163.302)
		(width 0.4)
		(layer "B.Cu")
		(net 206)
	)
	(segment
		(start 152.575001 166.7025)
		(end 152.475001 166.8025)
		(width 0.4)
		(layer "B.Cu")
		(net 206)
	)
	(segment
		(start 148.373501 167.301)
		(end 148.875001 167.8025)
		(width 0.4)
		(layer "B.Cu")
		(net 206)
	)
	(segment
		(start 158.109 142.884)
		(end 157.425 142.884)
		(width 0.256)
		(layer "B.Cu")
		(net 206)
	)
	(segment
		(start 137.292001 160.8005)
		(end 137.291501 160.8)
		(width 0.4)
		(layer "B.Cu")
		(net 206)
	)
	(segment
		(start 195.386 139.268)
		(end 194.603 139.268)
		(width 0.15)
		(layer "F.Cu")
		(net 207)
	)
	(segment
		(start 194.603 139.268)
		(end 194.55 139.215)
		(width 0.15)
		(layer "F.Cu")
		(net 207)
	)
	(segment
		(start 199.1765 150.8035)
		(end 198.1755 150.8035)
		(width 0.256)
		(layer "F.Cu")
		(net 207)
	)
	(via
		(at 194.55 139.215)
		(size 0.45)
		(drill 0.1)
		(layers "F.Cu" "B.Cu")
		(net 207)
	)
	(via
		(at 198.1755 150.8035)
		(size 0.45)
		(drill 0.1)
		(layers "F.Cu" "B.Cu")
		(net 207)
	)
	(segment
		(start 192.575 140.475)
		(end 193.835 139.215)
		(width 0.15)
		(layer "B.Cu")
		(net 207)
	)
	(segment
		(start 195.285 139.235)
		(end 195.3 139.235)
		(width 0.1)
		(layer "B.Cu")
		(net 207)
	)
	(segment
		(start 198.154 150.825)
		(end 198.1755 150.8035)
		(width 0.15)
		(layer "B.Cu")
		(net 207)
	)
	(segment
		(start 192.575 149.025)
		(end 192.575 140.475)
		(width 0.15)
		(layer "B.Cu")
		(net 207)
	)
	(segment
		(start 194.55 139.215)
		(end 195.265 139.215)
		(width 0.256)
		(layer "B.Cu")
		(net 207)
	)
	(segment
		(start 195.265 139.215)
		(end 195.285 139.235)
		(width 0.1)
		(layer "B.Cu")
		(net 207)
	)
	(segment
		(start 194.375 150.825)
		(end 192.575 149.025)
		(width 0.15)
		(layer "B.Cu")
		(net 207)
	)
	(segment
		(start 193.835 139.215)
		(end 194.55 139.215)
		(width 0.15)
		(layer "B.Cu")
		(net 207)
	)
	(segment
		(start 194.375 150.825)
		(end 198.154 150.825)
		(width 0.15)
		(layer "B.Cu")
		(net 207)
	)
	(segment
		(start 196.368501 162.7345)
		(end 196.381001 162.722)
		(width 0.182)
		(layer "F.Cu")
		(net 208)
	)
	(segment
		(start 196.366001 162.707)
		(end 196.381001 162.722)
		(width 0.182)
		(layer "F.Cu")
		(net 208)
	)
	(segment
		(start 196.366001 161.922)
		(end 196.366001 162.707)
		(width 0.182)
		(layer "F.Cu")
		(net 208)
	)
	(segment
		(start 196.368501 163.722)
		(end 196.368501 162.7345)
		(width 0.182)
		(layer "F.Cu")
		(net 208)
	)
	(via
		(at 196.381001 162.722)
		(size 0.45)
		(drill 0.1)
		(layers "F.Cu" "B.Cu")
		(net 208)
	)
	(segment
		(start 196.3 162.640999)
		(end 196.381001 162.722)
		(width 0.256)
		(layer "B.Cu")
		(net 208)
	)
	(segment
		(start 196.366001 162.707)
		(end 196.381001 162.722)
		(width 0.182)
		(layer "B.Cu")
		(net 208)
	)
	(segment
		(start 196.19 161.95)
		(end 196.3 162.06)
		(width 0.256)
		(layer "B.Cu")
		(net 208)
	)
	(segment
		(start 196.3 162.06)
		(end 196.3 162.640999)
		(width 0.256)
		(layer "B.Cu")
		(net 208)
	)
	(segment
		(start 197.018501 171.6695)
		(end 196.966001 171.722)
		(width 0.182)
		(layer "F.Cu")
		(net 209)
	)
	(segment
		(start 197.018501 169.997)
		(end 197.018501 171.6695)
		(width 0.182)
		(layer "F.Cu")
		(net 209)
	)
	(via
		(at 197.018501 170.9595)
		(size 0.45)
		(drill 0.1)
		(layers "F.Cu" "B.Cu")
		(net 209)
	)
	(segment
		(start 197.025 170.965999)
		(end 197.018501 170.9595)
		(width 0.182)
		(layer "B.Cu")
		(net 209)
	)
	(segment
		(start 197.185 171.725)
		(end 197.05 171.59)
		(width 0.256)
		(layer "B.Cu")
		(net 209)
	)
	(segment
		(start 197.05 170.990999)
		(end 197.018501 170.9595)
		(width 0.256)
		(layer "B.Cu")
		(net 209)
	)
	(segment
		(start 197.05 171.59)
		(end 197.05 170.990999)
		(width 0.256)
		(layer "B.Cu")
		(net 209)
	)
	(segment
		(start 197.045501 188.9955)
		(end 196.880501 189.1605)
		(width 0.182)
		(layer "F.Cu")
		(net 210)
	)
	(segment
		(start 197.045501 187.448)
		(end 197.045501 188.3605)
		(width 0.182)
		(layer "F.Cu")
		(net 210)
	)
	(segment
		(start 197.045501 188.3605)
		(end 197.045501 188.9955)
		(width 0.182)
		(layer "F.Cu")
		(net 210)
	)
	(via
		(at 197.045501 188.3605)
		(size 0.45)
		(drill 0.1)
		(layers "F.Cu" "B.Cu")
		(net 210)
	)
	(segment
		(start 197.075 188.389999)
		(end 197.045501 188.3605)
		(width 0.256)
		(layer "B.Cu")
		(net 210)
	)
	(segment
		(start 197.075 189.065)
		(end 197.075 188.389999)
		(width 0.256)
		(layer "B.Cu")
		(net 210)
	)
	(segment
		(start 197.185 189.175)
		(end 197.075 189.065)
		(width 0.256)
		(layer "B.Cu")
		(net 210)
	)
	(segment
		(start 196.395501 179.5255)
		(end 196.395501 180.2105)
		(width 0.182)
		(layer "F.Cu")
		(net 211)
	)
	(segment
		(start 196.395501 181.173)
		(end 196.395501 180.2105)
		(width 0.182)
		(layer "F.Cu")
		(net 211)
	)
	(segment
		(start 196.280501 179.4105)
		(end 196.395501 179.5255)
		(width 0.182)
		(layer "F.Cu")
		(net 211)
	)
	(via
		(at 196.395501 180.2105)
		(size 0.45)
		(drill 0.1)
		(layers "F.Cu" "B.Cu")
		(net 211)
	)
	(segment
		(start 196.215 179.4)
		(end 196.325 179.51)
		(width 0.256)
		(layer "B.Cu")
		(net 211)
	)
	(segment
		(start 196.325 180.139999)
		(end 196.395501 180.2105)
		(width 0.256)
		(layer "B.Cu")
		(net 211)
	)
	(segment
		(start 196.325 179.51)
		(end 196.325 180.139999)
		(width 0.256)
		(layer "B.Cu")
		(net 211)
	)
	(segment
		(start 156.150001 138.8025)
		(end 156.150001 139.8775)
		(width 0.201)
		(layer "F.Cu")
		(net 212)
	)
	(segment
		(start 150.375501 163.302)
		(end 150.875002 162.8025)
		(width 0.256)
		(layer "F.Cu")
		(net 212)
	)
	(via
		(at 156.150001 139.8775)
		(size 0.45)
		(drill 0.1)
		(layers "F.Cu" "B.Cu")
		(net 212)
	)
	(via
		(at 150.875002 162.8025)
		(size 0.45)
		(drill 0.1)
		(layers "F.Cu" "B.Cu")
		(net 212)
	)
	(segment
		(start 151.358502 163.286)
		(end 150.875002 162.8025)
		(width 0.148)
		(layer "In6.Cu")
		(net 212)
	)
	(segment
		(start 159.5 158.75)
		(end 154.964 163.286)
		(width 0.148)
		(layer "In6.Cu")
		(net 212)
	)
	(segment
		(start 157.4 146.15)
		(end 157.9 146.65)
		(width 0.148)
		(layer "In6.Cu")
		(net 212)
	)
	(segment
		(start 157.4 141.127499)
		(end 157.4 146.15)
		(width 0.148)
		(layer "In6.Cu")
		(net 212)
	)
	(segment
		(start 157.9 146.65)
		(end 157.9 147.495886)
		(width 0.148)
		(layer "In6.Cu")
		(net 212)
	)
	(segment
		(start 156.150001 139.8775)
		(end 157.4 141.127499)
		(width 0.148)
		(layer "In6.Cu")
		(net 212)
	)
	(segment
		(start 154.964 163.286)
		(end 151.358502 163.286)
		(width 0.148)
		(layer "In6.Cu")
		(net 212)
	)
	(segment
		(start 157.9 147.495886)
		(end 159.5 149.095886)
		(width 0.148)
		(layer "In6.Cu")
		(net 212)
	)
	(segment
		(start 159.5 149.095886)
		(end 159.5 158.75)
		(width 0.148)
		(layer "In6.Cu")
		(net 212)
	)
	(segment
		(start 156.4 146.2025)
		(end 156.4 147.2775)
		(width 0.201)
		(layer "F.Cu")
		(net 213)
	)
	(segment
		(start 151.375501 163.302)
		(end 151.875001 162.8025)
		(width 0.256)
		(layer "F.Cu")
		(net 213)
	)
	(via
		(at 151.875001 162.8025)
		(size 0.45)
		(drill 0.1)
		(layers "F.Cu" "B.Cu")
		(net 213)
	)
	(via
		(at 156.4 147.2775)
		(size 0.45)
		(drill 0.1)
		(layers "F.Cu" "B.Cu")
		(net 213)
	)
	(segment
		(start 156.279787 161.12598)
		(end 156.279787 161.125979)
		(width 0.148)
		(layer "In6.Cu")
		(net 213)
	)
	(segment
		(start 154.865575 162.540192)
		(end 154.865575 162.540191)
		(width 0.148)
		(layer "In6.Cu")
		(net 213)
	)
	(segment
		(start 157.693999 159.711767)
		(end 157.038233 159.056001)
		(width 0.148)
		(layer "In6.Cu")
		(net 213)
	)
	(segment
		(start 157.391787 158.348893)
		(end 157.391786 158.348894)
		(width 0.148)
		(layer "In6.Cu")
		(net 213)
	)
	(segment
		(start 155.270468 160.823766)
		(end 155.926234 161.479532)
		(width 0.148)
		(layer "In6.Cu")
		(net 213)
	)
	(segment
		(start 155.977573 159.763107)
		(end 155.977574 159.763107)
		(width 0.148)
		(layer "In6.Cu")
		(net 213)
	)
	(segment
		(start 158.5 158.25)
		(end 158.25 158.5)
		(width 0.148)
		(layer "In6.Cu")
		(net 213)
	)
	(segment
		(start 155.219128 162.540192)
		(end 155.219127 162.540192)
		(width 0.148)
		(layer "In6.Cu")
		(net 213)
	)
	(segment
		(start 157.391786 158.702447)
		(end 158.047552 159.358214)
		(width 0.148)
		(layer "In6.Cu")
		(net 213)
	)
	(segment
		(start 154.360916 162.389086)
		(end 153.9475 162.8025)
		(width 0.148)
		(layer "In6.Cu")
		(net 213)
	)
	(segment
		(start 155.270467 160.470213)
		(end 155.270468 160.470213)
		(width 0.148)
		(layer "In6.Cu")
		(net 213)
	)
	(segment
		(start 156.684679 159.056001)
		(end 156.68468 159.056001)
		(width 0.148)
		(layer "In6.Cu")
		(net 213)
	)
	(segment
		(start 155.572681 161.833086)
		(end 155.572681 161.833085)
		(width 0.148)
		(layer "In6.Cu")
		(net 213)
	)
	(segment
		(start 157.391786 158.702446)
		(end 157.391786 158.702447)
		(width 0.148)
		(layer "In6.Cu")
		(net 213)
	)
	(segment
		(start 156.68468 159.409554)
		(end 157.340446 160.06532)
		(width 0.148)
		(layer "In6.Cu")
		(net 213)
	)
	(segment
		(start 156.68468 159.409553)
		(end 156.68468 159.409554)
		(width 0.148)
		(layer "In6.Cu")
		(net 213)
	)
	(segment
		(start 155.977574 160.11666)
		(end 156.63334 160.772426)
		(width 0.148)
		(layer "In6.Cu")
		(net 213)
	)
	(segment
		(start 157.340446 160.418874)
		(end 157.340445 160.418874)
		(width 0.148)
		(layer "In6.Cu")
		(net 213)
	)
	(segment
		(start 157.896446 158.5)
		(end 157.74534 158.348894)
		(width 0.148)
		(layer "In6.Cu")
		(net 213)
	)
	(segment
		(start 155.977574 160.116659)
		(end 155.977574 160.11666)
		(width 0.148)
		(layer "In6.Cu")
		(net 213)
	)
	(segment
		(start 156.279787 161.125979)
		(end 155.624021 160.470213)
		(width 0.148)
		(layer "In6.Cu")
		(net 213)
	)
	(segment
		(start 154.865575 162.540191)
		(end 154.71447 162.389086)
		(width 0.148)
		(layer "In6.Cu")
		(net 213)
	)
	(segment
		(start 154.563362 161.530872)
		(end 155.219128 162.186638)
		(width 0.148)
		(layer "In6.Cu")
		(net 213)
	)
	(segment
		(start 154.563362 161.530871)
		(end 154.563362 161.530872)
		(width 0.148)
		(layer "In6.Cu")
		(net 213)
	)
	(segment
		(start 156.4 147.2775)
		(end 158.5 149.3775)
		(width 0.148)
		(layer "In6.Cu")
		(net 213)
	)
	(segment
		(start 154.360917 162.389085)
		(end 154.360916 162.389086)
		(width 0.148)
		(layer "In6.Cu")
		(net 213)
	)
	(segment
		(start 155.270468 160.823765)
		(end 155.270468 160.823766)
		(width 0.148)
		(layer "In6.Cu")
		(net 213)
	)
	(segment
		(start 154.563361 161.177319)
		(end 154.563362 161.177319)
		(width 0.148)
		(layer "In6.Cu")
		(net 213)
	)
	(segment
		(start 153.9475 162.8025)
		(end 151.875001 162.8025)
		(width 0.148)
		(layer "In6.Cu")
		(net 213)
	)
	(segment
		(start 158.5 149.3775)
		(end 158.5 158.25)
		(width 0.148)
		(layer "In6.Cu")
		(net 213)
	)
	(segment
		(start 157.693999 159.711768)
		(end 157.693999 159.711767)
		(width 0.148)
		(layer "In6.Cu")
		(net 213)
	)
	(segment
		(start 156.63334 161.12598)
		(end 156.633339 161.12598)
		(width 0.148)
		(layer "In6.Cu")
		(net 213)
	)
	(segment
		(start 155.572681 161.833085)
		(end 154.916915 161.177319)
		(width 0.148)
		(layer "In6.Cu")
		(net 213)
	)
	(segment
		(start 156.986893 160.418874)
		(end 156.986893 160.418873)
		(width 0.148)
		(layer "In6.Cu")
		(net 213)
	)
	(segment
		(start 155.926234 161.833086)
		(end 155.926233 161.833086)
		(width 0.148)
		(layer "In6.Cu")
		(net 213)
	)
	(segment
		(start 158.047552 159.711768)
		(end 158.047551 159.711768)
		(width 0.148)
		(layer "In6.Cu")
		(net 213)
	)
	(segment
		(start 156.986893 160.418873)
		(end 156.331127 159.763107)
		(width 0.148)
		(layer "In6.Cu")
		(net 213)
	)
	(arc
		(start 155.624021 160.470213)
		(mid 155.447244 160.39699)
		(end 155.270467 160.470213)
		(width 0.148)
		(layer "In6.Cu")
		(net 213)
	)
	(arc
		(start 157.340445 160.418874)
		(mid 157.16367 160.492096)
		(end 156.986893 160.418874)
		(width 0.148)
		(layer "In6.Cu")
		(net 213)
	)
	(arc
		(start 158.047552 159.358214)
		(mid 158.120775 159.534991)
		(end 158.047552 159.711768)
		(width 0.148)
		(layer "In6.Cu")
		(net 213)
	)
	(arc
		(start 154.563362 161.177319)
		(mid 154.490139 161.354095)
		(end 154.563362 161.530871)
		(width 0.148)
		(layer "In6.Cu")
		(net 213)
	)
	(arc
		(start 155.219128 162.186638)
		(mid 155.292351 162.363415)
		(end 155.219128 162.540192)
		(width 0.148)
		(layer "In6.Cu")
		(net 213)
	)
	(arc
		(start 155.926233 161.833086)
		(mid 155.749458 161.906308)
		(end 155.572681 161.833086)
		(width 0.148)
		(layer "In6.Cu")
		(net 213)
	)
	(arc
		(start 154.71447 162.389086)
		(mid 154.537694 162.315862)
		(end 154.360917 162.389085)
		(width 0.148)
		(layer "In6.Cu")
		(net 213)
	)
	(arc
		(start 157.391786 158.348894)
		(mid 157.318563 158.52567)
		(end 157.391786 158.702446)
		(width 0.148)
		(layer "In6.Cu")
		(net 213)
	)
	(arc
		(start 157.038233 159.056001)
		(mid 156.861456 158.982778)
		(end 156.684679 159.056001)
		(width 0.148)
		(layer "In6.Cu")
		(net 213)
	)
	(arc
		(start 157.74534 158.348894)
		(mid 157.568564 158.27567)
		(end 157.391787 158.348893)
		(width 0.148)
		(layer "In6.Cu")
		(net 213)
	)
	(arc
		(start 155.219127 162.540192)
		(mid 155.042352 162.613414)
		(end 154.865575 162.540192)
		(width 0.148)
		(layer "In6.Cu")
		(net 213)
	)
	(arc
		(start 155.270468 160.470213)
		(mid 155.197245 160.646989)
		(end 155.270468 160.823765)
		(width 0.148)
		(layer "In6.Cu")
		(net 213)
	)
	(arc
		(start 155.977574 159.763107)
		(mid 155.904351 159.939883)
		(end 155.977574 160.116659)
		(width 0.148)
		(layer "In6.Cu")
		(net 213)
	)
	(arc
		(start 156.63334 160.772426)
		(mid 156.706563 160.949203)
		(end 156.63334 161.12598)
		(width 0.148)
		(layer "In6.Cu")
		(net 213)
	)
	(arc
		(start 156.633339 161.12598)
		(mid 156.456564 161.199202)
		(end 156.279787 161.12598)
		(width 0.148)
		(layer "In6.Cu")
		(net 213)
	)
	(arc
		(start 158.047551 159.711768)
		(mid 157.870776 159.78499)
		(end 157.693999 159.711768)
		(width 0.148)
		(layer "In6.Cu")
		(net 213)
	)
	(arc
		(start 158.25 158.5)
		(mid 158.073223 158.573223)
		(end 157.896446 158.5)
		(width 0.148)
		(layer "In6.Cu")
		(net 213)
	)
	(arc
		(start 154.916915 161.177319)
		(mid 154.740138 161.104096)
		(end 154.563361 161.177319)
		(width 0.148)
		(layer "In6.Cu")
		(net 213)
	)
	(arc
		(start 156.331127 159.763107)
		(mid 156.15435 159.689884)
		(end 155.977573 159.763107)
		(width 0.148)
		(layer "In6.Cu")
		(net 213)
	)
	(arc
		(start 156.68468 159.056001)
		(mid 156.611457 159.232777)
		(end 156.68468 159.409553)
		(width 0.148)
		(layer "In6.Cu")
		(net 213)
	)
	(arc
		(start 157.340446 160.06532)
		(mid 157.413669 160.242097)
		(end 157.340446 160.418874)
		(width 0.148)
		(layer "In6.Cu")
		(net 213)
	)
	(arc
		(start 155.926234 161.479532)
		(mid 155.999457 161.656309)
		(end 155.926234 161.833086)
		(width 0.148)
		(layer "In6.Cu")
		(net 213)
	)
	(segment
		(start 82.856897 138.154037)
		(end 84.4405 138.154037)
		(width 0.256)
		(layer "B.Cu")
		(net 214)
	)
	(segment
		(start 87.0405 136.928487)
		(end 86.9905 136.878487)
		(width 0.2)
		(layer "B.Cu")
		(net 215)
	)
	(segment
		(start 88.806897 136.928487)
		(end 87.0405 136.928487)
		(width 0.256)
		(layer "B.Cu")
		(net 215)
	)
	(segment
		(start 202.925501 181.4305)
		(end 202.320501 182.0355)
		(width 0.182)
		(layer "F.Cu")
		(net 216)
	)
	(segment
		(start 202.320501 182.0355)
		(end 202.020501 182.0355)
		(width 0.182)
		(layer "F.Cu")
		(net 216)
	)
	(segment
		(start 202.945501 181.4305)
		(end 202.925501 181.4305)
		(width 0.182)
		(layer "F.Cu")
		(net 216)
	)
	(segment
		(start 201.158001 182.0355)
		(end 202.020501 182.0355)
		(width 0.182)
		(layer "F.Cu")
		(net 216)
	)
	(via
		(at 202.020501 182.0355)
		(size 0.45)
		(drill 0.1)
		(layers "F.Cu" "B.Cu")
		(net 216)
	)
	(segment
		(start 202.815 182.025)
		(end 202.031001 182.025)
		(width 0.256)
		(layer "B.Cu")
		(net 216)
	)
	(segment
		(start 202.031001 182.025)
		(end 202.020501 182.0355)
		(width 0.256)
		(layer "B.Cu")
		(net 216)
	)
	(segment
		(start 202.925 181.915)
		(end 202.815 182.025)
		(width 0.256)
		(layer "B.Cu")
		(net 216)
	)
	(segment
		(start 202.253501 164.5845)
		(end 202.881001 163.957)
		(width 0.182)
		(layer "F.Cu")
		(net 217)
	)
	(segment
		(start 202.043501 164.5845)
		(end 202.253501 164.5845)
		(width 0.182)
		(layer "F.Cu")
		(net 217)
	)
	(segment
		(start 201.131001 164.5845)
		(end 202.043501 164.5845)
		(width 0.182)
		(layer "F.Cu")
		(net 217)
	)
	(via
		(at 202.043501 164.5845)
		(size 0.45)
		(drill 0.1)
		(layers "F.Cu" "B.Cu")
		(net 217)
	)
	(segment
		(start 202.715 164.525)
		(end 202.103001 164.525)
		(width 0.256)
		(layer "B.Cu")
		(net 217)
	)
	(segment
		(start 202.875 164.365)
		(end 202.715 164.525)
		(width 0.256)
		(layer "B.Cu")
		(net 217)
	)
	(segment
		(start 202.103001 164.525)
		(end 202.043501 164.5845)
		(width 0.256)
		(layer "B.Cu")
		(net 217)
	)
	(segment
		(start 201.793501 169.1345)
		(end 202.131001 169.472)
		(width 0.182)
		(layer "F.Cu")
		(net 218)
	)
	(segment
		(start 201.131001 169.1345)
		(end 201.793501 169.1345)
		(width 0.182)
		(layer "F.Cu")
		(net 218)
	)
	(segment
		(start 202.881001 169.737)
		(end 202.396001 169.737)
		(width 0.182)
		(layer "F.Cu")
		(net 218)
	)
	(segment
		(start 202.396001 169.737)
		(end 202.131001 169.472)
		(width 0.182)
		(layer "F.Cu")
		(net 218)
	)
	(via
		(at 202.131001 169.472)
		(size 0.45)
		(drill 0.1)
		(layers "F.Cu" "B.Cu")
		(net 218)
	)
	(segment
		(start 202.131001 169.472)
		(end 202.384001 169.725)
		(width 0.182)
		(layer "B.Cu")
		(net 218)
	)
	(segment
		(start 202.869001 169.725)
		(end 202.881001 169.737)
		(width 0.182)
		(layer "B.Cu")
		(net 218)
	)
	(segment
		(start 202.384001 169.725)
		(end 202.869001 169.725)
		(width 0.182)
		(layer "B.Cu")
		(net 218)
	)
	(segment
		(start 151.375501 164.302)
		(end 151.875001 163.8025)
		(width 0.256)
		(layer "F.Cu")
		(net 219)
	)
	(segment
		(start 157.150002 138.8025)
		(end 157.150002 139.8775)
		(width 0.201)
		(layer "F.Cu")
		(net 219)
	)
	(via
		(at 157.150002 139.8775)
		(size 0.45)
		(drill 0.1)
		(layers "F.Cu" "B.Cu")
		(net 219)
	)
	(via
		(at 151.875001 163.8025)
		(size 0.45)
		(drill 0.1)
		(layers "F.Cu" "B.Cu")
		(net 219)
	)
	(segment
		(start 158.864804 141.238748)
		(end 158.864805 141.23875)
		(width 0.148)
		(layer "In6.Cu")
		(net 219)
	)
	(segment
		(start 155.9475 163.8025)
		(end 151.875001 163.8025)
		(width 0.148)
		(layer "In6.Cu")
		(net 219)
	)
	(segment
		(start 159.7 145.647942)
		(end 160.400501 146.348443)
		(width 0.148)
		(layer "In6.Cu")
		(net 219)
	)
	(segment
		(start 159.361951 141.44871)
		(end 159.218357 141.592301)
		(width 0.148)
		(layer "In6.Cu")
		(net 219)
	)
	(segment
		(start 160.400501 146.348443)
		(end 160.400501 159.349499)
		(width 0.148)
		(layer "In6.Cu")
		(net 219)
	)
	(segment
		(start 159.218357 141.945855)
		(end 159.7 142.427498)
		(width 0.148)
		(layer "In6.Cu")
		(net 219)
	)
	(segment
		(start 159.7 142.427498)
		(end 159.7 145.647942)
		(width 0.148)
		(layer "In6.Cu")
		(net 219)
	)
	(segment
		(start 159.361949 141.095155)
		(end 159.36195 141.095156)
		(width 0.148)
		(layer "In6.Cu")
		(net 219)
	)
	(segment
		(start 159.218356 141.945854)
		(end 159.218357 141.945855)
		(width 0.148)
		(layer "In6.Cu")
		(net 219)
	)
	(segment
		(start 160.400501 159.349499)
		(end 155.9475 163.8025)
		(width 0.148)
		(layer "In6.Cu")
		(net 219)
	)
	(segment
		(start 157.150002 139.8775)
		(end 158.511251 141.238749)
		(width 0.148)
		(layer "In6.Cu")
		(net 219)
	)
	(segment
		(start 158.864805 141.23875)
		(end 159.008396 141.095156)
		(width 0.148)
		(layer "In6.Cu")
		(net 219)
	)
	(segment
		(start 159.361949 141.448709)
		(end 159.361951 141.44871)
		(width 0.148)
		(layer "In6.Cu")
		(net 219)
	)
	(arc
		(start 159.008396 141.095156)
		(mid 159.185172 141.021932)
		(end 159.361949 141.095155)
		(width 0.148)
		(layer "In6.Cu")
		(net 219)
	)
	(arc
		(start 158.511251 141.238749)
		(mid 158.688028 141.311972)
		(end 158.864804 141.238748)
		(width 0.148)
		(layer "In6.Cu")
		(net 219)
	)
	(arc
		(start 159.36195 141.095156)
		(mid 159.435173 141.271933)
		(end 159.361949 141.448709)
		(width 0.148)
		(layer "In6.Cu")
		(net 219)
	)
	(arc
		(start 159.218357 141.592301)
		(mid 159.145133 141.769077)
		(end 159.218356 141.945854)
		(width 0.148)
		(layer "In6.Cu")
		(net 219)
	)
	(segment
		(start 202.305501 186.5855)
		(end 202.895501 187.1755)
		(width 0.182)
		(layer "F.Cu")
		(net 220)
	)
	(segment
		(start 201.158001 186.5855)
		(end 202.020501 186.5855)
		(width 0.182)
		(layer "F.Cu")
		(net 220)
	)
	(segment
		(start 202.020501 186.5855)
		(end 202.305501 186.5855)
		(width 0.182)
		(layer "F.Cu")
		(net 220)
	)
	(via
		(at 202.020501 186.5855)
		(size 0.45)
		(drill 0.1)
		(layers "F.Cu" "B.Cu")
		(net 220)
	)
	(segment
		(start 202.020501 186.5855)
		(end 202.3455 186.5855)
		(width 0.182)
		(layer "B.Cu")
		(net 220)
	)
	(segment
		(start 202.3455 186.5855)
		(end 202.925 187.165)
		(width 0.182)
		(layer "B.Cu")
		(net 220)
	)
	(segment
		(start 194.288499 147.801)
		(end 194.214499 147.875)
		(width 0.182)
		(layer "F.Cu")
		(net 221)
	)
	(segment
		(start 170.370501 194.214502)
		(end 170.270502 194.314502)
		(width 0.177)
		(layer "F.Cu")
		(net 221)
	)
	(segment
		(start 171.020504 194.214502)
		(end 170.370501 194.214502)
		(width 0.177)
		(layer "F.Cu")
		(net 221)
	)
	(segment
		(start 195.165 147.801)
		(end 194.288499 147.801)
		(width 0.182)
		(layer "F.Cu")
		(net 221)
	)
	(via
		(at 194.214499 147.875)
		(size 0.45)
		(drill 0.1)
		(layers "F.Cu" "B.Cu")
		(net 221)
	)
	(via
		(at 170.270502 194.314502)
		(size 0.45)
		(drill 0.1)
		(layers "F.Cu" "B.Cu")
		(net 221)
	)
	(segment
		(start 194.93 147.851)
		(end 194.238499 147.851)
		(width 0.256)
		(layer "B.Cu")
		(net 221)
	)
	(segment
		(start 194.238499 147.851)
		(end 194.214499 147.875)
		(width 0.256)
		(layer "B.Cu")
		(net 221)
	)
	(segment
		(start 193.525 147.875)
		(end 192.6 148.8)
		(width 0.1)
		(layer "In2.Cu")
		(net 221)
	)
	(segment
		(start 191.573 161.927)
		(end 191.573 180.327)
		(width 0.1)
		(layer "In2.Cu")
		(net 221)
	)
	(segment
		(start 168.5 193.65)
		(end 169.164502 194.314502)
		(width 0.1)
		(layer "In2.Cu")
		(net 221)
	)
	(segment
		(start 192.6 148.8)
		(end 192.6 160.9)
		(width 0.1)
		(layer "In2.Cu")
		(net 221)
	)
	(segment
		(start 168.5 191.8)
		(end 168.5 193.65)
		(width 0.1)
		(layer "In2.Cu")
		(net 221)
	)
	(segment
		(start 194.214499 147.875)
		(end 193.525 147.875)
		(width 0.1)
		(layer "In2.Cu")
		(net 221)
	)
	(segment
		(start 169.164502 194.314502)
		(end 170.270502 194.314502)
		(width 0.1)
		(layer "In2.Cu")
		(net 221)
	)
	(segment
		(start 169.9 190.4)
		(end 168.5 191.8)
		(width 0.1)
		(layer "In2.Cu")
		(net 221)
	)
	(segment
		(start 181.5 190.4)
		(end 169.9 190.4)
		(width 0.1)
		(layer "In2.Cu")
		(net 221)
	)
	(segment
		(start 191.573 180.327)
		(end 181.5 190.4)
		(width 0.1)
		(layer "In2.Cu")
		(net 221)
	)
	(segment
		(start 192.6 160.9)
		(end 191.573 161.927)
		(width 0.1)
		(layer "In2.Cu")
		(net 221)
	)
	(segment
		(start 195.165 146.851)
		(end 194.214499 146.851)
		(width 0.182)
		(layer "F.Cu")
		(net 222)
	)
	(segment
		(start 197.695501 187.4465)
		(end 197.695501 188.471)
		(width 0.256)
		(layer "F.Cu")
		(net 222)
	)
	(segment
		(start 197.695501 188.471)
		(end 197.700501 188.476)
		(width 0.256)
		(layer "F.Cu")
		(net 222)
	)
	(via
		(at 197.700501 188.476)
		(size 0.45)
		(drill 0.1)
		(layers "F.Cu" "B.Cu")
		(net 222)
	)
	(via
		(at 194.214499 146.851)
		(size 0.45)
		(drill 0.1)
		(layers "F.Cu" "B.Cu")
		(net 222)
	)
	(segment
		(start 194.93 146.851)
		(end 194.214499 146.851)
		(width 0.256)
		(layer "B.Cu")
		(net 222)
	)
	(segment
		(start 193.1 149.2)
		(end 193.1 161.1)
		(width 0.1)
		(layer "In2.Cu")
		(net 222)
	)
	(segment
		(start 194.214499 146.851)
		(end 194.825 147.461501)
		(width 0.1)
		(layer "In2.Cu")
		(net 222)
	)
	(segment
		(start 194.825 147.461501)
		(end 194.825 148.65)
		(width 0.1)
		(layer "In2.Cu")
		(net 222)
	)
	(segment
		(start 192.5 182.6)
		(end 197.700501 187.800501)
		(width 0.1)
		(layer "In2.Cu")
		(net 222)
	)
	(segment
		(start 194.825 148.65)
		(end 194.475 149)
		(width 0.1)
		(layer "In2.Cu")
		(net 222)
	)
	(segment
		(start 194.475 149)
		(end 193.3 149)
		(width 0.1)
		(layer "In2.Cu")
		(net 222)
	)
	(segment
		(start 192.5 161.7)
		(end 192.5 182.6)
		(width 0.1)
		(layer "In2.Cu")
		(net 222)
	)
	(segment
		(start 193.3 149)
		(end 193.1 149.2)
		(width 0.1)
		(layer "In2.Cu")
		(net 222)
	)
	(segment
		(start 193.1 161.1)
		(end 192.5 161.7)
		(width 0.1)
		(layer "In2.Cu")
		(net 222)
	)
	(segment
		(start 197.700501 187.800501)
		(end 197.700501 188.476)
		(width 0.1)
		(layer "In2.Cu")
		(net 222)
	)
	(segment
		(start 197.668501 170.944)
		(end 197.800501 171.076)
		(width 0.256)
		(layer "F.Cu")
		(net 223)
	)
	(segment
		(start 197.668501 169.9955)
		(end 197.668501 170.944)
		(width 0.256)
		(layer "F.Cu")
		(net 223)
	)
	(segment
		(start 194.240499 145.901)
		(end 194.214499 145.875)
		(width 0.182)
		(layer "F.Cu")
		(net 223)
	)
	(segment
		(start 195.165 145.901)
		(end 194.240499 145.901)
		(width 0.182)
		(layer "F.Cu")
		(net 223)
	)
	(via
		(at 194.214499 145.875)
		(size 0.45)
		(drill 0.1)
		(layers "F.Cu" "B.Cu")
		(net 223)
	)
	(via
		(at 197.800501 171.076)
		(size 0.45)
		(drill 0.1)
		(layers "F.Cu" "B.Cu")
		(net 223)
	)
	(segment
		(start 194.93 145.851)
		(end 194.238499 145.851)
		(width 0.256)
		(layer "B.Cu")
		(net 223)
	)
	(segment
		(start 194.238499 145.851)
		(end 194.214499 145.875)
		(width 0.256)
		(layer "B.Cu")
		(net 223)
	)
	(segment
		(start 193.7 150.08825)
		(end 193.7 161.219669)
		(width 0.1)
		(layer "In2.Cu")
		(net 223)
	)
	(segment
		(start 193.125 161.794669)
		(end 193.125 165.925)
		(width 0.1)
		(layer "In2.Cu")
		(net 223)
	)
	(segment
		(start 193.125 165.925)
		(end 197.800501 170.600501)
		(width 0.1)
		(layer "In2.Cu")
		(net 223)
	)
	(segment
		(start 194.1 149.68825)
		(end 193.7 150.08825)
		(width 0.1)
		(layer "In2.Cu")
		(net 223)
	)
	(segment
		(start 197.800501 170.600501)
		(end 197.800501 171.076)
		(width 0.1)
		(layer "In2.Cu")
		(net 223)
	)
	(segment
		(start 194.76175 149.68825)
		(end 194.1 149.68825)
		(width 0.1)
		(layer "In2.Cu")
		(net 223)
	)
	(segment
		(start 195.525 146.875)
		(end 195.525 148.925)
		(width 0.1)
		(layer "In2.Cu")
		(net 223)
	)
	(segment
		(start 193.7 161.219669)
		(end 193.125 161.794669)
		(width 0.1)
		(layer "In2.Cu")
		(net 223)
	)
	(segment
		(start 195.525 148.925)
		(end 194.76175 149.68825)
		(width 0.1)
		(layer "In2.Cu")
		(net 223)
	)
	(segment
		(start 194.525 145.875)
		(end 195.525 146.875)
		(width 0.1)
		(layer "In2.Cu")
		(net 223)
	)
	(segment
		(start 194.214499 145.875)
		(end 194.525 145.875)
		(width 0.1)
		(layer "In2.Cu")
		(net 223)
	)
	(segment
		(start 193.2 194.85)
		(end 191.775 194.85)
		(width 0.256)
		(layer "F.Cu")
		(net 224)
	)
	(segment
		(start 175.585504 194.714501)
		(end 176.085501 194.214502)
		(width 0.177)
		(layer "F.Cu")
		(net 225)
	)
	(segment
		(start 174.720501 194.714501)
		(end 175.585504 194.714501)
		(width 0.177)
		(layer "F.Cu")
		(net 225)
	)
	(segment
		(start 149.876001 184.8015)
		(end 150.375501 185.301)
		(width 0.256)
		(layer "F.Cu")
		(net 226)
	)
	(segment
		(start 149.375501 176.301)
		(end 149.875001 176.8005)
		(width 0.256)
		(layer "F.Cu")
		(net 226)
	)
	(segment
		(start 149.375501 184.301)
		(end 149.875001 184.8005)
		(width 0.256)
		(layer "F.Cu")
		(net 226)
	)
	(segment
		(start 149.375501 180.301)
		(end 149.875001 180.8005)
		(width 0.256)
		(layer "F.Cu")
		(net 226)
	)
	(segment
		(start 149.876001 180.8015)
		(end 150.375501 181.301)
		(width 0.256)
		(layer "F.Cu")
		(net 226)
	)
	(segment
		(start 149.375501 186.301)
		(end 149.875001 186.8005)
		(width 0.256)
		(layer "F.Cu")
		(net 226)
	)
	(segment
		(start 150.375501 177.301)
		(end 150.875001 177.8005)
		(width 0.256)
		(layer "F.Cu")
		(net 226)
	)
	(segment
		(start 147.375501 176.300999)
		(end 147.875001 176.8005)
		(width 0.256)
		(layer "F.Cu")
		(net 226)
	)
	(via
		(at 189.725 194.4)
		(size 0.45)
		(drill 0.1)
		(layers "F.Cu" "B.Cu")
		(net 226)
	)
	(via
		(at 188.875 192.875)
		(size 0.45)
		(drill 0.1)
		(layers "F.Cu" "B.Cu")
		(net 226)
	)
	(via
		(at 188.9 194.05)
		(size 0.45)
		(drill 0.1)
		(layers "F.Cu" "B.Cu")
		(net 226)
	)
	(via
		(at 189.2 193.425)
		(size 0.45)
		(drill 0.1)
		(layers "F.Cu" "B.Cu")
		(net 226)
	)
	(via
		(at 150.875001 177.8005)
		(size 0.45)
		(drill 0.1)
		(layers "F.Cu" "B.Cu")
		(net 226)
	)
	(via
		(at 147.875001 176.8005)
		(size 0.45)
		(drill 0.1)
		(layers "F.Cu" "B.Cu")
		(net 226)
	)
	(via
		(at 149.875001 184.8005)
		(size 0.45)
		(drill 0.1)
		(layers "F.Cu" "B.Cu")
		(net 226)
	)
	(via
		(at 188.9 194.8)
		(size 0.45)
		(drill 0.1)
		(layers "F.Cu" "B.Cu")
		(net 226)
	)
	(via
		(at 149.875001 186.8005)
		(size 0.45)
		(drill 0.1)
		(layers "F.Cu" "B.Cu")
		(net 226)
	)
	(via
		(at 149.875001 180.8005)
		(size 0.45)
		(drill 0.1)
		(layers "F.Cu" "B.Cu")
		(net 226)
	)
	(via
		(at 149.875001 176.8005)
		(size 0.45)
		(drill 0.1)
		(layers "F.Cu" "B.Cu")
		(net 226)
	)
	(segment
		(start 188.325 192.875)
		(end 188.05 193.15)
		(width 0.15)
		(layer "B.Cu")
		(net 226)
	)
	(segment
		(start 148.376001 177.3015)
		(end 147.875001 176.8005)
		(width 0.4)
		(layer "B.Cu")
		(net 226)
	)
	(segment
		(start 149.875001 176.8005)
		(end 150.373001 176.3025)
		(width 0.4)
		(layer "B.Cu")
		(net 226)
	)
	(segment
		(start 149.875001 186.8005)
		(end 149.875001 186.1525)
		(width 0.256)
		(layer "B.Cu")
		(net 226)
	)
	(segment
		(start 149.875001 180.8005)
		(end 149.377001 180.3025)
		(width 0.4)
		(layer "B.Cu")
		(net 226)
	)
	(segment
		(start 149.377001 181.3025)
		(end 149.377001 181.2985)
		(width 0.4)
		(layer "B.Cu")
		(net 226)
	)
	(segment
		(start 149.377001 184.2985)
		(end 149.377001 184.3025)
		(width 0.4)
		(layer "B.Cu")
		(net 226)
	)
	(segment
		(start 149.377001 184.3025)
		(end 149.875001 184.8005)
		(width 0.4)
		(layer "B.Cu")
		(net 226)
	)
	(segment
		(start 148.376001 177.3025)
		(end 148.376001 177.3015)
		(width 0.4)
		(layer "B.Cu")
		(net 226)
	)
	(segment
		(start 149.875001 186.1525)
		(end 149.877001 186.1505)
		(width 0.256)
		(layer "B.Cu")
		(net 226)
	)
	(segment
		(start 151.375001 177.3005)
		(end 150.875001 177.8005)
		(width 0.4)
		(layer "B.Cu")
		(net 226)
	)
	(segment
		(start 188.05 193.15)
		(end 186.4 193.15)
		(width 0.15)
		(layer "B.Cu")
		(net 226)
	)
	(segment
		(start 149.377001 181.2985)
		(end 149.875001 180.8005)
		(width 0.4)
		(layer "B.Cu")
		(net 226)
	)
	(segment
		(start 188.875 192.875)
		(end 188.325 192.875)
		(width 0.15)
		(layer "B.Cu")
		(net 226)
	)
	(segment
		(start 151.377001 177.3005)
		(end 151.375001 177.3005)
		(width 0.4)
		(layer "B.Cu")
		(net 226)
	)
	(segment
		(start 139.375501 175.301)
		(end 139.875001 175.8005)
		(width 0.256)
		(layer "F.Cu")
		(net 227)
	)
	(segment
		(start 140.375501 172.302)
		(end 140.875001 171.8025)
		(width 0.256)
		(layer "F.Cu")
		(net 227)
	)
	(segment
		(start 137.376501 175.301)
		(end 136.877001 175.8005)
		(width 0.256)
		(layer "F.Cu")
		(net 227)
	)
	(segment
		(start 138.376501 176.300999)
		(end 137.877001 176.8005)
		(width 0.256)
		(layer "F.Cu")
		(net 227)
	)
	(segment
		(start 143.375501 175.301)
		(end 143.875001 175.8005)
		(width 0.256)
		(layer "F.Cu")
		(net 227)
	)
	(segment
		(start 140.3755 178.301)
		(end 140.875001 178.8005)
		(width 0.256)
		(layer "F.Cu")
		(net 227)
	)
	(segment
		(start 143.375501 177.301)
		(end 143.875002 177.8005)
		(width 0.256)
		(layer "F.Cu")
		(net 227)
	)
	(segment
		(start 139.375501 177.301)
		(end 139.875 177.8005)
		(width 0.256)
		(layer "F.Cu")
		(net 227)
	)
	(segment
		(start 138.376501 174.302)
		(end 137.877001 173.8025)
		(width 0.256)
		(layer "F.Cu")
		(net 227)
	)
	(segment
		(start 137.376501 177.301)
		(end 136.877001 177.8005)
		(width 0.256)
		(layer "F.Cu")
		(net 227)
	)
	(segment
		(start 137.376501 171.302)
		(end 136.877001 170.8025)
		(width 0.256)
		(layer "F.Cu")
		(net 227)
	)
	(segment
		(start 144.375501 178.300999)
		(end 144.875001 178.8005)
		(width 0.256)
		(layer "F.Cu")
		(net 227)
	)
	(segment
		(start 142.375501 178.301)
		(end 142.875001 178.8005)
		(width 0.256)
		(layer "F.Cu")
		(net 227)
	)
	(segment
		(start 144.375501 176.301)
		(end 144.875001 176.8005)
		(width 0.256)
		(layer "F.Cu")
		(net 227)
	)
	(segment
		(start 143.375501 179.301)
		(end 143.875001 179.8005)
		(width 0.256)
		(layer "F.Cu")
		(net 227)
	)
	(segment
		(start 139.375501 173.302001)
		(end 139.875001 172.8025)
		(width 0.256)
		(layer "F.Cu")
		(net 227)
	)
	(segment
		(start 137.376501 173.302)
		(end 136.877001 172.8025)
		(width 0.256)
		(layer "F.Cu")
		(net 227)
	)
	(segment
		(start 138.376501 172.301999)
		(end 137.877002 171.8025)
		(width 0.256)
		(layer "F.Cu")
		(net 227)
	)
	(segment
		(start 139.375501 171.302)
		(end 139.875001 170.8025)
		(width 0.256)
		(layer "F.Cu")
		(net 227)
	)
	(segment
		(start 138.376501 178.301)
		(end 137.877001 178.8005)
		(width 0.256)
		(layer "F.Cu")
		(net 227)
	)
	(segment
		(start 98.938 132.981)
		(end 98.17 132.981)
		(width 0.256)
		(layer "F.Cu")
		(net 227)
	)
	(via
		(at 137.877001 178.8005)
		(size 0.45)
		(drill 0.1)
		(layers "F.Cu" "B.Cu")
		(net 227)
	)
	(via
		(at 123.3 190.7)
		(size 0.45)
		(drill 0.1)
		(layers "F.Cu" "B.Cu")
		(net 227)
	)
	(via
		(at 165.4 189.4)
		(size 0.45)
		(drill 0.1)
		(layers "F.Cu" "B.Cu")
		(net 227)
	)
	(via
		(at 143.875001 175.8005)
		(size 0.45)
		(drill 0.1)
		(layers "F.Cu" "B.Cu")
		(net 227)
	)
	(via
		(at 127.875501 190.626)
		(size 0.45)
		(drill 0.1)
		(layers "F.Cu" "B.Cu")
		(net 227)
	)
	(via
		(at 126.900501 191.176)
		(size 0.45)
		(drill 0.1)
		(layers "F.Cu" "B.Cu")
		(net 227)
	)
	(via
		(at 165.5 192.1)
		(size 0.45)
		(drill 0.1)
		(layers "F.Cu" "B.Cu")
		(net 227)
	)
	(via
		(at 164.6 191.6)
		(size 0.45)
		(drill 0.1)
		(layers "F.Cu" "B.Cu")
		(net 227)
	)
	(via
		(at 164.5 198.425999)
		(size 0.45)
		(drill 0.1)
		(layers "F.Cu" "B.Cu")
		(net 227)
	)
	(via
		(at 136.877001 177.8005)
		(size 0.45)
		(drill 0.1)
		(layers "F.Cu" "B.Cu")
		(net 227)
	)
	(via
		(at 140.875001 178.8005)
		(size 0.45)
		(drill 0.1)
		(layers "F.Cu" "B.Cu")
		(net 227)
	)
	(via
		(at 166.05 189.4)
		(size 0.45)
		(drill 0.1)
		(layers "F.Cu" "B.Cu")
		(net 227)
	)
	(via
		(at 139.875001 172.8025)
		(size 0.45)
		(drill 0.1)
		(layers "F.Cu" "B.Cu")
		(net 227)
	)
	(via
		(at 165.15 198.076001)
		(size 0.45)
		(drill 0.1)
		(layers "F.Cu" "B.Cu")
		(net 227)
	)
	(via
		(at 128.200501 190.076)
		(size 0.45)
		(drill 0.1)
		(layers "F.Cu" "B.Cu")
		(net 227)
	)
	(via
		(at 164.6 194.75)
		(size 0.45)
		(drill 0.1)
		(layers "F.Cu" "B.Cu")
		(net 227)
	)
	(via
		(at 164.8 192.45)
		(size 0.45)
		(drill 0.1)
		(layers "F.Cu" "B.Cu")
		(net 227)
	)
	(via
		(at 122.9 191.25)
		(size 0.45)
		(drill 0.1)
		(layers "F.Cu" "B.Cu")
		(net 227)
	)
	(via
		(at 128.200501 191.176)
		(size 0.45)
		(drill 0.1)
		(layers "F.Cu" "B.Cu")
		(net 227)
	)
	(via
		(at 165.75 198.35)
		(size 0.45)
		(drill 0.1)
		(layers "F.Cu" "B.Cu")
		(net 227)
	)
	(via
		(at 164.7 189.4)
		(size 0.45)
		(drill 0.1)
		(layers "F.Cu" "B.Cu")
		(net 227)
	)
	(via
		(at 140.875001 171.8025)
		(size 0.45)
		(drill 0.1)
		(layers "F.Cu" "B.Cu")
		(net 227)
	)
	(via
		(at 131.650501 189.976)
		(size 0.45)
		(drill 0.1)
		(layers "F.Cu" "B.Cu")
		(net 227)
	)
	(via
		(at 165 190.8)
		(size 0.45)
		(drill 0.1)
		(layers "F.Cu" "B.Cu")
		(net 227)
	)
	(via
		(at 165.65 195.15)
		(size 0.45)
		(drill 0.1)
		(layers "F.Cu" "B.Cu")
		(net 227)
	)
	(via
		(at 139.875001 170.8025)
		(size 0.45)
		(drill 0.1)
		(layers "F.Cu" "B.Cu")
		(net 227)
	)
	(via
		(at 165.5 193.05)
		(size 0.45)
		(drill 0.1)
		(layers "F.Cu" "B.Cu")
		(net 227)
	)
	(via
		(at 136.877001 170.8025)
		(size 0.45)
		(drill 0.1)
		(layers "F.Cu" "B.Cu")
		(net 227)
	)
	(via
		(at 137.877002 171.8025)
		(size 0.45)
		(drill 0.1)
		(layers "F.Cu" "B.Cu")
		(net 227)
	)
	(via
		(at 152.4 192.6)
		(size 0.45)
		(drill 0.1)
		(layers "F.Cu" "B.Cu")
		(net 227)
	)
	(via
		(at 139.875 177.8005)
		(size 0.45)
		(drill 0.1)
		(layers "F.Cu" "B.Cu")
		(net 227)
	)
	(via
		(at 164.6 193.4)
		(size 0.45)
		(drill 0.1)
		(layers "F.Cu" "B.Cu")
		(net 227)
	)
	(via
		(at 127.550501 190.076)
		(size 0.45)
		(drill 0.1)
		(layers "F.Cu" "B.Cu")
		(net 227)
	)
	(via
		(at 154.7 188.8)
		(size 0.45)
		(drill 0.1)
		(layers "F.Cu" "B.Cu")
		(net 227)
	)
	(via
		(at 144.875001 176.8005)
		(size 0.45)
		(drill 0.1)
		(layers "F.Cu" "B.Cu")
		(net 227)
	)
	(via
		(at 164.6 197.2)
		(size 0.45)
		(drill 0.1)
		(layers "F.Cu" "B.Cu")
		(net 227)
	)
	(via
		(at 166.4 198.35)
		(size 0.45)
		(drill 0.1)
		(layers "F.Cu" "B.Cu")
		(net 227)
	)
	(via
		(at 164.6 195.95)
		(size 0.45)
		(drill 0.1)
		(layers "F.Cu" "B.Cu")
		(net 227)
	)
	(via
		(at 131.650501 191.076)
		(size 0.45)
		(drill 0.1)
		(layers "F.Cu" "B.Cu")
		(net 227)
	)
	(via
		(at 165.65 196.15)
		(size 0.45)
		(drill 0.1)
		(layers "F.Cu" "B.Cu")
		(net 227)
	)
	(via
		(at 122.9 190.15)
		(size 0.45)
		(drill 0.1)
		(layers "F.Cu" "B.Cu")
		(net 227)
	)
	(via
		(at 131.975501 190.526)
		(size 0.45)
		(drill 0.1)
		(layers "F.Cu" "B.Cu")
		(net 227)
	)
	(via
		(at 139.875001 175.8005)
		(size 0.45)
		(drill 0.1)
		(layers "F.Cu" "B.Cu")
		(net 227)
	)
	(via
		(at 136.877001 175.8005)
		(size 0.45)
		(drill 0.1)
		(layers "F.Cu" "B.Cu")
		(net 227)
	)
	(via
		(at 143.875001 179.8005)
		(size 0.45)
		(drill 0.1)
		(layers "F.Cu" "B.Cu")
		(net 227)
	)
	(via
		(at 137.877001 173.8025)
		(size 0.45)
		(drill 0.1)
		(layers "F.Cu" "B.Cu")
		(net 227)
	)
	(via
		(at 144.875001 178.8005)
		(size 0.45)
		(drill 0.1)
		(layers "F.Cu" "B.Cu")
		(net 227)
	)
	(via
		(at 142.875001 178.8005)
		(size 0.45)
		(drill 0.1)
		(layers "F.Cu" "B.Cu")
		(net 227)
	)
	(via
		(at 143.875002 177.8005)
		(size 0.45)
		(drill 0.1)
		(layers "F.Cu" "B.Cu")
		(net 227)
	)
	(via
		(at 136.877001 172.8025)
		(size 0.45)
		(drill 0.1)
		(layers "F.Cu" "B.Cu")
		(net 227)
	)
	(via
		(at 165.05 195.45)
		(size 0.45)
		(drill 0.1)
		(layers "F.Cu" "B.Cu")
		(net 227)
	)
	(via
		(at 98.17 132.981)
		(size 0.45)
		(drill 0.1)
		(layers "F.Cu" "B.Cu")
		(net 227)
	)
	(via
		(at 127.175501 190.626)
		(size 0.45)
		(drill 0.1)
		(layers "F.Cu" "B.Cu")
		(net 227)
	)
	(via
		(at 126.900501 190.076)
		(size 0.45)
		(drill 0.1)
		(layers "F.Cu" "B.Cu")
		(net 227)
	)
	(via
		(at 127.550501 191.176)
		(size 0.45)
		(drill 0.1)
		(layers "F.Cu" "B.Cu")
		(net 227)
	)
	(via
		(at 165.5 191.25)
		(size 0.45)
		(drill 0.1)
		(layers "F.Cu" "B.Cu")
		(net 227)
	)
	(via
		(at 137.877001 176.8005)
		(size 0.45)
		(drill 0.1)
		(layers "F.Cu" "B.Cu")
		(net 227)
	)
	(segment
		(start 137.879001 173.8025)
		(end 138.379001 173.3025)
		(width 0.4)
		(layer "B.Cu")
		(net 227)
	)
	(segment
		(start 139.375001 178.3045)
		(end 139.375001 178.300499)
		(width 0.4)
		(layer "B.Cu")
		(net 227)
	)
	(segment
		(start 136.377001 173.3025)
		(end 136.377001 174.1275)
		(width 0.256)
		(layer "B.Cu")
		(net 227)
	)
	(segment
		(start 144.375001 178.3005)
		(end 144.875001 178.8005)
		(width 0.4)
		(layer "B.Cu")
		(net 227)
	)
	(segment
		(start 136.877001 177.8005)
		(end 136.877001 177.8045)
		(width 0.4)
		(layer "B.Cu")
		(net 227)
	)
	(segment
		(start 143.875002 177.8005)
		(end 143.873001 177.8005)
		(width 0.4)
		(layer "B.Cu")
		(net 227)
	)
	(segment
		(start 139.375001 176.3005)
		(end 139.875001 175.8005)
		(width 0.4)
		(layer "B.Cu")
		(net 227)
	)
	(segment
		(start 137.050501 174.629)
		(end 137.877001 173.8025)
		(width 0.4)
		(layer "B.Cu")
		(net 227)
	)
	(segment
		(start 139.398501 172.326)
		(end 139.875001 172.8025)
		(width 0.4)
		(layer "B.Cu")
		(net 227)
	)
	(segment
		(start 136.877001 170.8025)
		(end 136.877001 170.804501)
		(width 0.4)
		(layer "B.Cu")
		(net 227)
	)
	(segment
		(start 137.877001 176.8005)
		(end 137.877001 176.8065)
		(width 0.4)
		(layer "B.Cu")
		(net 227)
	)
	(segment
		(start 140.375001 172.3025)
		(end 140.875001 171.8025)
		(width 0.4)
		(layer "B.Cu")
		(net 227)
	)
	(segment
		(start 137.877001 173.8025)
		(end 137.879001 173.8025)
		(width 0.4)
		(layer "B.Cu")
		(net 227)
	)
	(segment
		(start 136.877001 170.804501)
		(end 136.379002 171.3025)
		(width 0.4)
		(layer "B.Cu")
		(net 227)
	)
	(segment
		(start 143.875002 177.8005)
		(end 144.375001 178.3005)
		(width 0.4)
		(layer "B.Cu")
		(net 227)
	)
	(segment
		(start 139.375001 176.3045)
		(end 139.375001 176.3005)
		(width 0.4)
		(layer "B.Cu")
		(net 227)
	)
	(segment
		(start 136.877001 175.8005)
		(end 136.877001 174.9745)
		(width 0.4)
		(layer "B.Cu")
		(net 227)
	)
	(segment
		(start 137.877002 171.8025)
		(end 137.875001 171.8025)
		(width 0.4)
		(layer "B.Cu")
		(net 227)
	)
	(segment
		(start 143.875001 179.8005)
		(end 144.377001 180.3025)
		(width 0.4)
		(layer "B.Cu")
		(net 227)
	)
	(segment
		(start 140.375001 172.3045)
		(end 140.375001 172.3025)
		(width 0.4)
		(layer "B.Cu")
		(net 227)
	)
	(segment
		(start 140.373001 171.3025)
		(end 140.373001 171.3005)
		(width 0.4)
		(layer "B.Cu")
		(net 227)
	)
	(segment
		(start 143.873001 177.8005)
		(end 143.375001 177.3025)
		(width 0.4)
		(layer "B.Cu")
		(net 227)
	)
	(segment
		(start 136.877001 172.8025)
		(end 136.377001 173.3025)
		(width 0.4)
		(layer "B.Cu")
		(net 227)
	)
	(segment
		(start 137.375001 179.3025)
		(end 137.877001 178.8005)
		(width 0.4)
		(layer "B.Cu")
		(net 227)
	)
	(segment
		(start 140.373001 171.3005)
		(end 139.875001 170.8025)
		(width 0.4)
		(layer "B.Cu")
		(net 227)
	)
	(segment
		(start 145.373001 176.3025)
		(end 144.875001 176.8005)
		(width 0.4)
		(layer "B.Cu")
		(net 227)
	)
	(segment
		(start 139.375001 178.300499)
		(end 139.875 177.8005)
		(width 0.4)
		(layer "B.Cu")
		(net 227)
	)
	(segment
		(start 137.877001 176.8065)
		(end 138.373001 177.3025)
		(width 0.4)
		(layer "B.Cu")
		(net 227)
	)
	(segment
		(start 137.875001 171.8025)
		(end 137.375001 172.3025)
		(width 0.4)
		(layer "B.Cu")
		(net 227)
	)
	(segment
		(start 136.877001 174.9745)
		(end 137.050501 174.801)
		(width 0.4)
		(layer "B.Cu")
		(net 227)
	)
	(segment
		(start 139.398501 172.276)
		(end 139.398501 172.326)
		(width 0.4)
		(layer "B.Cu")
		(net 227)
	)
	(segment
		(start 142.373001 179.3025)
		(end 142.875001 178.8005)
		(width 0.4)
		(layer "B.Cu")
		(net 227)
	)
	(segment
		(start 136.377001 174.1275)
		(end 137.050501 174.801)
		(width 0.256)
		(layer "B.Cu")
		(net 227)
	)
	(segment
		(start 136.877001 177.8045)
		(end 137.375001 178.3025)
		(width 0.4)
		(layer "B.Cu")
		(net 227)
	)
	(segment
		(start 143.875001 175.8005)
		(end 143.373001 176.3025)
		(width 0.4)
		(layer "B.Cu")
		(net 227)
	)
	(segment
		(start 137.377001 176.3025)
		(end 137.377001 176.3005)
		(width 0.4)
		(layer "B.Cu")
		(net 227)
	)
	(segment
		(start 137.050501 174.801)
		(end 137.050501 174.629)
		(width 0.4)
		(layer "B.Cu")
		(net 227)
	)
	(segment
		(start 140.375501 178.301)
		(end 140.875001 178.8005)
		(width 0.4)
		(layer "B.Cu")
		(net 227)
	)
	(segment
		(start 137.377001 176.3005)
		(end 136.877001 175.8005)
		(width 0.4)
		(layer "B.Cu")
		(net 227)
	)
	(segment
		(start 137.375001 179.3045)
		(end 137.375001 179.3025)
		(width 0.4)
		(layer "B.Cu")
		(net 227)
	)
	(segment
		(start 131.650501 189.976)
		(end 131.676 189.976)
		(width 0.4)
		(layer "In2.Cu")
		(net 227)
	)
	(segment
		(start 146.375501 166.302)
		(end 146.875001 165.8025)
		(width 0.256)
		(layer "F.Cu")
		(net 228)
	)
	(segment
		(start 157.4 146.2025)
		(end 157.4 147.2775)
		(width 0.201)
		(layer "F.Cu")
		(net 228)
	)
	(via
		(at 146.875001 165.8025)
		(size 0.45)
		(drill 0.1)
		(layers "F.Cu" "B.Cu")
		(net 228)
	)
	(via
		(at 157.4 147.2775)
		(size 0.45)
		(drill 0.1)
		(layers "F.Cu" "B.Cu")
		(net 228)
	)
	(segment
		(start 157.4 147.2775)
		(end 156.5775 148.1)
		(width 0.148)
		(layer "In2.Cu")
		(net 228)
	)
	(segment
		(start 150.625501 150.302)
		(end 150.754693 150.302)
		(width 0.148)
		(layer "In2.Cu")
		(net 228)
	)
	(segment
		(start 146.9 159.8)
		(end 145.375001 161.324999)
		(width 0.148)
		(layer "In2.Cu")
		(net 228)
	)
	(segment
		(start 149.996309 155.302)
		(end 150.125501 155.302)
		(width 0.148)
		(layer "In2.Cu")
		(net 228)
	)
	(segment
		(start 145.848229 165.34)
		(end 146.412501 165.34)
		(width 0.148)
		(layer "In2.Cu")
		(net 228)
	)
	(segment
		(start 146.412501 165.34)
		(end 146.875001 165.8025)
		(width 0.148)
		(layer "In2.Cu")
		(net 228)
	)
	(segment
		(start 150.375501 158.424499)
		(end 149 159.8)
		(width 0.148)
		(layer "In2.Cu")
		(net 228)
	)
	(segment
		(start 156.5775 148.1)
		(end 151.7 148.1)
		(width 0.148)
		(layer "In2.Cu")
		(net 228)
	)
	(segment
		(start 149.996309 151.802)
		(end 150.754693 151.802)
		(width 0.148)
		(layer "In2.Cu")
		(net 228)
	)
	(segment
		(start 149.996309 153.802)
		(end 150.754693 153.802)
		(width 0.148)
		(layer "In2.Cu")
		(net 228)
	)
	(segment
		(start 150.754693 150.802)
		(end 150.625501 150.802)
		(width 0.148)
		(layer "In2.Cu")
		(net 228)
	)
	(segment
		(start 150.625501 150.802)
		(end 149.996309 150.802)
		(width 0.148)
		(layer "In2.Cu")
		(net 228)
	)
	(segment
		(start 149.996309 153.302)
		(end 150.754693 153.302)
		(width 0.148)
		(layer "In2.Cu")
		(net 228)
	)
	(segment
		(start 150.375501 155.552)
		(end 150.375501 158.424499)
		(width 0.148)
		(layer "In2.Cu")
		(net 228)
	)
	(segment
		(start 149.996309 151.302)
		(end 150.754693 151.302)
		(width 0.148)
		(layer "In2.Cu")
		(net 228)
	)
	(segment
		(start 149.996309 154.302)
		(end 150.754693 154.302)
		(width 0.148)
		(layer "In2.Cu")
		(net 228)
	)
	(segment
		(start 145.375001 161.324999)
		(end 145.375001 164.866772)
		(width 0.148)
		(layer "In2.Cu")
		(net 228)
	)
	(segment
		(start 151.7 148.1)
		(end 150.375501 149.424499)
		(width 0.148)
		(layer "In2.Cu")
		(net 228)
	)
	(segment
		(start 149.996309 154.802)
		(end 150.754693 154.802)
		(width 0.148)
		(layer "In2.Cu")
		(net 228)
	)
	(segment
		(start 150.375501 149.424499)
		(end 150.375501 150.052)
		(width 0.148)
		(layer "In2.Cu")
		(net 228)
	)
	(segment
		(start 149.996309 152.802)
		(end 150.754693 152.802)
		(width 0.148)
		(layer "In2.Cu")
		(net 228)
	)
	(segment
		(start 149 159.8)
		(end 146.9 159.8)
		(width 0.148)
		(layer "In2.Cu")
		(net 228)
	)
	(segment
		(start 149.996309 152.302)
		(end 150.754693 152.302)
		(width 0.148)
		(layer "In2.Cu")
		(net 228)
	)
	(segment
		(start 145.375001 164.866772)
		(end 145.848229 165.34)
		(width 0.148)
		(layer "In2.Cu")
		(net 228)
	)
	(arc
		(start 150.754693 150.302)
		(mid 150.93147 150.375223)
		(end 151.004693 150.552)
		(width 0.148)
		(layer "In2.Cu")
		(net 228)
	)
	(arc
		(start 150.125501 155.302)
		(mid 150.302278 155.375223)
		(end 150.375501 155.552)
		(width 0.148)
		(layer "In2.Cu")
		(net 228)
	)
	(arc
		(start 150.754693 152.302)
		(mid 150.93147 152.375223)
		(end 151.004693 152.552)
		(width 0.148)
		(layer "In2.Cu")
		(net 228)
	)
	(arc
		(start 149.746309 154.052)
		(mid 149.819532 154.228777)
		(end 149.996309 154.302)
		(width 0.148)
		(layer "In2.Cu")
		(net 228)
	)
	(arc
		(start 151.004693 154.552)
		(mid 150.93147 154.728777)
		(end 150.754693 154.802)
		(width 0.148)
		(layer "In2.Cu")
		(net 228)
	)
	(arc
		(start 151.004693 151.552)
		(mid 150.93147 151.728777)
		(end 150.754693 151.802)
		(width 0.148)
		(layer "In2.Cu")
		(net 228)
	)
	(arc
		(start 151.004693 150.552)
		(mid 150.93147 150.728777)
		(end 150.754693 150.802)
		(width 0.148)
		(layer "In2.Cu")
		(net 228)
	)
	(arc
		(start 150.754693 151.302)
		(mid 150.93147 151.375223)
		(end 151.004693 151.552)
		(width 0.148)
		(layer "In2.Cu")
		(net 228)
	)
	(arc
		(start 149.996309 153.802)
		(mid 149.819532 153.875223)
		(end 149.746309 154.052)
		(width 0.148)
		(layer "In2.Cu")
		(net 228)
	)
	(arc
		(start 149.746309 152.052)
		(mid 149.819532 152.228777)
		(end 149.996309 152.302)
		(width 0.148)
		(layer "In2.Cu")
		(net 228)
	)
	(arc
		(start 150.754693 153.302)
		(mid 150.93147 153.375223)
		(end 151.004693 153.552)
		(width 0.148)
		(layer "In2.Cu")
		(net 228)
	)
	(arc
		(start 151.004693 152.552)
		(mid 150.93147 152.728777)
		(end 150.754693 152.802)
		(width 0.148)
		(layer "In2.Cu")
		(net 228)
	)
	(arc
		(start 150.375501 150.052)
		(mid 150.448724 150.228777)
		(end 150.625501 150.302)
		(width 0.148)
		(layer "In2.Cu")
		(net 228)
	)
	(arc
		(start 149.996309 151.802)
		(mid 149.819532 151.875223)
		(end 149.746309 152.052)
		(width 0.148)
		(layer "In2.Cu")
		(net 228)
	)
	(arc
		(start 149.746309 151.052)
		(mid 149.819532 151.228777)
		(end 149.996309 151.302)
		(width 0.148)
		(layer "In2.Cu")
		(net 228)
	)
	(arc
		(start 149.746309 153.052)
		(mid 149.819532 153.228777)
		(end 149.996309 153.302)
		(width 0.148)
		(layer "In2.Cu")
		(net 228)
	)
	(arc
		(start 149.996309 150.802)
		(mid 149.819532 150.875223)
		(end 149.746309 151.052)
		(width 0.148)
		(layer "In2.Cu")
		(net 228)
	)
	(arc
		(start 149.996309 152.802)
		(mid 149.819532 152.875223)
		(end 149.746309 153.052)
		(width 0.148)
		(layer "In2.Cu")
		(net 228)
	)
	(arc
		(start 149.746309 155.052)
		(mid 149.819532 155.228777)
		(end 149.996309 155.302)
		(width 0.148)
		(layer "In2.Cu")
		(net 228)
	)
	(arc
		(start 150.754693 154.302)
		(mid 150.93147 154.375223)
		(end 151.004693 154.552)
		(width 0.148)
		(layer "In2.Cu")
		(net 228)
	)
	(arc
		(start 149.996309 154.802)
		(mid 149.819532 154.875223)
		(end 149.746309 155.052)
		(width 0.148)
		(layer "In2.Cu")
		(net 228)
	)
	(arc
		(start 151.004693 153.552)
		(mid 150.93147 153.728777)
		(end 150.754693 153.802)
		(width 0.148)
		(layer "In2.Cu")
		(net 228)
	)
	(segment
		(start 114.3 193.970501)
		(end 114.2 193.870501)
		(width 0.4)
		(layer "F.Cu")
		(net 229)
	)
	(segment
		(start 114.1 192.8)
		(end 114.1 193.5)
		(width 0.4)
		(layer "F.Cu")
		(net 229)
	)
	(segment
		(start 114.2 192.7)
		(end 114.1 192.8)
		(width 0.4)
		(layer "F.Cu")
		(net 229)
	)
	(segment
		(start 114.3 193.970501)
		(end 114.3 193.7)
		(width 0.4)
		(layer "F.Cu")
		(net 229)
	)
	(segment
		(start 114.2 193.870501)
		(end 114.2 193.6)
		(width 0.4)
		(layer "F.Cu")
		(net 229)
	)
	(segment
		(start 114.1 193.5)
		(end 114.2 193.6)
		(width 0.4)
		(layer "F.Cu")
		(net 229)
	)
	(segment
		(start 115.35 192.7)
		(end 114.2 192.7)
		(width 0.4)
		(layer "F.Cu")
		(net 229)
	)
	(segment
		(start 114.2 193.6)
		(end 114.3 193.7)
		(width 0.4)
		(layer "F.Cu")
		(net 229)
	)
	(segment
		(start 114.3 193.970501)
		(end 114.1 193.770501)
		(width 0.4)
		(layer "F.Cu")
		(net 229)
	)
	(segment
		(start 114.1 193.770501)
		(end 114.1 192.8)
		(width 0.4)
		(layer "F.Cu")
		(net 229)
	)
	(segment
		(start 114.1 193.7)
		(end 115.35 193.7)
		(width 0.4)
		(layer "F.Cu")
		(net 229)
	)
	(via
		(at 114.525501 206.400501)
		(size 0.45)
		(drill 0.1)
		(layers "F.Cu" "B.Cu")
		(net 229)
	)
	(via
		(at 114.3 193.970501)
		(size 0.45)
		(drill 0.1)
		(layers "F.Cu" "B.Cu")
		(net 229)
	)
	(segment
		(start 114.525501 206.400501)
		(end 114.525501 210.306)
		(width 0.256)
		(layer "B.Cu")
		(net 229)
	)
	(segment
		(start 114.329499 194)
		(end 117.9 194)
		(width 0.1)
		(layer "In2.Cu")
		(net 229)
	)
	(segment
		(start 114.525501 205.364499)
		(end 114.525501 206.400501)
		(width 0.1)
		(layer "In2.Cu")
		(net 229)
	)
	(segment
		(start 119.7 200.19)
		(end 114.525501 205.364499)
		(width 0.1)
		(layer "In2.Cu")
		(net 229)
	)
	(segment
		(start 114.3 193.970501)
		(end 114.329499 194)
		(width 0.1)
		(layer "In2.Cu")
		(net 229)
	)
	(segment
		(start 117.9 194)
		(end 119.7 195.8)
		(width 0.1)
		(layer "In2.Cu")
		(net 229)
	)
	(segment
		(start 119.7 195.8)
		(end 119.7 200.19)
		(width 0.1)
		(layer "In2.Cu")
		(net 229)
	)
	(segment
		(start 122.2 192.7)
		(end 122.4 192.5)
		(width 0.4)
		(layer "F.Cu")
		(net 230)
	)
	(segment
		(start 132.225001 206.200501)
		(end 132.225001 207.300501)
		(width 0.256)
		(layer "F.Cu")
		(net 230)
	)
	(segment
		(start 133.475001 206.000501)
		(end 133.175001 205.700501)
		(width 0.256)
		(layer "F.Cu")
		(net 230)
	)
	(segment
		(start 133.175001 205.700501)
		(end 132.725001 205.700501)
		(width 0.256)
		(layer "F.Cu")
		(net 230)
	)
	(segment
		(start 132.225001 207.300501)
		(end 132.525501 207.601001)
		(width 0.256)
		(layer "F.Cu")
		(net 230)
	)
	(segment
		(start 121.25 192.7)
		(end 122.2 192.7)
		(width 0.4)
		(layer "F.Cu")
		(net 230)
	)
	(segment
		(start 132.525501 207.601001)
		(end 132.525501 210.306)
		(width 0.256)
		(layer "F.Cu")
		(net 230)
	)
	(segment
		(start 132.725001 205.700501)
		(end 132.225001 206.200501)
		(width 0.256)
		(layer "F.Cu")
		(net 230)
	)
	(via
		(at 133.475001 206.000501)
		(size 0.45)
		(drill 0.1)
		(layers "F.Cu" "B.Cu")
		(net 230)
	)
	(via
		(at 122.4 192.5)
		(size 0.45)
		(drill 0.1)
		(layers "F.Cu" "B.Cu")
		(net 230)
	)
	(segment
		(start 133.475001 206.000501)
		(end 131.7245 204.25)
		(width 0.1)
		(layer "In2.Cu")
		(net 230)
	)
	(segment
		(start 122.75 204.25)
		(end 120.4 201.9)
		(width 0.1)
		(layer "In2.Cu")
		(net 230)
	)
	(segment
		(start 131.7245 204.25)
		(end 122.75 204.25)
		(width 0.1)
		(layer "In2.Cu")
		(net 230)
	)
	(segment
		(start 120.4 194.5)
		(end 122.4 192.5)
		(width 0.1)
		(layer "In2.Cu")
		(net 230)
	)
	(segment
		(start 120.4 201.9)
		(end 120.4 194.5)
		(width 0.1)
		(layer "In2.Cu")
		(net 230)
	)
	(segment
		(start 122.0255 193.7)
		(end 122.4 194.0745)
		(width 0.4)
		(layer "F.Cu")
		(net 231)
	)
	(segment
		(start 146.525501 205.950001)
		(end 146.525501 210.306)
		(width 0.256)
		(layer "F.Cu")
		(net 231)
	)
	(segment
		(start 121.25 193.7)
		(end 122.0255 193.7)
		(width 0.4)
		(layer "F.Cu")
		(net 231)
	)
	(via
		(at 122.4 194.0745)
		(size 0.45)
		(drill 0.1)
		(layers "F.Cu" "B.Cu")
		(net 231)
	)
	(via
		(at 146.525501 205.950001)
		(size 0.45)
		(drill 0.1)
		(layers "F.Cu" "B.Cu")
		(net 231)
	)
	(segment
		(start 146.525501 205.950001)
		(end 146.525501 204.725501)
		(width 0.1)
		(layer "In2.Cu")
		(net 231)
	)
	(segment
		(start 146.525501 204.725501)
		(end 143.1 201.3)
		(width 0.1)
		(layer "In2.Cu")
		(net 231)
	)
	(segment
		(start 121.4 195.0745)
		(end 122.4 194.0745)
		(width 0.1)
		(layer "In2.Cu")
		(net 231)
	)
	(segment
		(start 143.1 201.3)
		(end 122 201.3)
		(width 0.1)
		(layer "In2.Cu")
		(net 231)
	)
	(segment
		(start 121.4 200.7)
		(end 121.4 195.0745)
		(width 0.1)
		(layer "In2.Cu")
		(net 231)
	)
	(segment
		(start 122 201.3)
		(end 121.4 200.7)
		(width 0.1)
		(layer "In2.Cu")
		(net 231)
	)
	(segment
		(start 200.196 177.172)
		(end 199.773 177.172)
		(width 0.1)
		(layer "F.Cu")
		(net 232)
	)
	(segment
		(start 180.139 185.661)
		(end 180.1 185.7)
		(width 0.2)
		(layer "F.Cu")
		(net 232)
	)
	(segment
		(start 180.926107 185.661)
		(end 180.139 185.661)
		(width 0.2)
		(layer "F.Cu")
		(net 232)
	)
	(via
		(at 180.1 185.7)
		(size 0.45)
		(drill 0.1)
		(layers "F.Cu" "B.Cu")
		(net 232)
	)
	(via
		(at 199.773 177.172)
		(size 0.45)
		(drill 0.1)
		(layers "F.Cu" "B.Cu")
		(net 232)
	)
	(segment
		(start 182.433172 185.50825)
		(end 184.4 183.541422)
		(width 0.1)
		(layer "In4.Cu")
		(net 232)
	)
	(segment
		(start 184.4 183.541422)
		(end 184.4 178.841422)
		(width 0.1)
		(layer "In4.Cu")
		(net 232)
	)
	(segment
		(start 184.4 178.841422)
		(end 185.341422 177.9)
		(width 0.1)
		(layer "In4.Cu")
		(net 232)
	)
	(segment
		(start 198.841422 178.5)
		(end 199.598 177.743422)
		(width 0.1)
		(layer "In4.Cu")
		(net 232)
	)
	(segment
		(start 199.598 177.743422)
		(end 199.598 177.347)
		(width 0.1)
		(layer "In4.Cu")
		(net 232)
	)
	(segment
		(start 180.29175 185.50825)
		(end 182.433172 185.50825)
		(width 0.1)
		(layer "In4.Cu")
		(net 232)
	)
	(segment
		(start 185.341422 177.9)
		(end 197.258578 177.9)
		(width 0.1)
		(layer "In4.Cu")
		(net 232)
	)
	(segment
		(start 197.858578 178.5)
		(end 198.841422 178.5)
		(width 0.1)
		(layer "In4.Cu")
		(net 232)
	)
	(segment
		(start 199.598 177.347)
		(end 199.773 177.172)
		(width 0.1)
		(layer "In4.Cu")
		(net 232)
	)
	(segment
		(start 197.258578 177.9)
		(end 197.858578 178.5)
		(width 0.1)
		(layer "In4.Cu")
		(net 232)
	)
	(segment
		(start 180.1 185.7)
		(end 180.29175 185.50825)
		(width 0.1)
		(layer "In4.Cu")
		(net 232)
	)
	(segment
		(start 158.150002 138.8025)
		(end 158.150002 139.8775)
		(width 0.201)
		(layer "F.Cu")
		(net 233)
	)
	(segment
		(start 146.375501 168.302)
		(end 146.875001 167.802499)
		(width 0.256)
		(layer "F.Cu")
		(net 233)
	)
	(via
		(at 158.150002 139.8775)
		(size 0.45)
		(drill 0.1)
		(layers "F.Cu" "B.Cu")
		(net 233)
	)
	(via
		(at 146.875001 167.802499)
		(size 0.45)
		(drill 0.1)
		(layers "F.Cu" "B.Cu")
		(net 233)
	)
	(segment
		(start 155.152929 143.267194)
		(end 155.152929 143.267193)
		(width 0.148)
		(layer "In2.Cu")
		(net 233)
	)
	(segment
		(start 145.99064 166.2775)
		(end 146.475001 166.761861)
		(width 0.148)
		(layer "In2.Cu")
		(net 233)
	)
	(segment
		(start 155.486948 142.187)
		(end 155.467415 142.167467)
		(width 0.148)
		(layer "In2.Cu")
		(net 233)
	)
	(segment
		(start 144.628001 165.2555)
		(end 145.062639 165.2555)
		(width 0.148)
		(layer "In2.Cu")
		(net 233)
	)
	(segment
		(start 154.406756 143.228125)
		(end 154.406756 143.228126)
		(width 0.148)
		(layer "In2.Cu")
		(net 233)
	)
	(segment
		(start 145.062639 165.2555)
		(end 145.350001 165.542862)
		(width 0.148)
		(layer "In2.Cu")
		(net 233)
	)
	(segment
		(start 145.350001 165.542862)
		(end 145.350001 166.0775)
		(width 0.148)
		(layer "In2.Cu")
		(net 233)
	)
	(segment
		(start 145.550001 166.2775)
		(end 145.99064 166.2775)
		(width 0.148)
		(layer "In2.Cu")
		(net 233)
	)
	(segment
		(start 154.406756 142.874574)
		(end 154.406756 142.874573)
		(width 0.148)
		(layer "In2.Cu")
		(net 233)
	)
	(segment
		(start 149.125501 156.474499)
		(end 144.375001 161.224999)
		(width 0.148)
		(layer "In2.Cu")
		(net 233)
	)
	(segment
		(start 145.350001 166.0775)
		(end 145.550001 166.2775)
		(width 0.148)
		(layer "In2.Cu")
		(net 233)
	)
	(segment
		(start 150.1 144.8)
		(end 150.1 146)
		(width 0.148)
		(layer "In2.Cu")
		(net 233)
	)
	(segment
		(start 144.375001 165.0025)
		(end 144.628001 165.2555)
		(width 0.148)
		(layer "In2.Cu")
		(net 233)
	)
	(segment
		(start 150.1 146)
		(end 149.125501 146.974499)
		(width 0.148)
		(layer "In2.Cu")
		(net 233)
	)
	(segment
		(start 154.426288 143.601211)
		(end 153.827502 144.2)
		(width 0.148)
		(layer "In2.Cu")
		(net 233)
	)
	(segment
		(start 155.113862 142.52102)
		(end 155.506482 142.91364)
		(width 0.148)
		(layer "In2.Cu")
		(net 233)
	)
	(segment
		(start 155.113861 142.167467)
		(end 155.113862 142.167467)
		(width 0.148)
		(layer "In2.Cu")
		(net 233)
	)
	(segment
		(start 155.506481 143.267193)
		(end 155.506481 143.267194)
		(width 0.148)
		(layer "In2.Cu")
		(net 233)
	)
	(segment
		(start 155.113862 142.521019)
		(end 155.113862 142.52102)
		(width 0.148)
		(layer "In2.Cu")
		(net 233)
	)
	(segment
		(start 144.375001 161.224999)
		(end 144.375001 165.0025)
		(width 0.148)
		(layer "In2.Cu")
		(net 233)
	)
	(segment
		(start 146.475001 166.761861)
		(end 146.475001 167.402499)
		(width 0.148)
		(layer "In2.Cu")
		(net 233)
	)
	(segment
		(start 150.7 144.2)
		(end 150.1 144.8)
		(width 0.148)
		(layer "In2.Cu")
		(net 233)
	)
	(segment
		(start 158.150002 139.8775)
		(end 155.840502 142.187)
		(width 0.148)
		(layer "In2.Cu")
		(net 233)
	)
	(segment
		(start 155.152929 143.267193)
		(end 154.760309 142.874573)
		(width 0.148)
		(layer "In2.Cu")
		(net 233)
	)
	(segment
		(start 149.125501 146.974499)
		(end 149.125501 156.474499)
		(width 0.148)
		(layer "In2.Cu")
		(net 233)
	)
	(segment
		(start 154.406756 143.228126)
		(end 154.426288 143.247658)
		(width 0.148)
		(layer "In2.Cu")
		(net 233)
	)
	(segment
		(start 146.475001 167.402499)
		(end 146.875001 167.802499)
		(width 0.148)
		(layer "In2.Cu")
		(net 233)
	)
	(segment
		(start 153.827502 144.2)
		(end 150.7 144.2)
		(width 0.148)
		(layer "In2.Cu")
		(net 233)
	)
	(segment
		(start 154.426288 143.601212)
		(end 154.426288 143.601211)
		(width 0.148)
		(layer "In2.Cu")
		(net 233)
	)
	(arc
		(start 155.506482 142.91364)
		(mid 155.579705 143.090417)
		(end 155.506481 143.267193)
		(width 0.148)
		(layer "In2.Cu")
		(net 233)
	)
	(arc
		(start 155.840502 142.187)
		(mid 155.663725 142.260223)
		(end 155.486948 142.187)
		(width 0.148)
		(layer "In2.Cu")
		(net 233)
	)
	(arc
		(start 154.760309 142.874573)
		(mid 154.583532 142.80135)
		(end 154.406756 142.874574)
		(width 0.148)
		(layer "In2.Cu")
		(net 233)
	)
	(arc
		(start 155.113862 142.167467)
		(mid 155.040639 142.344243)
		(end 155.113862 142.521019)
		(width 0.148)
		(layer "In2.Cu")
		(net 233)
	)
	(arc
		(start 154.426288 143.247658)
		(mid 154.499511 143.424435)
		(end 154.426288 143.601212)
		(width 0.148)
		(layer "In2.Cu")
		(net 233)
	)
	(arc
		(start 155.467415 142.167467)
		(mid 155.290638 142.094244)
		(end 155.113861 142.167467)
		(width 0.148)
		(layer "In2.Cu")
		(net 233)
	)
	(arc
		(start 155.506481 143.267194)
		(mid 155.329706 143.340416)
		(end 155.152929 143.267194)
		(width 0.148)
		(layer "In2.Cu")
		(net 233)
	)
	(arc
		(start 154.406756 142.874573)
		(mid 154.333533 143.051349)
		(end 154.406756 143.228125)
		(width 0.148)
		(layer "In2.Cu")
		(net 233)
	)
	(segment
		(start 132.376501 187.301)
		(end 131.877001 187.8005)
		(width 0.256)
		(layer "F.Cu")
		(net 234)
	)
	(segment
		(start 103.050501 116.126)
		(end 103.750501 116.126)
		(width 0.15)
		(layer "F.Cu")
		(net 234)
	)
	(segment
		(start 103.750501 116.126)
		(end 103.800501 116.176)
		(width 0.15)
		(layer "F.Cu")
		(net 234)
	)
	(via
		(at 103.800501 116.176)
		(size 0.45)
		(drill 0.1)
		(layers "F.Cu" "B.Cu")
		(net 234)
	)
	(via
		(at 131.877001 187.8005)
		(size 0.45)
		(drill 0.1)
		(layers "F.Cu" "B.Cu")
		(net 234)
	)
	(segment
		(start 81.4 149.4)
		(end 81.4 158.475499)
		(width 0.1)
		(layer "In2.Cu")
		(net 234)
	)
	(segment
		(start 103.800501 116.176)
		(end 102.45 117.526501)
		(width 0.1)
		(layer "In2.Cu")
		(net 234)
	)
	(segment
		(start 81.4 158.475499)
		(end 87.750501 164.826)
		(width 0.1)
		(layer "In2.Cu")
		(net 234)
	)
	(segment
		(start 111.1 187.3)
		(end 102.6 178.8)
		(width 0.1)
		(layer "In2.Cu")
		(net 234)
	)
	(segment
		(start 94.076501 126)
		(end 90.500501 129.576)
		(width 0.1)
		(layer "In2.Cu")
		(net 234)
	)
	(segment
		(start 87.750501 164.826)
		(end 100.426 164.826)
		(width 0.1)
		(layer "In2.Cu")
		(net 234)
	)
	(segment
		(start 131.376501 187.3)
		(end 111.1 187.3)
		(width 0.1)
		(layer "In2.Cu")
		(net 234)
	)
	(segment
		(start 95.2 126)
		(end 94.076501 126)
		(width 0.1)
		(layer "In2.Cu")
		(net 234)
	)
	(segment
		(start 102.45 117.526501)
		(end 102.45 118.75)
		(width 0.1)
		(layer "In2.Cu")
		(net 234)
	)
	(segment
		(start 90.500501 140.299499)
		(end 81.4 149.4)
		(width 0.1)
		(layer "In2.Cu")
		(net 234)
	)
	(segment
		(start 90.500501 129.576)
		(end 90.500501 140.299499)
		(width 0.1)
		(layer "In2.Cu")
		(net 234)
	)
	(segment
		(start 102.45 118.75)
		(end 95.2 126)
		(width 0.1)
		(layer "In2.Cu")
		(net 234)
	)
	(segment
		(start 102.6 167)
		(end 102.6 178.8)
		(width 0.1)
		(layer "In2.Cu")
		(net 234)
	)
	(segment
		(start 131.376501 187.3)
		(end 131.877001 187.8005)
		(width 0.1)
		(layer "In2.Cu")
		(net 234)
	)
	(segment
		(start 100.426 164.826)
		(end 102.6 167)
		(width 0.1)
		(layer "In2.Cu")
		(net 234)
	)
	(segment
		(start 103.050501 121.526)
		(end 103.750501 121.526)
		(width 0.15)
		(layer "F.Cu")
		(net 235)
	)
	(segment
		(start 129.376501 184.301001)
		(end 128.877002 184.8005)
		(width 0.256)
		(layer "F.Cu")
		(net 235)
	)
	(segment
		(start 103.750501 121.526)
		(end 103.800501 121.576)
		(width 0.15)
		(layer "F.Cu")
		(net 235)
	)
	(via
		(at 128.877002 184.8005)
		(size 0.45)
		(drill 0.1)
		(layers "F.Cu" "B.Cu")
		(net 235)
	)
	(via
		(at 103.800501 121.576)
		(size 0.45)
		(drill 0.1)
		(layers "F.Cu" "B.Cu")
		(net 235)
	)
	(segment
		(start 128.2 186.3)
		(end 112.5 186.3)
		(width 0.1)
		(layer "In2.Cu")
		(net 235)
	)
	(segment
		(start 106.275 178.525)
		(end 106.725 178.975)
		(width 0.1)
		(layer "In2.Cu")
		(net 235)
	)
	(segment
		(start 82 157.875499)
		(end 87.600501 163.476)
		(width 0.1)
		(layer "In2.Cu")
		(net 235)
	)
	(segment
		(start 106.725 181.075)
		(end 107.35 181.7)
		(width 0.1)
		(layer "In2.Cu")
		(net 235)
	)
	(segment
		(start 103.700501 177.500501)
		(end 104.725 178.525)
		(width 0.1)
		(layer "In2.Cu")
		(net 235)
	)
	(segment
		(start 128.4 185.277502)
		(end 128.877002 184.8005)
		(width 0.1)
		(layer "In2.Cu")
		(net 235)
	)
	(segment
		(start 104.725 178.525)
		(end 106.275 178.525)
		(width 0.1)
		(layer "In2.Cu")
		(net 235)
	)
	(segment
		(start 87.600501 163.476)
		(end 100.376 163.476)
		(width 0.1)
		(layer "In2.Cu")
		(net 235)
	)
	(segment
		(start 101.699707 121.576)
		(end 91.6 131.675707)
		(width 0.1)
		(layer "In2.Cu")
		(net 235)
	)
	(segment
		(start 128.2 186.3)
		(end 128.4 186.1)
		(width 0.1)
		(layer "In2.Cu")
		(net 235)
	)
	(segment
		(start 82 150)
		(end 82 157.875499)
		(width 0.1)
		(layer "In2.Cu")
		(net 235)
	)
	(segment
		(start 100.376 163.476)
		(end 103.700501 166.800501)
		(width 0.1)
		(layer "In2.Cu")
		(net 235)
	)
	(segment
		(start 91.6 131.675707)
		(end 91.6 140.4)
		(width 0.1)
		(layer "In2.Cu")
		(net 235)
	)
	(segment
		(start 107.35 181.7)
		(end 108.3 181.7)
		(width 0.1)
		(layer "In2.Cu")
		(net 235)
	)
	(segment
		(start 103.800501 121.576)
		(end 101.699707 121.576)
		(width 0.1)
		(layer "In2.Cu")
		(net 235)
	)
	(segment
		(start 128.4 186.1)
		(end 128.4 185.277502)
		(width 0.1)
		(layer "In2.Cu")
		(net 235)
	)
	(segment
		(start 106.725 178.975)
		(end 106.725 181.075)
		(width 0.1)
		(layer "In2.Cu")
		(net 235)
	)
	(segment
		(start 103.700501 166.800501)
		(end 103.700501 177.500501)
		(width 0.1)
		(layer "In2.Cu")
		(net 235)
	)
	(segment
		(start 112.5 186.3)
		(end 108.95 182.75)
		(width 0.1)
		(layer "In2.Cu")
		(net 235)
	)
	(segment
		(start 108.3 181.7)
		(end 108.95 182.35)
		(width 0.1)
		(layer "In2.Cu")
		(net 235)
	)
	(segment
		(start 91.6 140.4)
		(end 82 150)
		(width 0.1)
		(layer "In2.Cu")
		(net 235)
	)
	(segment
		(start 108.95 182.35)
		(end 108.95 182.75)
		(width 0.1)
		(layer "In2.Cu")
		(net 235)
	)
	(segment
		(start 103.050501 118.826)
		(end 103.750501 118.826)
		(width 0.15)
		(layer "F.Cu")
		(net 236)
	)
	(segment
		(start 103.750501 118.826)
		(end 103.800501 118.876)
		(width 0.15)
		(layer "F.Cu")
		(net 236)
	)
	(segment
		(start 131.376501 183.301)
		(end 130.877001 183.8005)
		(width 0.256)
		(layer "F.Cu")
		(net 236)
	)
	(via
		(at 130.877001 183.8005)
		(size 0.45)
		(drill 0.1)
		(layers "F.Cu" "B.Cu")
		(net 236)
	)
	(via
		(at 103.800501 118.876)
		(size 0.45)
		(drill 0.1)
		(layers "F.Cu" "B.Cu")
		(net 236)
	)
	(segment
		(start 87.500501 162.176)
		(end 82.7 157.375499)
		(width 0.1)
		(layer "In2.Cu")
		(net 236)
	)
	(segment
		(start 104.400501 175.150501)
		(end 104.400501 164.700501)
		(width 0.1)
		(layer "In2.Cu")
		(net 236)
	)
	(segment
		(start 130.377501 184.3)
		(end 127.6 184.3)
		(width 0.1)
		(layer "In2.Cu")
		(net 236)
	)
	(segment
		(start 127.6 184.3)
		(end 127.4 184.5)
		(width 0.1)
		(layer "In2.Cu")
		(net 236)
	)
	(segment
		(start 102.725501 123.951)
		(end 104.600501 122.076)
		(width 0.1)
		(layer "In2.Cu")
		(net 236)
	)
	(segment
		(start 114.55 185.3)
		(end 104.400501 175.150501)
		(width 0.1)
		(layer "In2.Cu")
		(net 236)
	)
	(segment
		(start 101.649 123.951)
		(end 102.725501 123.951)
		(width 0.1)
		(layer "In2.Cu")
		(net 236)
	)
	(segment
		(start 92.800501 132.799499)
		(end 101.649 123.951)
		(width 0.1)
		(layer "In2.Cu")
		(net 236)
	)
	(segment
		(start 104.600501 119.676)
		(end 103.800501 118.876)
		(width 0.1)
		(layer "In2.Cu")
		(net 236)
	)
	(segment
		(start 127.4 184.5)
		(end 127.4 185.1)
		(width 0.1)
		(layer "In2.Cu")
		(net 236)
	)
	(segment
		(start 104.400501 164.700501)
		(end 101.876 162.176)
		(width 0.1)
		(layer "In2.Cu")
		(net 236)
	)
	(segment
		(start 127.4 185.1)
		(end 127.2 185.3)
		(width 0.1)
		(layer "In2.Cu")
		(net 236)
	)
	(segment
		(start 82.7 157.375499)
		(end 82.7 150.6)
		(width 0.1)
		(layer "In2.Cu")
		(net 236)
	)
	(segment
		(start 104.600501 122.076)
		(end 104.600501 119.676)
		(width 0.1)
		(layer "In2.Cu")
		(net 236)
	)
	(segment
		(start 127.2 185.3)
		(end 114.55 185.3)
		(width 0.1)
		(layer "In2.Cu")
		(net 236)
	)
	(segment
		(start 82.7 150.6)
		(end 92.800501 140.499499)
		(width 0.1)
		(layer "In2.Cu")
		(net 236)
	)
	(segment
		(start 101.876 162.176)
		(end 87.500501 162.176)
		(width 0.1)
		(layer "In2.Cu")
		(net 236)
	)
	(segment
		(start 130.877001 183.8005)
		(end 130.377501 184.3)
		(width 0.1)
		(layer "In2.Cu")
		(net 236)
	)
	(segment
		(start 92.800501 140.499499)
		(end 92.800501 132.799499)
		(width 0.1)
		(layer "In2.Cu")
		(net 236)
	)
	(segment
		(start 198.8 177.173)
		(end 199.222 177.173)
		(width 0.1)
		(layer "F.Cu")
		(net 237)
	)
	(segment
		(start 180.1445 185.161)
		(end 180.1 185.1165)
		(width 0.2)
		(layer "F.Cu")
		(net 237)
	)
	(segment
		(start 180.926107 185.161)
		(end 180.1445 185.161)
		(width 0.2)
		(layer "F.Cu")
		(net 237)
	)
	(via
		(at 180.1 185.1165)
		(size 0.45)
		(drill 0.1)
		(layers "F.Cu" "B.Cu")
		(net 237)
	)
	(via
		(at 199.223 177.172)
		(size 0.45)
		(drill 0.1)
		(layers "F.Cu" "B.Cu")
		(net 237)
	)
	(segment
		(start 185.258578 177.7)
		(end 184.2 178.758578)
		(width 0.1)
		(layer "In4.Cu")
		(net 237)
	)
	(segment
		(start 198.930734 178.127841)
		(end 198.758578 178.3)
		(width 0.1)
		(layer "In4.Cu")
		(net 237)
	)
	(segment
		(start 199.107512 177.774289)
		(end 199.072156 177.738933)
		(width 0.1)
		(layer "In4.Cu")
		(net 237)
	)
	(segment
		(start 198.895379 177.915709)
		(end 198.930734 177.951064)
		(width 0.1)
		(layer "In4.Cu")
		(net 237)
	)
	(segment
		(start 198.895379 177.738934)
		(end 198.895379 177.738933)
		(width 0.1)
		(layer "In4.Cu")
		(net 237)
	)
	(segment
		(start 199.107511 177.774289)
		(end 199.107512 177.774289)
		(width 0.1)
		(layer "In4.Cu")
		(net 237)
	)
	(segment
		(start 182.350328 185.30825)
		(end 180.29175 185.30825)
		(width 0.1)
		(layer "In4.Cu")
		(net 237)
	)
	(segment
		(start 184.2 183.458578)
		(end 182.350328 185.30825)
		(width 0.1)
		(layer "In4.Cu")
		(net 237)
	)
	(segment
		(start 180.29175 185.30825)
		(end 180.1 185.1165)
		(width 0.1)
		(layer "In4.Cu")
		(net 237)
	)
	(segment
		(start 198.1 178.3)
		(end 197.941422 178.3)
		(width 0.1)
		(layer "In4.Cu")
		(net 237)
	)
	(segment
		(start 198.758578 178.3)
		(end 198.65 178.3)
		(width 0.1)
		(layer "In4.Cu")
		(net 237)
	)
	(segment
		(start 199.398 177.660578)
		(end 199.284289 177.774289)
		(width 0.1)
		(layer "In4.Cu")
		(net 237)
	)
	(segment
		(start 198.15 178.3)
		(end 198.1 178.3)
		(width 0.1)
		(layer "In4.Cu")
		(net 237)
	)
	(segment
		(start 198.930733 178.127841)
		(end 198.930734 178.127841)
		(width 0.1)
		(layer "In4.Cu")
		(net 237)
	)
	(segment
		(start 197.941422 178.3)
		(end 197.341422 177.7)
		(width 0.1)
		(layer "In4.Cu")
		(net 237)
	)
	(segment
		(start 199.223 177.172)
		(end 199.398 177.347)
		(width 0.1)
		(layer "In4.Cu")
		(net 237)
	)
	(segment
		(start 199.398 177.347)
		(end 199.398 177.660578)
		(width 0.1)
		(layer "In4.Cu")
		(net 237)
	)
	(segment
		(start 184.2 178.758578)
		(end 184.2 183.458578)
		(width 0.1)
		(layer "In4.Cu")
		(net 237)
	)
	(segment
		(start 197.341422 177.7)
		(end 185.258578 177.7)
		(width 0.1)
		(layer "In4.Cu")
		(net 237)
	)
	(arc
		(start 198.895379 177.738933)
		(mid 198.858767 177.827321)
		(end 198.895379 177.915709)
		(width 0.1)
		(layer "In4.Cu")
		(net 237)
	)
	(arc
		(start 198.65 178.3)
		(mid 198.561612 178.263388)
		(end 198.525 178.175)
		(width 0.1)
		(layer "In4.Cu")
		(net 237)
	)
	(arc
		(start 198.930734 177.951064)
		(mid 198.967345 178.039453)
		(end 198.930733 178.127841)
		(width 0.1)
		(layer "In4.Cu")
		(net 237)
	)
	(arc
		(start 199.284289 177.774289)
		(mid 199.1959 177.810901)
		(end 199.107511 177.774289)
		(width 0.1)
		(layer "In4.Cu")
		(net 237)
	)
	(arc
		(start 199.072156 177.738933)
		(mid 198.983767 177.702322)
		(end 198.895379 177.738934)
		(width 0.1)
		(layer "In4.Cu")
		(net 237)
	)
	(arc
		(start 198.4 178.05)
		(mid 198.311612 178.086612)
		(end 198.275 178.175)
		(width 0.1)
		(layer "In4.Cu")
		(net 237)
	)
	(arc
		(start 198.525 178.175)
		(mid 198.488388 178.086612)
		(end 198.4 178.05)
		(width 0.1)
		(layer "In4.Cu")
		(net 237)
	)
	(arc
		(start 198.275 178.175)
		(mid 198.238388 178.263388)
		(end 198.15 178.3)
		(width 0.1)
		(layer "In4.Cu")
		(net 237)
	)
	(segment
		(start 147.375501 168.302)
		(end 147.875001 167.8025)
		(width 0.256)
		(layer "F.Cu")
		(net 238)
	)
	(segment
		(start 158.400001 146.2025)
		(end 158.4 147.277499)
		(width 0.201)
		(layer "F.Cu")
		(net 238)
	)
	(via
		(at 158.4 147.277499)
		(size 0.45)
		(drill 0.1)
		(layers "F.Cu" "B.Cu")
		(net 238)
	)
	(via
		(at 147.875001 167.8025)
		(size 0.45)
		(drill 0.1)
		(layers "F.Cu" "B.Cu")
		(net 238)
	)
	(segment
		(start 150.75 161)
		(end 147.7 161)
		(width 0.148)
		(layer "In2.Cu")
		(net 238)
	)
	(segment
		(start 147.375001 161.324999)
		(end 147.375001 167.3025)
		(width 0.148)
		(layer "In2.Cu")
		(net 238)
	)
	(segment
		(start 157.75 149)
		(end 154.4 149)
		(width 0.148)
		(layer "In2.Cu")
		(net 238)
	)
	(segment
		(start 152.562418 155.302)
		(end 152.875501 155.302)
		(width 0.148)
		(layer "In2.Cu")
		(net 238)
	)
	(segment
		(start 154.4 149)
		(end 153.125501 150.274499)
		(width 0.148)
		(layer "In2.Cu")
		(net 238)
	)
	(segment
		(start 147.7 161)
		(end 147.375001 161.324999)
		(width 0.148)
		(layer "In2.Cu")
		(net 238)
	)
	(segment
		(start 152.562418 153.802)
		(end 153.688584 153.802)
		(width 0.148)
		(layer "In2.Cu")
		(net 238)
	)
	(segment
		(start 152.562418 154.802)
		(end 153.688584 154.802)
		(width 0.148)
		(layer "In2.Cu")
		(net 238)
	)
	(segment
		(start 153.125501 155.552)
		(end 153.125501 158.624499)
		(width 0.148)
		(layer "In2.Cu")
		(net 238)
	)
	(segment
		(start 152.562418 151.802)
		(end 153.688584 151.802)
		(width 0.148)
		(layer "In2.Cu")
		(net 238)
	)
	(segment
		(start 153.125501 150.274499)
		(end 153.125501 150.552)
		(width 0.148)
		(layer "In2.Cu")
		(net 238)
	)
	(segment
		(start 152.562418 153.302)
		(end 153.688584 153.302)
		(width 0.148)
		(layer "In2.Cu")
		(net 238)
	)
	(segment
		(start 153.125501 158.624499)
		(end 150.75 161)
		(width 0.148)
		(layer "In2.Cu")
		(net 238)
	)
	(segment
		(start 152.562418 152.302)
		(end 153.688584 152.302)
		(width 0.148)
		(layer "In2.Cu")
		(net 238)
	)
	(segment
		(start 152.875501 150.802)
		(end 152.562418 150.802)
		(width 0.148)
		(layer "In2.Cu")
		(net 238)
	)
	(segment
		(start 152.562418 152.802)
		(end 153.688584 152.802)
		(width 0.148)
		(layer "In2.Cu")
		(net 238)
	)
	(segment
		(start 158.4 148.35)
		(end 157.75 149)
		(width 0.148)
		(layer "In2.Cu")
		(net 238)
	)
	(segment
		(start 158.4 147.277499)
		(end 158.4 148.35)
		(width 0.148)
		(layer "In2.Cu")
		(net 238)
	)
	(segment
		(start 152.562418 154.302)
		(end 153.688584 154.302)
		(width 0.148)
		(layer "In2.Cu")
		(net 238)
	)
	(segment
		(start 147.375001 167.3025)
		(end 147.875001 167.8025)
		(width 0.148)
		(layer "In2.Cu")
		(net 238)
	)
	(segment
		(start 152.562418 151.302)
		(end 153.688584 151.302)
		(width 0.148)
		(layer "In2.Cu")
		(net 238)
	)
	(arc
		(start 153.125501 150.552)
		(mid 153.052278 150.728777)
		(end 152.875501 150.802)
		(width 0.148)
		(layer "In2.Cu")
		(net 238)
	)
	(arc
		(start 152.312418 153.052)
		(mid 152.385641 153.228777)
		(end 152.562418 153.302)
		(width 0.148)
		(layer "In2.Cu")
		(net 238)
	)
	(arc
		(start 153.688584 152.302)
		(mid 153.865361 152.375223)
		(end 153.938584 152.552)
		(width 0.148)
		(layer "In2.Cu")
		(net 238)
	)
	(arc
		(start 152.312418 151.052)
		(mid 152.385641 151.228777)
		(end 152.562418 151.302)
		(width 0.148)
		(layer "In2.Cu")
		(net 238)
	)
	(arc
		(start 153.938584 153.552)
		(mid 153.865361 153.728777)
		(end 153.688584 153.802)
		(width 0.148)
		(layer "In2.Cu")
		(net 238)
	)
	(arc
		(start 152.562418 152.802)
		(mid 152.385641 152.875223)
		(end 152.312418 153.052)
		(width 0.148)
		(layer "In2.Cu")
		(net 238)
	)
	(arc
		(start 152.312418 155.052)
		(mid 152.385641 155.228777)
		(end 152.562418 155.302)
		(width 0.148)
		(layer "In2.Cu")
		(net 238)
	)
	(arc
		(start 153.688584 154.302)
		(mid 153.865361 154.375223)
		(end 153.938584 154.552)
		(width 0.148)
		(layer "In2.Cu")
		(net 238)
	)
	(arc
		(start 152.875501 155.302)
		(mid 153.052278 155.375223)
		(end 153.125501 155.552)
		(width 0.148)
		(layer "In2.Cu")
		(net 238)
	)
	(arc
		(start 153.688584 151.302)
		(mid 153.865361 151.375223)
		(end 153.938584 151.552)
		(width 0.148)
		(layer "In2.Cu")
		(net 238)
	)
	(arc
		(start 152.562418 154.802)
		(mid 152.385641 154.875223)
		(end 152.312418 155.052)
		(width 0.148)
		(layer "In2.Cu")
		(net 238)
	)
	(arc
		(start 152.562418 153.802)
		(mid 152.385641 153.875223)
		(end 152.312418 154.052)
		(width 0.148)
		(layer "In2.Cu")
		(net 238)
	)
	(arc
		(start 152.562418 150.802)
		(mid 152.385641 150.875223)
		(end 152.312418 151.052)
		(width 0.148)
		(layer "In2.Cu")
		(net 238)
	)
	(arc
		(start 152.562418 151.802)
		(mid 152.385641 151.875223)
		(end 152.312418 152.052)
		(width 0.148)
		(layer "In2.Cu")
		(net 238)
	)
	(arc
		(start 153.938584 154.552)
		(mid 153.865361 154.728777)
		(end 153.688584 154.802)
		(width 0.148)
		(layer "In2.Cu")
		(net 238)
	)
	(arc
		(start 153.688584 153.302)
		(mid 153.865361 153.375223)
		(end 153.938584 153.552)
		(width 0.148)
		(layer "In2.Cu")
		(net 238)
	)
	(arc
		(start 153.938584 152.552)
		(mid 153.865361 152.728777)
		(end 153.688584 152.802)
		(width 0.148)
		(layer "In2.Cu")
		(net 238)
	)
	(arc
		(start 153.938584 151.552)
		(mid 153.865361 151.728777)
		(end 153.688584 151.802)
		(width 0.148)
		(layer "In2.Cu")
		(net 238)
	)
	(arc
		(start 152.312418 154.052)
		(mid 152.385641 154.228777)
		(end 152.562418 154.302)
		(width 0.148)
		(layer "In2.Cu")
		(net 238)
	)
	(arc
		(start 152.312418 152.052)
		(mid 152.385641 152.228777)
		(end 152.562418 152.302)
		(width 0.148)
		(layer "In2.Cu")
		(net 238)
	)
	(via
		(at 192 177.2)
		(size 0.45)
		(drill 0.1)
		(layers "F.Cu" "B.Cu")
		(net 239)
	)
	(via
		(at 191.1 176.9)
		(size 0.45)
		(drill 0.1)
		(layers "F.Cu" "B.Cu")
		(net 239)
	)
	(via
		(at 196.4 177.3)
		(size 0.45)
		(drill 0.1)
		(layers "F.Cu" "B.Cu")
		(net 239)
	)
	(via
		(at 196.4 176.5)
		(size 0.45)
		(drill 0.1)
		(layers "F.Cu" "B.Cu")
		(net 239)
	)
	(via
		(at 192 176.5)
		(size 0.45)
		(drill 0.1)
		(layers "F.Cu" "B.Cu")
		(net 239)
	)
	(segment
		(start 97.050501 130.999499)
		(end 97.05 131)
		(width 0.15)
		(layer "F.Cu")
		(net 240)
	)
	(segment
		(start 97.050501 130.286461)
		(end 97.050501 130.999499)
		(width 0.15)
		(layer "F.Cu")
		(net 240)
	)
	(segment
		(start 177.4 178.315)
		(end 177.4 182.4)
		(width 0.15)
		(layer "F.Cu")
		(net 240)
	)
	(segment
		(start 177.4 182.4)
		(end 177.415 182.415)
		(width 0.15)
		(layer "F.Cu")
		(net 240)
	)
	(via
		(at 177.4 178.315)
		(size 0.45)
		(drill 0.1)
		(layers "F.Cu" "B.Cu")
		(net 240)
	)
	(via
		(at 97.05 131)
		(size 0.45)
		(drill 0.1)
		(layers "F.Cu" "B.Cu")
		(net 240)
	)
	(segment
		(start 177.4 178.315)
		(end 177.4 172.9)
		(width 0.15)
		(layer "B.Cu")
		(net 240)
	)
	(segment
		(start 185.7 162.5)
		(end 185.7 156.3)
		(width 0.15)
		(layer "B.Cu")
		(net 240)
	)
	(segment
		(start 186.2 147.55)
		(end 173.05 134.4)
		(width 0.15)
		(layer "B.Cu")
		(net 240)
	)
	(segment
		(start 177.4 172.9)
		(end 184.25 166.05)
		(width 0.15)
		(layer "B.Cu")
		(net 240)
	)
	(segment
		(start 100.45 134.4)
		(end 97.05 131)
		(width 0.15)
		(layer "B.Cu")
		(net 240)
	)
	(segment
		(start 185.7 156.3)
		(end 186.2 155.8)
		(width 0.15)
		(layer "B.Cu")
		(net 240)
	)
	(segment
		(start 186.2 155.8)
		(end 186.2 147.55)
		(width 0.15)
		(layer "B.Cu")
		(net 240)
	)
	(segment
		(start 184.25 163.95)
		(end 185.7 162.5)
		(width 0.15)
		(layer "B.Cu")
		(net 240)
	)
	(segment
		(start 184.25 166.05)
		(end 184.25 163.95)
		(width 0.15)
		(layer "B.Cu")
		(net 240)
	)
	(segment
		(start 173.05 134.4)
		(end 100.45 134.4)
		(width 0.15)
		(layer "B.Cu")
		(net 240)
	)
	(segment
		(start 190.545 141.26)
		(end 190.63 141.175)
		(width 0.201)
		(layer "F.Cu")
		(net 241)
	)
	(segment
		(start 189.89 141.26)
		(end 189.875 141.275)
		(width 0.201)
		(layer "F.Cu")
		(net 241)
	)
	(segment
		(start 191.425 141.175)
		(end 191.55 141.05)
		(width 0.201)
		(layer "F.Cu")
		(net 241)
	)
	(segment
		(start 190.63 141.175)
		(end 191.425 141.175)
		(width 0.201)
		(layer "F.Cu")
		(net 241)
	)
	(segment
		(start 190.545 141.26)
		(end 189.89 141.26)
		(width 0.201)
		(layer "F.Cu")
		(net 241)
	)
	(segment
		(start 126.376501 181.301)
		(end 125.877001 181.8005)
		(width 0.256)
		(layer "F.Cu")
		(net 241)
	)
	(via
		(at 189.875 141.275)
		(size 0.45)
		(drill 0.1)
		(layers "F.Cu" "B.Cu")
		(net 241)
	)
	(via
		(at 125.877001 181.8005)
		(size 0.45)
		(drill 0.1)
		(layers "F.Cu" "B.Cu")
		(net 241)
	)
	(segment
		(start 148.4 170.1)
		(end 148.6 170.3)
		(width 0.1)
		(layer "In4.Cu")
		(net 241)
	)
	(segment
		(start 151.4 173.05)
		(end 151.625 173.275)
		(width 0.1)
		(layer "In4.Cu")
		(net 241)
	)
	(segment
		(start 158.6 173.5)
		(end 158.9 173.2)
		(width 0.1)
		(layer "In4.Cu")
		(net 241)
	)
	(segment
		(start 161.7 173.2)
		(end 162.9 172)
		(width 0.1)
		(layer "In4.Cu")
		(net 241)
	)
	(segment
		(start 126.65 178.3)
		(end 138.204002 178.3)
		(width 0.1)
		(layer "In4.Cu")
		(net 241)
	)
	(segment
		(start 186.775 141.275)
		(end 189.875 141.275)
		(width 0.1)
		(layer "In4.Cu")
		(net 241)
	)
	(segment
		(start 162.9 172)
		(end 166.7 172)
		(width 0.1)
		(layer "In4.Cu")
		(net 241)
	)
	(segment
		(start 178.875 149.175)
		(end 186.775 141.275)
		(width 0.1)
		(layer "In4.Cu")
		(net 241)
	)
	(segment
		(start 158.9 173.2)
		(end 161.7 173.2)
		(width 0.1)
		(layer "In4.Cu")
		(net 241)
	)
	(segment
		(start 152.45 173.5)
		(end 158.6 173.5)
		(width 0.1)
		(layer "In4.Cu")
		(net 241)
	)
	(segment
		(start 125.877001 181.8005)
		(end 126.4 181.277501)
		(width 0.1)
		(layer "In4.Cu")
		(net 241)
	)
	(segment
		(start 151.4 171.7)
		(end 151.4 173.05)
		(width 0.1)
		(layer "In4.Cu")
		(net 241)
	)
	(segment
		(start 149.1 170.3)
		(end 149.4 170.6)
		(width 0.1)
		(layer "In4.Cu")
		(net 241)
	)
	(segment
		(start 138.204002 178.3)
		(end 139.252001 177.252001)
		(width 0.1)
		(layer "In4.Cu")
		(net 241)
	)
	(segment
		(start 151 171.3)
		(end 151.4 171.7)
		(width 0.1)
		(layer "In4.Cu")
		(net 241)
	)
	(segment
		(start 166.7 172)
		(end 178.875 159.825)
		(width 0.1)
		(layer "In4.Cu")
		(net 241)
	)
	(segment
		(start 149.4 170.9)
		(end 149.8 171.3)
		(width 0.1)
		(layer "In4.Cu")
		(net 241)
	)
	(segment
		(start 152.225 173.275)
		(end 152.45 173.5)
		(width 0.1)
		(layer "In4.Cu")
		(net 241)
	)
	(segment
		(start 148.045 169.3)
		(end 148.4 169.655)
		(width 0.1)
		(layer "In4.Cu")
		(net 241)
	)
	(segment
		(start 139.847169 169.3)
		(end 148.045 169.3)
		(width 0.1)
		(layer "In4.Cu")
		(net 241)
	)
	(segment
		(start 139.252001 177.252001)
		(end 139.252001 169.895168)
		(width 0.1)
		(layer "In4.Cu")
		(net 241)
	)
	(segment
		(start 126.4 181.277501)
		(end 126.4 178.55)
		(width 0.1)
		(layer "In4.Cu")
		(net 241)
	)
	(segment
		(start 148.4 169.655)
		(end 148.4 170.1)
		(width 0.1)
		(layer "In4.Cu")
		(net 241)
	)
	(segment
		(start 149.4 170.6)
		(end 149.4 170.9)
		(width 0.1)
		(layer "In4.Cu")
		(net 241)
	)
	(segment
		(start 151.625 173.275)
		(end 152.225 173.275)
		(width 0.1)
		(layer "In4.Cu")
		(net 241)
	)
	(segment
		(start 139.252001 169.895168)
		(end 139.847169 169.3)
		(width 0.1)
		(layer "In4.Cu")
		(net 241)
	)
	(segment
		(start 178.875 159.825)
		(end 178.875 149.175)
		(width 0.1)
		(layer "In4.Cu")
		(net 241)
	)
	(segment
		(start 149.8 171.3)
		(end 151 171.3)
		(width 0.1)
		(layer "In4.Cu")
		(net 241)
	)
	(segment
		(start 148.6 170.3)
		(end 149.1 170.3)
		(width 0.1)
		(layer "In4.Cu")
		(net 241)
	)
	(segment
		(start 126.4 178.55)
		(end 126.65 178.3)
		(width 0.1)
		(layer "In4.Cu")
		(net 241)
	)
	(segment
		(start 129.376501 182.301)
		(end 128.877001 182.8005)
		(width 0.256)
		(layer "F.Cu")
		(net 242)
	)
	(segment
		(start 191.594 138.295)
		(end 190.665 138.295)
		(width 0.256)
		(layer "F.Cu")
		(net 242)
	)
	(segment
		(start 189.785 138.415)
		(end 189.775 138.425)
		(width 0.256)
		(layer "F.Cu")
		(net 242)
	)
	(segment
		(start 190.665 138.295)
		(end 190.545 138.415)
		(width 0.256)
		(layer "F.Cu")
		(net 242)
	)
	(segment
		(start 190.545 138.415)
		(end 189.785 138.415)
		(width 0.256)
		(layer "F.Cu")
		(net 242)
	)
	(via
		(at 128.877001 182.8005)
		(size 0.45)
		(drill 0.1)
		(layers "F.Cu" "B.Cu")
		(net 242)
	)
	(via
		(at 189.775 138.425)
		(size 0.45)
		(drill 0.1)
		(layers "F.Cu" "B.Cu")
		(net 242)
	)
	(via
		(at 177.4 185.1)
		(size 0.45)
		(drill 0.1)
		(layers "F.Cu" "B.Cu")
		(net 242)
	)
	(segment
		(start 189.775 138.425)
		(end 191.4 140.05)
		(width 0.1)
		(layer "In2.Cu")
		(net 242)
	)
	(segment
		(start 177.8 185.1)
		(end 177.4 185.1)
		(width 0.1)
		(layer "In2.Cu")
		(net 242)
	)
	(segment
		(start 180.2 184.4)
		(end 179.8 184)
		(width 0.1)
		(layer "In2.Cu")
		(net 242)
	)
	(segment
		(start 191.4 140.05)
		(end 191.4 160.7)
		(width 0.1)
		(layer "In2.Cu")
		(net 242)
	)
	(segment
		(start 190.6 172.9)
		(end 184.275 179.225)
		(width 0.1)
		(layer "In2.Cu")
		(net 242)
	)
	(segment
		(start 191.4 160.7)
		(end 190.6 161.5)
		(width 0.1)
		(layer "In2.Cu")
		(net 242)
	)
	(segment
		(start 184.275 181.925)
		(end 181.8 184.4)
		(width 0.1)
		(layer "In2.Cu")
		(net 242)
	)
	(segment
		(start 181.8 184.4)
		(end 180.2 184.4)
		(width 0.1)
		(layer "In2.Cu")
		(net 242)
	)
	(segment
		(start 184.275 179.225)
		(end 184.275 181.925)
		(width 0.1)
		(layer "In2.Cu")
		(net 242)
	)
	(segment
		(start 179.8 184)
		(end 178.9 184)
		(width 0.1)
		(layer "In2.Cu")
		(net 242)
	)
	(segment
		(start 190.6 161.5)
		(end 190.6 172.9)
		(width 0.1)
		(layer "In2.Cu")
		(net 242)
	)
	(segment
		(start 178.9 184)
		(end 177.8 185.1)
		(width 0.1)
		(layer "In2.Cu")
		(net 242)
	)
	(segment
		(start 138.35 183.55)
		(end 138.35 183.95)
		(width 0.1)
		(layer "In4.Cu")
		(net 242)
	)
	(segment
		(start 129.228001 182.8005)
		(end 129.603001 182.4255)
		(width 0.1)
		(layer "In4.Cu")
		(net 242)
	)
	(segment
		(start 131.54617 183.25)
		(end 138.05 183.25)
		(width 0.1)
		(layer "In4.Cu")
		(net 242)
	)
	(segment
		(start 129.603001 182.4255)
		(end 131.032332 182.4255)
		(width 0.1)
		(layer "In4.Cu")
		(net 242)
	)
	(segment
		(start 131.252001 182.645169)
		(end 131.252001 182.955831)
		(width 0.1)
		(layer "In4.Cu")
		(net 242)
	)
	(segment
		(start 138.35 183.95)
		(end 138.7 184.3)
		(width 0.1)
		(layer "In4.Cu")
		(net 242)
	)
	(segment
		(start 131.032332 182.4255)
		(end 131.252001 182.645169)
		(width 0.1)
		(layer "In4.Cu")
		(net 242)
	)
	(segment
		(start 152.704831 185.1)
		(end 151.904831 184.3)
		(width 0.1)
		(layer "In4.Cu")
		(net 242)
	)
	(segment
		(start 128.877001 182.8005)
		(end 129.228001 182.8005)
		(width 0.1)
		(layer "In4.Cu")
		(net 242)
	)
	(segment
		(start 152.704831 185.1)
		(end 177.4 185.1)
		(width 0.1)
		(layer "In4.Cu")
		(net 242)
	)
	(segment
		(start 138.7 184.3)
		(end 151.904831 184.3)
		(width 0.1)
		(layer "In4.Cu")
		(net 242)
	)
	(segment
		(start 131.252001 182.955831)
		(end 131.54617 183.25)
		(width 0.1)
		(layer "In4.Cu")
		(net 242)
	)
	(segment
		(start 138.05 183.25)
		(end 138.35 183.55)
		(width 0.1)
		(layer "In4.Cu")
		(net 242)
	)
	(segment
		(start 182.637108 168.211)
		(end 182.637107 168.992607)
		(width 0.2)
		(layer "F.Cu")
		(net 243)
	)
	(segment
		(start 189.365 171.7)
		(end 188.943 171.7)
		(width 0.1)
		(layer "F.Cu")
		(net 243)
	)
	(segment
		(start 182.637107 168.992607)
		(end 182.592606 169.037107)
		(width 0.2)
		(layer "F.Cu")
		(net 243)
	)
	(via
		(at 188.942 171.701)
		(size 0.45)
		(drill 0.1)
		(layers "F.Cu" "B.Cu")
		(net 243)
	)
	(via
		(at 182.592606 169.037107)
		(size 0.45)
		(drill 0.1)
		(layers "F.Cu" "B.Cu")
		(net 243)
	)
	(segment
		(start 185.758578 173.2)
		(end 187.941422 173.2)
		(width 0.1)
		(layer "In4.Cu")
		(net 243)
	)
	(segment
		(start 182.592606 169.037107)
		(end 182.784357 169.228858)
		(width 0.1)
		(layer "In4.Cu")
		(net 243)
	)
	(segment
		(start 188.767 171.876)
		(end 188.942 171.701)
		(width 0.1)
		(layer "In4.Cu")
		(net 243)
	)
	(segment
		(start 182.784357 169.228858)
		(end 182.784357 170.225779)
		(width 0.1)
		(layer "In4.Cu")
		(net 243)
	)
	(segment
		(start 187.941422 173.2)
		(end 188.767 172.374422)
		(width 0.1)
		(layer "In4.Cu")
		(net 243)
	)
	(segment
		(start 182.784357 170.225779)
		(end 185.758578 173.2)
		(width 0.1)
		(layer "In4.Cu")
		(net 243)
	)
	(segment
		(start 188.767 172.374422)
		(end 188.767 171.876)
		(width 0.1)
		(layer "In4.Cu")
		(net 243)
	)
	(segment
		(start 183.851107 185.660999)
		(end 184.632714 185.661)
		(width 0.2)
		(layer "F.Cu")
		(net 244)
	)
	(segment
		(start 184.632714 185.661)
		(end 184.677214 185.705501)
		(width 0.2)
		(layer "F.Cu")
		(net 244)
	)
	(segment
		(start 189.371 179.498)
		(end 188.948 179.498)
		(width 0.1)
		(layer "F.Cu")
		(net 244)
	)
	(via
		(at 184.677214 185.705501)
		(size 0.45)
		(drill 0.1)
		(layers "F.Cu" "B.Cu")
		(net 244)
	)
	(via
		(at 188.948 179.498)
		(size 0.45)
		(drill 0.1)
		(layers "F.Cu" "B.Cu")
		(net 244)
	)
	(segment
		(start 189.5 182.641422)
		(end 189.5 180.858578)
		(width 0.1)
		(layer "In4.Cu")
		(net 244)
	)
	(segment
		(start 188.773 179.673)
		(end 188.948 179.498)
		(width 0.1)
		(layer "In4.Cu")
		(net 244)
	)
	(segment
		(start 184.677214 185.705501)
		(end 184.868965 185.51375)
		(width 0.1)
		(layer "In4.Cu")
		(net 244)
	)
	(segment
		(start 184.868965 185.51375)
		(end 186.627672 185.51375)
		(width 0.1)
		(layer "In4.Cu")
		(net 244)
	)
	(segment
		(start 186.627672 185.51375)
		(end 189.5 182.641422)
		(width 0.1)
		(layer "In4.Cu")
		(net 244)
	)
	(segment
		(start 189.5 180.858578)
		(end 188.773 180.131578)
		(width 0.1)
		(layer "In4.Cu")
		(net 244)
	)
	(segment
		(start 188.773 180.131578)
		(end 188.773 179.673)
		(width 0.1)
		(layer "In4.Cu")
		(net 244)
	)
	(segment
		(start 183.137107 168.211)
		(end 183.137107 168.998107)
		(width 0.2)
		(layer "F.Cu")
		(net 245)
	)
	(segment
		(start 183.137107 168.998107)
		(end 183.176107 169.037107)
		(width 0.2)
		(layer "F.Cu")
		(net 245)
	)
	(segment
		(start 187.969 171.701)
		(end 188.392 171.701)
		(width 0.1)
		(layer "F.Cu")
		(net 245)
	)
	(via
		(at 183.176107 169.037107)
		(size 0.45)
		(drill 0.1)
		(layers "F.Cu" "B.Cu")
		(net 245)
	)
	(via
		(at 188.392 171.701)
		(size 0.45)
		(drill 0.1)
		(layers "F.Cu" "B.Cu")
		(net 245)
	)
	(segment
		(start 188.567 172.291578)
		(end 187.858578 173)
		(width 0.1)
		(layer "In4.Cu")
		(net 245)
	)
	(segment
		(start 188.567 171.876)
		(end 188.567 172.291578)
		(width 0.1)
		(layer "In4.Cu")
		(net 245)
	)
	(segment
		(start 182.984357 169.228857)
		(end 183.176107 169.037107)
		(width 0.1)
		(layer "In4.Cu")
		(net 245)
	)
	(segment
		(start 188.392 171.701)
		(end 188.567 171.876)
		(width 0.1)
		(layer "In4.Cu")
		(net 245)
	)
	(segment
		(start 185.841422 173)
		(end 182.984357 170.142935)
		(width 0.1)
		(layer "In4.Cu")
		(net 245)
	)
	(segment
		(start 187.858578 173)
		(end 187.5 173)
		(width 0.1)
		(layer "In4.Cu")
		(net 245)
	)
	(segment
		(start 186.5 173)
		(end 185.841422 173)
		(width 0.1)
		(layer "In4.Cu")
		(net 245)
	)
	(segment
		(start 182.984357 170.142935)
		(end 182.984357 169.228857)
		(width 0.1)
		(layer "In4.Cu")
		(net 245)
	)
	(arc
		(start 186.75 172.75)
		(mid 186.661612 172.786612)
		(end 186.625 172.875)
		(width 0.1)
		(layer "In4.Cu")
		(net 245)
	)
	(arc
		(start 187 173)
		(mid 186.911612 172.963388)
		(end 186.875 172.875)
		(width 0.1)
		(layer "In4.Cu")
		(net 245)
	)
	(arc
		(start 187.5 173)
		(mid 187.411612 172.963388)
		(end 187.375 172.875)
		(width 0.1)
		(layer "In4.Cu")
		(net 245)
	)
	(arc
		(start 187.375 172.875)
		(mid 187.338388 172.786612)
		(end 187.25 172.75)
		(width 0.1)
		(layer "In4.Cu")
		(net 245)
	)
	(arc
		(start 187.25 172.75)
		(mid 187.161612 172.786612)
		(end 187.125 172.875)
		(width 0.1)
		(layer "In4.Cu")
		(net 245)
	)
	(arc
		(start 186.625 172.875)
		(mid 186.588388 172.963388)
		(end 186.5 173)
		(width 0.1)
		(layer "In4.Cu")
		(net 245)
	)
	(arc
		(start 186.875 172.875)
		(mid 186.838388 172.786612)
		(end 186.75 172.75)
		(width 0.1)
		(layer "In4.Cu")
		(net 245)
	)
	(arc
		(start 187.125 172.875)
		(mid 187.088388 172.963388)
		(end 187 173)
		(width 0.1)
		(layer "In4.Cu")
		(net 245)
	)
	(segment
		(start 184.638214 185.161)
		(end 184.677214 185.122)
		(width 0.2)
		(layer "F.Cu")
		(net 246)
	)
	(segment
		(start 183.851107 185.161)
		(end 184.638214 185.161)
		(width 0.2)
		(layer "F.Cu")
		(net 246)
	)
	(segment
		(start 187.975 179.499)
		(end 188.397 179.499)
		(width 0.1)
		(layer "F.Cu")
		(net 246)
	)
	(via
		(at 184.677214 185.122)
		(size 0.45)
		(drill 0.1)
		(layers "F.Cu" "B.Cu")
		(net 246)
	)
	(via
		(at 188.398 179.498)
		(size 0.45)
		(drill 0.1)
		(layers "F.Cu" "B.Cu")
		(net 246)
	)
	(segment
		(start 186.544828 185.31375)
		(end 184.868964 185.31375)
		(width 0.1)
		(layer "In4.Cu")
		(net 246)
	)
	(segment
		(start 188.398 179.498)
		(end 188.573 179.673)
		(width 0.1)
		(layer "In4.Cu")
		(net 246)
	)
	(segment
		(start 189.3 180.941422)
		(end 189.3 181.3)
		(width 0.1)
		(layer "In4.Cu")
		(net 246)
	)
	(segment
		(start 184.868964 185.31375)
		(end 184.677214 185.122)
		(width 0.1)
		(layer "In4.Cu")
		(net 246)
	)
	(segment
		(start 189.3 182.3)
		(end 189.3 182.323879)
		(width 0.1)
		(layer "In4.Cu")
		(net 246)
	)
	(segment
		(start 189.3 182.558578)
		(end 186.544828 185.31375)
		(width 0.1)
		(layer "In4.Cu")
		(net 246)
	)
	(segment
		(start 188.573 180.214422)
		(end 189.3 180.941422)
		(width 0.1)
		(layer "In4.Cu")
		(net 246)
	)
	(segment
		(start 189.3 182.323879)
		(end 189.3 182.558578)
		(width 0.1)
		(layer "In4.Cu")
		(net 246)
	)
	(segment
		(start 188.573 179.673)
		(end 188.573 180.214422)
		(width 0.1)
		(layer "In4.Cu")
		(net 246)
	)
	(arc
		(start 189.175 181.925)
		(mid 189.086612 181.961612)
		(end 189.05 182.05)
		(width 0.1)
		(layer "In4.Cu")
		(net 246)
	)
	(arc
		(start 189.3 181.8)
		(mid 189.263388 181.888388)
		(end 189.175 181.925)
		(width 0.1)
		(layer "In4.Cu")
		(net 246)
	)
	(arc
		(start 189.175 181.675)
		(mid 189.263388 181.711612)
		(end 189.3 181.8)
		(width 0.1)
		(layer "In4.Cu")
		(net 246)
	)
	(arc
		(start 189.05 181.55)
		(mid 189.086612 181.638388)
		(end 189.175 181.675)
		(width 0.1)
		(layer "In4.Cu")
		(net 246)
	)
	(arc
		(start 189.175 181.425)
		(mid 189.086612 181.461612)
		(end 189.05 181.55)
		(width 0.1)
		(layer "In4.Cu")
		(net 246)
	)
	(arc
		(start 189.3 181.3)
		(mid 189.263388 181.388388)
		(end 189.175 181.425)
		(width 0.1)
		(layer "In4.Cu")
		(net 246)
	)
	(arc
		(start 189.05 182.05)
		(mid 189.086612 182.138388)
		(end 189.175 182.175)
		(width 0.1)
		(layer "In4.Cu")
		(net 246)
	)
	(arc
		(start 189.175 182.175)
		(mid 189.263388 182.211612)
		(end 189.3 182.3)
		(width 0.1)
		(layer "In4.Cu")
		(net 246)
	)
	(segment
		(start 159.150003 138.8025)
		(end 159.150002 139.877499)
		(width 0.201)
		(layer "F.Cu")
		(net 247)
	)
	(segment
		(start 146.375501 165.302)
		(end 146.875001 164.8025)
		(width 0.256)
		(layer "F.Cu")
		(net 247)
	)
	(via
		(at 159.150002 139.877499)
		(size 0.45)
		(drill 0.1)
		(layers "F.Cu" "B.Cu")
		(net 247)
	)
	(via
		(at 146.875001 164.8025)
		(size 0.45)
		(drill 0.1)
		(layers "F.Cu" "B.Cu")
		(net 247)
	)
	(segment
		(start 153.3 148.5)
		(end 151.625501 150.174499)
		(width 0.148)
		(layer "In2.Cu")
		(net 247)
	)
	(segment
		(start 157.4 148.5)
		(end 153.3 148.5)
		(width 0.148)
		(layer "In2.Cu")
		(net 247)
	)
	(segment
		(start 151.33178 156.802)
		(end 151.919222 156.802)
		(width 0.148)
		(layer "In2.Cu")
		(net 247)
	)
	(segment
		(start 151.375501 155.802)
		(end 151.33178 155.802)
		(width 0.148)
		(layer "In2.Cu")
		(net 247)
	)
	(segment
		(start 159.150002 139.877499)
		(end 157.400001 141.6275)
		(width 0.148)
		(layer "In2.Cu")
		(net 247)
	)
	(segment
		(start 151.919222 157.802)
		(end 151.875501 157.802)
		(width 0.148)
		(layer "In2.Cu")
		(net 247)
	)
	(segment
		(start 157.400001 141.6275)
		(end 157.400001 145.900001)
		(width 0.148)
		(layer "In2.Cu")
		(net 247)
	)
	(segment
		(start 157.8255 148.0745)
		(end 157.4 148.5)
		(width 0.148)
		(layer "In2.Cu")
		(net 247)
	)
	(segment
		(start 151.375501 156.302)
		(end 151.919222 156.302)
		(width 0.148)
		(layer "In2.Cu")
		(net 247)
	)
	(segment
		(start 151.33178 156.302)
		(end 151.375501 156.302)
		(width 0.148)
		(layer "In2.Cu")
		(net 247)
	)
	(segment
		(start 157.8255 146.3255)
		(end 157.8255 148.0745)
		(width 0.148)
		(layer "In2.Cu")
		(net 247)
	)
	(segment
		(start 151.625501 158.052)
		(end 151.625501 158.624499)
		(width 0.148)
		(layer "In2.Cu")
		(net 247)
	)
	(segment
		(start 151.625501 150.174499)
		(end 151.625501 155.552)
		(width 0.148)
		(layer "In2.Cu")
		(net 247)
	)
	(segment
		(start 151.625501 158.624499)
		(end 150 160.25)
		(width 0.148)
		(layer "In2.Cu")
		(net 247)
	)
	(segment
		(start 146.375001 164.3025)
		(end 146.875001 164.8025)
		(width 0.148)
		(layer "In2.Cu")
		(net 247)
	)
	(segment
		(start 147.477501 160.25)
		(end 146.375001 161.3525)
		(width 0.148)
		(layer "In2.Cu")
		(net 247)
	)
	(segment
		(start 150 160.25)
		(end 147.477501 160.25)
		(width 0.148)
		(layer "In2.Cu")
		(net 247)
	)
	(segment
		(start 151.33178 157.302)
		(end 151.919222 157.302)
		(width 0.148)
		(layer "In2.Cu")
		(net 247)
	)
	(segment
		(start 157.400001 145.900001)
		(end 157.8255 146.3255)
		(width 0.148)
		(layer "In2.Cu")
		(net 247)
	)
	(segment
		(start 146.375001 161.3525)
		(end 146.375001 164.3025)
		(width 0.148)
		(layer "In2.Cu")
		(net 247)
	)
	(arc
		(start 151.33178 156.802)
		(mid 151.155003 156.875223)
		(end 151.08178 157.052)
		(width 0.148)
		(layer "In2.Cu")
		(net 247)
	)
	(arc
		(start 151.625501 155.552)
		(mid 151.552278 155.728777)
		(end 151.375501 155.802)
		(width 0.148)
		(layer "In2.Cu")
		(net 247)
	)
	(arc
		(start 152.169222 156.552)
		(mid 152.095999 156.728777)
		(end 151.919222 156.802)
		(width 0.148)
		(layer "In2.Cu")
		(net 247)
	)
	(arc
		(start 151.875501 157.802)
		(mid 151.698724 157.875223)
		(end 151.625501 158.052)
		(width 0.148)
		(layer "In2.Cu")
		(net 247)
	)
	(arc
		(start 151.08178 156.052)
		(mid 151.155003 156.228777)
		(end 151.33178 156.302)
		(width 0.148)
		(layer "In2.Cu")
		(net 247)
	)
	(arc
		(start 151.919222 156.302)
		(mid 152.095999 156.375223)
		(end 152.169222 156.552)
		(width 0.148)
		(layer "In2.Cu")
		(net 247)
	)
	(arc
		(start 152.169222 157.552)
		(mid 152.095999 157.728777)
		(end 151.919222 157.802)
		(width 0.148)
		(layer "In2.Cu")
		(net 247)
	)
	(arc
		(start 151.919222 157.302)
		(mid 152.095999 157.375223)
		(end 152.169222 157.552)
		(width 0.148)
		(layer "In2.Cu")
		(net 247)
	)
	(arc
		(start 151.08178 157.052)
		(mid 151.155003 157.228777)
		(end 151.33178 157.302)
		(width 0.148)
		(layer "In2.Cu")
		(net 247)
	)
	(arc
		(start 151.33178 155.802)
		(mid 151.155003 155.875223)
		(end 151.08178 156.052)
		(width 0.148)
		(layer "In2.Cu")
		(net 247)
	)
	(segment
		(start 130.376501 162.302)
		(end 129.877001 161.8025)
		(width 0.256)
		(layer "F.Cu")
		(net 248)
	)
	(via
		(at 135.75 143.5)
		(size 0.45)
		(drill 0.1)
		(layers "F.Cu" "B.Cu")
		(net 248)
	)
	(via
		(at 129.877001 161.8025)
		(size 0.45)
		(drill 0.1)
		(layers "F.Cu" "B.Cu")
		(net 248)
	)
	(segment
		(start 135.75 143.5)
		(end 136.9 144.65)
		(width 0.15)
		(layer "B.Cu")
		(net 248)
	)
	(segment
		(start 136.9 146.3)
		(end 136.4 146.8)
		(width 0.15)
		(layer "B.Cu")
		(net 248)
	)
	(segment
		(start 136.4 146.8)
		(end 136.4 150.5)
		(width 0.15)
		(layer "B.Cu")
		(net 248)
	)
	(segment
		(start 130.4 156.5)
		(end 130.4 161.279501)
		(width 0.15)
		(layer "B.Cu")
		(net 248)
	)
	(segment
		(start 130.4 161.279501)
		(end 129.877001 161.8025)
		(width 0.15)
		(layer "B.Cu")
		(net 248)
	)
	(segment
		(start 136.4 150.5)
		(end 130.4 156.5)
		(width 0.15)
		(layer "B.Cu")
		(net 248)
	)
	(segment
		(start 135.75 142.885)
		(end 135.75 143.5)
		(width 0.256)
		(layer "B.Cu")
		(net 248)
	)
	(segment
		(start 136.9 144.65)
		(end 136.9 146.3)
		(width 0.15)
		(layer "B.Cu")
		(net 248)
	)
	(segment
		(start 131.376501 163.302)
		(end 130.877001 162.8025)
		(width 0.256)
		(layer "F.Cu")
		(net 249)
	)
	(via
		(at 139.7 142.910188)
		(size 0.45)
		(drill 0.1)
		(layers "F.Cu" "B.Cu")
		(net 249)
	)
	(via
		(at 130.877001 162.8025)
		(size 0.45)
		(drill 0.1)
		(layers "F.Cu" "B.Cu")
		(net 249)
	)
	(segment
		(start 131.4 156.9)
		(end 131.4 162.279501)
		(width 0.15)
		(layer "B.Cu")
		(net 249)
	)
	(segment
		(start 139 143.7)
		(end 137.95 144.75)
		(width 0.15)
		(layer "B.Cu")
		(net 249)
	)
	(segment
		(start 131.4 162.279501)
		(end 130.877001 162.8025)
		(width 0.15)
		(layer "B.Cu")
		(net 249)
	)
	(segment
		(start 139 142.885)
		(end 139 143.7)
		(width 0.15)
		(layer "B.Cu")
		(net 249)
	)
	(segment
		(start 137.95 150.35)
		(end 131.4 156.9)
		(width 0.15)
		(layer "B.Cu")
		(net 249)
	)
	(segment
		(start 139.025188 142.910188)
		(end 139 142.885)
		(width 0.256)
		(layer "B.Cu")
		(net 249)
	)
	(segment
		(start 139.7 142.910188)
		(end 139.025188 142.910188)
		(width 0.256)
		(layer "B.Cu")
		(net 249)
	)
	(segment
		(start 137.95 144.75)
		(end 137.95 150.35)
		(width 0.15)
		(layer "B.Cu")
		(net 249)
	)
	(segment
		(start 147.375501 166.302)
		(end 147.875001 165.8025)
		(width 0.256)
		(layer "F.Cu")
		(net 250)
	)
	(segment
		(start 159.42 147.292427)
		(end 159.375001 147.337426)
		(width 0.26)
		(layer "F.Cu")
		(net 250)
	)
	(segment
		(start 159.400001 146.8025)
		(end 159.420001 146.8225)
		(width 0.26)
		(layer "F.Cu")
		(net 250)
	)
	(segment
		(start 159.420001 146.8225)
		(end 159.42 147.292427)
		(width 0.26)
		(layer "F.Cu")
		(net 250)
	)
	(segment
		(start 159.400001 146.2025)
		(end 159.400001 146.8025)
		(width 0.26)
		(layer "F.Cu")
		(net 250)
	)
	(via
		(at 159.375001 147.337426)
		(size 0.45)
		(drill 0.1)
		(layers "F.Cu" "B.Cu")
		(net 250)
	)
	(via
		(at 147.875001 165.8025)
		(size 0.45)
		(drill 0.1)
		(layers "F.Cu" "B.Cu")
		(net 250)
	)
	(segment
		(start 159.375001 147.337426)
		(end 159.530001 147.492426)
		(width 0.13)
		(layer "In2.Cu")
		(net 250)
	)
	(segment
		(start 152.915648 163.092147)
		(end 152.831297 163.176498)
		(width 0.13)
		(layer "In2.Cu")
		(net 250)
	)
	(segment
		(start 157.475501 152.895501)
		(end 157.93512 152.895501)
		(width 0.13)
		(layer "In2.Cu")
		(net 250)
	)
	(segment
		(start 159.530001 147.492426)
		(end 159.530001 149.477794)
		(width 0.13)
		(layer "In2.Cu")
		(net 250)
	)
	(segment
		(start 157.005501 159.002294)
		(end 153.764181 162.243617)
		(width 0.13)
		(layer "In2.Cu")
		(net 250)
	)
	(segment
		(start 153.127783 162.667883)
		(end 153.108939 162.649039)
		(width 0.13)
		(layer "In2.Cu")
		(net 250)
	)
	(segment
		(start 152.896805 162.861172)
		(end 152.915648 162.880015)
		(width 0.13)
		(layer "In2.Cu")
		(net 250)
	)
	(segment
		(start 156.315882 155.695501)
		(end 157.93512 155.695501)
		(width 0.13)
		(layer "In2.Cu")
		(net 250)
	)
	(segment
		(start 148.270501 166.028506)
		(end 148.270501 163.528506)
		(width 0.1)
		(layer "In2.Cu")
		(net 250)
	)
	(segment
		(start 148.270501 163.528506)
		(end 148.602007 163.197)
		(width 0.1)
		(layer "In2.Cu")
		(net 250)
	)
	(segment
		(start 159.530001 149.477794)
		(end 157.005501 152.002294)
		(width 0.13)
		(layer "In2.Cu")
		(net 250)
	)
	(segment
		(start 156.315882 157.095501)
		(end 156.775501 157.095501)
		(width 0.13)
		(layer "In2.Cu")
		(net 250)
	)
	(segment
		(start 153.339914 162.667881)
		(end 153.339914 162.667882)
		(width 0.13)
		(layer "In2.Cu")
		(net 250)
	)
	(segment
		(start 147.875001 166.0615)
		(end 148.010501 166.197)
		(width 0.1)
		(layer "In2.Cu")
		(net 250)
	)
	(segment
		(start 153.321071 162.436906)
		(end 153.339914 162.455749)
		(width 0.13)
		(layer "In2.Cu")
		(net 250)
	)
	(segment
		(start 148.010501 166.197)
		(end 148.102007 166.197)
		(width 0.1)
		(layer "In2.Cu")
		(net 250)
	)
	(segment
		(start 153.552049 162.243617)
		(end 153.533205 162.224773)
		(width 0.13)
		(layer "In2.Cu")
		(net 250)
	)
	(segment
		(start 148.602007 163.197)
		(end 152.62072 163.197)
		(width 0.1)
		(layer "In2.Cu")
		(net 250)
	)
	(segment
		(start 157.005501 157.325501)
		(end 157.005501 159.002294)
		(width 0.13)
		(layer "In2.Cu")
		(net 250)
	)
	(segment
		(start 156.315882 156.155501)
		(end 157.93512 156.155501)
		(width 0.13)
		(layer "In2.Cu")
		(net 250)
	)
	(segment
		(start 153.108939 162.649039)
		(end 153.108939 162.64904)
		(width 0.13)
		(layer "In2.Cu")
		(net 250)
	)
	(segment
		(start 147.875001 165.8025)
		(end 147.875001 166.0615)
		(width 0.1)
		(layer "In2.Cu")
		(net 250)
	)
	(segment
		(start 152.62072 163.197)
		(end 152.641222 163.176498)
		(width 0.1)
		(layer "In2.Cu")
		(net 250)
	)
	(segment
		(start 153.533205 162.224773)
		(end 153.533205 162.224774)
		(width 0.13)
		(layer "In2.Cu")
		(net 250)
	)
	(segment
		(start 157.005501 152.002294)
		(end 157.005501 152.425501)
		(width 0.13)
		(layer "In2.Cu")
		(net 250)
	)
	(segment
		(start 156.315882 153.355501)
		(end 157.93512 153.355501)
		(width 0.13)
		(layer "In2.Cu")
		(net 250)
	)
	(segment
		(start 156.315882 154.295501)
		(end 157.93512 154.295501)
		(width 0.13)
		(layer "In2.Cu")
		(net 250)
	)
	(segment
		(start 148.102007 166.197)
		(end 148.270501 166.028506)
		(width 0.1)
		(layer "In2.Cu")
		(net 250)
	)
	(segment
		(start 153.339914 162.667882)
		(end 153.339915 162.667883)
		(width 0.13)
		(layer "In2.Cu")
		(net 250)
	)
	(segment
		(start 156.315882 154.755501)
		(end 157.93512 154.755501)
		(width 0.13)
		(layer "In2.Cu")
		(net 250)
	)
	(segment
		(start 152.831297 163.176498)
		(end 152.641222 163.176498)
		(width 0.13)
		(layer "In2.Cu")
		(net 250)
	)
	(arc
		(start 158.16512 155.925501)
		(mid 158.097755 156.088136)
		(end 157.93512 156.155501)
		(width 0.13)
		(layer "In2.Cu")
		(net 250)
	)
	(arc
		(start 155.845882 155.225501)
		(mid 155.983542 155.557841)
		(end 156.315882 155.695501)
		(width 0.13)
		(layer "In2.Cu")
		(net 250)
	)
	(arc
		(start 156.315882 156.155501)
		(mid 155.983542 156.293161)
		(end 155.845882 156.625501)
		(width 0.13)
		(layer "In2.Cu")
		(net 250)
	)
	(arc
		(start 155.845882 156.625501)
		(mid 155.983542 156.957841)
		(end 156.315882 157.095501)
		(width 0.13)
		(layer "In2.Cu")
		(net 250)
	)
	(arc
		(start 153.108939 162.64904)
		(mid 153.002873 162.605105)
		(end 152.896805 162.64904)
		(width 0.13)
		(layer "In2.Cu")
		(net 250)
	)
	(arc
		(start 156.775501 157.095501)
		(mid 156.938136 157.162866)
		(end 157.005501 157.325501)
		(width 0.13)
		(layer "In2.Cu")
		(net 250)
	)
	(arc
		(start 152.896805 162.64904)
		(mid 152.852871 162.755106)
		(end 152.896805 162.861172)
		(width 0.13)
		(layer "In2.Cu")
		(net 250)
	)
	(arc
		(start 153.339914 162.455749)
		(mid 153.383848 162.561815)
		(end 153.339914 162.667881)
		(width 0.13)
		(layer "In2.Cu")
		(net 250)
	)
	(arc
		(start 153.321071 162.224774)
		(mid 153.277137 162.33084)
		(end 153.321071 162.436906)
		(width 0.13)
		(layer "In2.Cu")
		(net 250)
	)
	(arc
		(start 153.533205 162.224774)
		(mid 153.427139 162.180839)
		(end 153.321071 162.224774)
		(width 0.13)
		(layer "In2.Cu")
		(net 250)
	)
	(arc
		(start 158.16512 154.525501)
		(mid 158.097755 154.688136)
		(end 157.93512 154.755501)
		(width 0.13)
		(layer "In2.Cu")
		(net 250)
	)
	(arc
		(start 157.93512 155.695501)
		(mid 158.097755 155.762866)
		(end 158.16512 155.925501)
		(width 0.13)
		(layer "In2.Cu")
		(net 250)
	)
	(arc
		(start 156.315882 154.755501)
		(mid 155.983542 154.893161)
		(end 155.845882 155.225501)
		(width 0.13)
		(layer "In2.Cu")
		(net 250)
	)
	(arc
		(start 153.339915 162.667883)
		(mid 153.233849 162.711817)
		(end 153.127783 162.667883)
		(width 0.13)
		(layer "In2.Cu")
		(net 250)
	)
	(arc
		(start 156.315882 153.355501)
		(mid 155.983542 153.493161)
		(end 155.845882 153.825501)
		(width 0.13)
		(layer "In2.Cu")
		(net 250)
	)
	(arc
		(start 158.16512 153.125501)
		(mid 158.097755 153.288136)
		(end 157.93512 153.355501)
		(width 0.13)
		(layer "In2.Cu")
		(net 250)
	)
	(arc
		(start 157.93512 154.295501)
		(mid 158.097755 154.362866)
		(end 158.16512 154.525501)
		(width 0.13)
		(layer "In2.Cu")
		(net 250)
	)
	(arc
		(start 157.005501 152.425501)
		(mid 157.143161 152.757841)
		(end 157.475501 152.895501)
		(width 0.13)
		(layer "In2.Cu")
		(net 250)
	)
	(arc
		(start 155.845882 153.825501)
		(mid 155.983542 154.157841)
		(end 156.315882 154.295501)
		(width 0.13)
		(layer "In2.Cu")
		(net 250)
	)
	(arc
		(start 153.764181 162.243617)
		(mid 153.658115 162.287551)
		(end 153.552049 162.243617)
		(width 0.13)
		(layer "In2.Cu")
		(net 250)
	)
	(arc
		(start 152.915648 162.880015)
		(mid 152.959582 162.986081)
		(end 152.915648 163.092147)
		(width 0.13)
		(layer "In2.Cu")
		(net 250)
	)
	(arc
		(start 157.93512 152.895501)
		(mid 158.097755 152.962866)
		(end 158.16512 153.125501)
		(width 0.13)
		(layer "In2.Cu")
		(net 250)
	)
	(segment
		(start 81.857858 183.566)
		(end 77.444501 183.566)
		(width 0.4)
		(layer "F.Cu")
		(net 251)
	)
	(segment
		(start 82.039858 183.384)
		(end 82.010758 183.4131)
		(width 0.4)
		(layer "F.Cu")
		(net 251)
	)
	(segment
		(start 71.450501 183.5695)
		(end 77.450501 183.5695)
		(width 0.4)
		(layer "F.Cu")
		(net 251)
	)
	(segment
		(start 82.010758 183.4131)
		(end 81.857858 183.566)
		(width 0.4)
		(layer "F.Cu")
		(net 251)
	)
	(segment
		(start 82.9995 183.384)
		(end 82.039858 183.384)
		(width 0.4)
		(layer "F.Cu")
		(net 251)
	)
	(segment
		(start 71.450501 198.0695)
		(end 71.450501 183.5695)
		(width 0.4)
		(layer "F.Cu")
		(net 251)
	)
	(segment
		(start 71.450501 198.0695)
		(end 77.450501 198.0695)
		(width 0.4)
		(layer "F.Cu")
		(net 251)
	)
	(segment
		(start 202.148 139.65)
		(end 200.9 139.65)
		(width 0.256)
		(layer "F.Cu")
		(net 252)
	)
	(segment
		(start 201.248 135.552)
		(end 202.148 135.552)
		(width 0.256)
		(layer "F.Cu")
		(net 252)
	)
	(segment
		(start 200.331 140.219)
		(end 197.7 140.219)
		(width 0.256)
		(layer "F.Cu")
		(net 252)
	)
	(segment
		(start 200.9 139.65)
		(end 200.9 135.9)
		(width 0.256)
		(layer "F.Cu")
		(net 252)
	)
	(segment
		(start 200.9 139.65)
		(end 200.331 140.219)
		(width 0.256)
		(layer "F.Cu")
		(net 252)
	)
	(segment
		(start 200.9 135.9)
		(end 201.248 135.552)
		(width 0.256)
		(layer "F.Cu")
		(net 252)
	)
	(segment
		(start 159.880001 146.8225)
		(end 159.880002 147.292427)
		(width 0.26)
		(layer "F.Cu")
		(net 253)
	)
	(segment
		(start 159.900001 146.2025)
		(end 159.900001 146.8025)
		(width 0.26)
		(layer "F.Cu")
		(net 253)
	)
	(segment
		(start 147.3755 167.302)
		(end 147.875001 166.8025)
		(width 0.256)
		(layer "F.Cu")
		(net 253)
	)
	(segment
		(start 159.900001 146.8025)
		(end 159.880001 146.8225)
		(width 0.26)
		(layer "F.Cu")
		(net 253)
	)
	(segment
		(start 159.880002 147.292427)
		(end 159.925001 147.337426)
		(width 0.26)
		(layer "F.Cu")
		(net 253)
	)
	(via
		(at 147.875001 166.8025)
		(size 0.45)
		(drill 0.1)
		(layers "F.Cu" "B.Cu")
		(net 253)
	)
	(via
		(at 159.925001 147.337426)
		(size 0.45)
		(drill 0.1)
		(layers "F.Cu" "B.Cu")
		(net 253)
	)
	(segment
		(start 148.688995 163.407)
		(end 152.631724 163.407)
		(width 0.1)
		(layer "In2.Cu")
		(net 253)
	)
	(segment
		(start 156.315882 154.055501)
		(end 157.93512 154.055501)
		(width 0.13)
		(layer "In2.Cu")
		(net 253)
	)
	(segment
		(start 147.990501 166.397)
		(end 148.200501 166.397)
		(width 0.1)
		(layer "In2.Cu")
		(net 253)
	)
	(segment
		(start 156.315882 153.595501)
		(end 157.93512 153.595501)
		(width 0.13)
		(layer "In2.Cu")
		(net 253)
	)
	(segment
		(start 156.315882 156.395501)
		(end 157.93512 156.395501)
		(width 0.13)
		(layer "In2.Cu")
		(net 253)
	)
	(segment
		(start 148.480501 166.117)
		(end 148.480501 163.615494)
		(width 0.1)
		(layer "In2.Cu")
		(net 253)
	)
	(segment
		(start 157.245501 159.101706)
		(end 152.930709 163.416498)
		(width 0.13)
		(layer "In2.Cu")
		(net 253)
	)
	(segment
		(start 159.770001 147.492426)
		(end 159.770001 149.577206)
		(width 0.13)
		(layer "In2.Cu")
		(net 253)
	)
	(segment
		(start 157.245501 152.101706)
		(end 157.245501 152.425501)
		(width 0.13)
		(layer "In2.Cu")
		(net 253)
	)
	(segment
		(start 159.925001 147.337426)
		(end 159.770001 147.492426)
		(width 0.13)
		(layer "In2.Cu")
		(net 253)
	)
	(segment
		(start 148.200501 166.397)
		(end 148.480501 166.117)
		(width 0.1)
		(layer "In2.Cu")
		(net 253)
	)
	(segment
		(start 152.631724 163.407)
		(end 152.641222 163.416498)
		(width 0.1)
		(layer "In2.Cu")
		(net 253)
	)
	(segment
		(start 148.480501 163.615494)
		(end 148.688995 163.407)
		(width 0.1)
		(layer "In2.Cu")
		(net 253)
	)
	(segment
		(start 156.315882 155.455501)
		(end 157.93512 155.455501)
		(width 0.13)
		(layer "In2.Cu")
		(net 253)
	)
	(segment
		(start 159.770001 149.577206)
		(end 157.245501 152.101706)
		(width 0.13)
		(layer "In2.Cu")
		(net 253)
	)
	(segment
		(start 157.475501 152.655501)
		(end 157.93512 152.655501)
		(width 0.13)
		(layer "In2.Cu")
		(net 253)
	)
	(segment
		(start 147.875001 166.5125)
		(end 147.990501 166.397)
		(width 0.1)
		(layer "In2.Cu")
		(net 253)
	)
	(segment
		(start 157.245501 157.325501)
		(end 157.245501 159.101706)
		(width 0.13)
		(layer "In2.Cu")
		(net 253)
	)
	(segment
		(start 156.315882 154.995501)
		(end 157.93512 154.995501)
		(width 0.13)
		(layer "In2.Cu")
		(net 253)
	)
	(segment
		(start 147.875001 166.8025)
		(end 147.875001 166.5125)
		(width 0.1)
		(layer "In2.Cu")
		(net 253)
	)
	(segment
		(start 156.315882 156.855501)
		(end 156.775501 156.855501)
		(width 0.13)
		(layer "In2.Cu")
		(net 253)
	)
	(segment
		(start 152.930709 163.416498)
		(end 152.641222 163.416498)
		(width 0.13)
		(layer "In2.Cu")
		(net 253)
	)
	(arc
		(start 157.93512 152.655501)
		(mid 158.26746 152.793161)
		(end 158.40512 153.125501)
		(width 0.13)
		(layer "In2.Cu")
		(net 253)
	)
	(arc
		(start 156.085882 156.625501)
		(mid 156.153247 156.788136)
		(end 156.315882 156.855501)
		(width 0.13)
		(layer "In2.Cu")
		(net 253)
	)
	(arc
		(start 156.775501 156.855501)
		(mid 157.107841 156.993161)
		(end 157.245501 157.325501)
		(width 0.13)
		(layer "In2.Cu")
		(net 253)
	)
	(arc
		(start 157.245501 152.425501)
		(mid 157.312866 152.588136)
		(end 157.475501 152.655501)
		(width 0.13)
		(layer "In2.Cu")
		(net 253)
	)
	(arc
		(start 156.315882 153.595501)
		(mid 156.153247 153.662866)
		(end 156.085882 153.825501)
		(width 0.13)
		(layer "In2.Cu")
		(net 253)
	)
	(arc
		(start 157.93512 155.455501)
		(mid 158.26746 155.593161)
		(end 158.40512 155.925501)
		(width 0.13)
		(layer "In2.Cu")
		(net 253)
	)
	(arc
		(start 158.40512 155.925501)
		(mid 158.26746 156.257841)
		(end 157.93512 156.395501)
		(width 0.13)
		(layer "In2.Cu")
		(net 253)
	)
	(arc
		(start 157.93512 154.055501)
		(mid 158.26746 154.193161)
		(end 158.40512 154.525501)
		(width 0.13)
		(layer "In2.Cu")
		(net 253)
	)
	(arc
		(start 158.40512 153.125501)
		(mid 158.26746 153.457841)
		(end 157.93512 153.595501)
		(width 0.13)
		(layer "In2.Cu")
		(net 253)
	)
	(arc
		(start 156.315882 154.995501)
		(mid 156.153247 155.062866)
		(end 156.085882 155.225501)
		(width 0.13)
		(layer "In2.Cu")
		(net 253)
	)
	(arc
		(start 158.40512 154.525501)
		(mid 158.26746 154.857841)
		(end 157.93512 154.995501)
		(width 0.13)
		(layer "In2.Cu")
		(net 253)
	)
	(arc
		(start 156.085882 153.825501)
		(mid 156.153247 153.988136)
		(end 156.315882 154.055501)
		(width 0.13)
		(layer "In2.Cu")
		(net 253)
	)
	(arc
		(start 156.315882 156.395501)
		(mid 156.153247 156.462866)
		(end 156.085882 156.625501)
		(width 0.13)
		(layer "In2.Cu")
		(net 253)
	)
	(arc
		(start 156.085882 155.225501)
		(mid 156.153247 155.388136)
		(end 156.315882 155.455501)
		(width 0.13)
		(layer "In2.Cu")
		(net 253)
	)
	(segment
		(start 160.150002 138.8025)
		(end 160.150002 139.877498)
		(width 0.201)
		(layer "F.Cu")
		(net 254)
	)
	(segment
		(start 147.375501 164.302)
		(end 147.875001 163.8025)
		(width 0.256)
		(layer "F.Cu")
		(net 254)
	)
	(via
		(at 160.150002 139.877498)
		(size 0.45)
		(drill 0.1)
		(layers "F.Cu" "B.Cu")
		(net 254)
	)
	(via
		(at 147.875001 163.8025)
		(size 0.45)
		(drill 0.1)
		(layers "F.Cu" "B.Cu")
		(net 254)
	)
	(segment
		(start 154.875501 155.552)
		(end 154.977585 155.552)
		(width 0.148)
		(layer "In2.Cu")
		(net 254)
	)
	(segment
		(start 160.150002 139.877498)
		(end 160.150002 140.349998)
		(width 0.148)
		(layer "In2.Cu")
		(net 254)
	)
	(segment
		(start 148.675001 162.3025)
		(end 148.4 162.577501)
		(width 0.148)
		(layer "In2.Cu")
		(net 254)
	)
	(segment
		(start 159.5 141)
		(end 159.5 145.75)
		(width 0.148)
		(layer "In2.Cu")
		(net 254)
	)
	(segment
		(start 154.977585 156.052)
		(end 154.875501 156.052)
		(width 0.148)
		(layer "In2.Cu")
		(net 254)
	)
	(segment
		(start 147.875001 163.4025)
		(end 147.875001 163.8025)
		(width 0.148)
		(layer "In2.Cu")
		(net 254)
	)
	(segment
		(start 154.977585 158.052)
		(end 154.875501 158.052)
		(width 0.148)
		(layer "In2.Cu")
		(net 254)
	)
	(segment
		(start 155.9 149.5)
		(end 154.625501 150.774499)
		(width 0.148)
		(layer "In2.Cu")
		(net 254)
	)
	(segment
		(start 158.875001 148.874999)
		(end 158.25 149.5)
		(width 0.148)
		(layer "In2.Cu")
		(net 254)
	)
	(segment
		(start 148.4 162.877501)
		(end 147.875001 163.4025)
		(width 0.148)
		(layer "In2.Cu")
		(net 254)
	)
	(segment
		(start 152.8 161.8)
		(end 152.2975 162.3025)
		(width 0.148)
		(layer "In2.Cu")
		(net 254)
	)
	(segment
		(start 152.2975 162.3025)
		(end 148.675001 162.3025)
		(width 0.148)
		(layer "In2.Cu")
		(net 254)
	)
	(segment
		(start 159.5 145.75)
		(end 158.875001 146.374999)
		(width 0.148)
		(layer "In2.Cu")
		(net 254)
	)
	(segment
		(start 154.273417 157.052)
		(end 154.977585 157.052)
		(width 0.148)
		(layer "In2.Cu")
		(net 254)
	)
	(segment
		(start 154.273417 157.552)
		(end 154.977585 157.552)
		(width 0.148)
		(layer "In2.Cu")
		(net 254)
	)
	(segment
		(start 154.273417 156.552)
		(end 154.977585 156.552)
		(width 0.148)
		(layer "In2.Cu")
		(net 254)
	)
	(segment
		(start 148.4 162.577501)
		(end 148.4 162.877501)
		(width 0.148)
		(layer "In2.Cu")
		(net 254)
	)
	(segment
		(start 154.625501 150.774499)
		(end 154.625501 155.302)
		(width 0.148)
		(layer "In2.Cu")
		(net 254)
	)
	(segment
		(start 158.25 149.5)
		(end 155.9 149.5)
		(width 0.148)
		(layer "In2.Cu")
		(net 254)
	)
	(segment
		(start 154.875501 156.052)
		(end 154.273417 156.052)
		(width 0.148)
		(layer "In2.Cu")
		(net 254)
	)
	(segment
		(start 154.625501 158.302)
		(end 154.625501 158.774499)
		(width 0.148)
		(layer "In2.Cu")
		(net 254)
	)
	(segment
		(start 158.875001 146.374999)
		(end 158.875001 148.874999)
		(width 0.148)
		(layer "In2.Cu")
		(net 254)
	)
	(segment
		(start 160.150002 140.349998)
		(end 159.5 141)
		(width 0.148)
		(layer "In2.Cu")
		(net 254)
	)
	(segment
		(start 154.625501 158.774499)
		(end 152.8 160.6)
		(width 0.148)
		(layer "In2.Cu")
		(net 254)
	)
	(segment
		(start 152.8 160.6)
		(end 152.8 161.8)
		(width 0.148)
		(layer "In2.Cu")
		(net 254)
	)
	(arc
		(start 154.273417 157.052)
		(mid 154.09664 157.125223)
		(end 154.023417 157.302)
		(width 0.148)
		(layer "In2.Cu")
		(net 254)
	)
	(arc
		(start 154.977585 155.552)
		(mid 155.154362 155.625223)
		(end 155.227585 155.802)
		(width 0.148)
		(layer "In2.Cu")
		(net 254)
	)
	(arc
		(start 155.227585 157.802)
		(mid 155.154362 157.978777)
		(end 154.977585 158.052)
		(width 0.148)
		(layer "In2.Cu")
		(net 254)
	)
	(arc
		(start 154.875501 158.052)
		(mid 154.698724 158.125223)
		(end 154.625501 158.302)
		(width 0.148)
		(layer "In2.Cu")
		(net 254)
	)
	(arc
		(start 154.977585 156.552)
		(mid 155.154362 156.625223)
		(end 155.227585 156.802)
		(width 0.148)
		(layer "In2.Cu")
		(net 254)
	)
	(arc
		(start 154.273417 156.052)
		(mid 154.09664 156.125223)
		(end 154.023417 156.302)
		(width 0.148)
		(layer "In2.Cu")
		(net 254)
	)
	(arc
		(start 155.227585 155.802)
		(mid 155.154362 155.978777)
		(end 154.977585 156.052)
		(width 0.148)
		(layer "In2.Cu")
		(net 254)
	)
	(arc
		(start 155.227585 156.802)
		(mid 155.154362 156.978777)
		(end 154.977585 157.052)
		(width 0.148)
		(layer "In2.Cu")
		(net 254)
	)
	(arc
		(start 154.977585 157.552)
		(mid 155.154362 157.625223)
		(end 155.227585 157.802)
		(width 0.148)
		(layer "In2.Cu")
		(net 254)
	)
	(arc
		(start 154.023417 156.302)
		(mid 154.09664 156.478777)
		(end 154.273417 156.552)
		(width 0.148)
		(layer "In2.Cu")
		(net 254)
	)
	(arc
		(start 154.023417 157.302)
		(mid 154.09664 157.478777)
		(end 154.273417 157.552)
		(width 0.148)
		(layer "In2.Cu")
		(net 254)
	)
	(arc
		(start 154.625501 155.302)
		(mid 154.698724 155.478777)
		(end 154.875501 155.552)
		(width 0.148)
		(layer "In2.Cu")
		(net 254)
	)
	(segment
		(start 160.900001 146.2025)
		(end 160.900001 147.2775)
		(width 0.201)
		(layer "F.Cu")
		(net 255)
	)
	(segment
		(start 149.375501 165.301999)
		(end 149.875001 164.8025)
		(width 0.256)
		(layer "F.Cu")
		(net 255)
	)
	(via
		(at 149.875001 164.8025)
		(size 0.45)
		(drill 0.1)
		(layers "F.Cu" "B.Cu")
		(net 255)
	)
	(via
		(at 160.900001 147.2775)
		(size 0.45)
		(drill 0.1)
		(layers "F.Cu" "B.Cu")
		(net 255)
	)
	(segment
		(start 154.515307 164.058202)
		(end 154.515308 164.058201)
		(width 0.148)
		(layer "In2.Cu")
		(net 255)
	)
	(segment
		(start 160.875001 149.874999)
		(end 160.875001 147.3025)
		(width 0.148)
		(layer "In2.Cu")
		(net 255)
	)
	(segment
		(start 155.424213 161.431567)
		(end 155.424214 161.431566)
		(width 0.148)
		(layer "In2.Cu")
		(net 255)
	)
	(segment
		(start 150.375001 164.3025)
		(end 153.4475 164.3025)
		(width 0.148)
		(layer "In2.Cu")
		(net 255)
	)
	(segment
		(start 158.699755 159.050243)
		(end 159 158.75)
		(width 0.148)
		(layer "In2.Cu")
		(net 255)
	)
	(segment
		(start 154.457106 163.646445)
		(end 154.009998 163.199336)
		(width 0.148)
		(layer "In2.Cu")
		(net 255)
	)
	(segment
		(start 149.875001 164.8025)
		(end 150.375001 164.3025)
		(width 0.148)
		(layer "In2.Cu")
		(net 255)
	)
	(segment
		(start 154.103552 164)
		(end 154.103553 164)
		(width 0.148)
		(layer "In2.Cu")
		(net 255)
	)
	(segment
		(start 159 158.75)
		(end 159 151.75)
		(width 0.148)
		(layer "In2.Cu")
		(net 255)
	)
	(segment
		(start 156.131321 160.724459)
		(end 156.131322 160.724458)
		(width 0.148)
		(layer "In2.Cu")
		(net 255)
	)
	(segment
		(start 157.545538 159.663796)
		(end 158.050849 160.169107)
		(width 0.148)
		(layer "In2.Cu")
		(net 255)
	)
	(segment
		(start 156.83843 160.370904)
		(end 157.343741 160.876215)
		(width 0.148)
		(layer "In2.Cu")
		(net 255)
	)
	(segment
		(start 156.131322 161.078012)
		(end 156.636633 161.583323)
		(width 0.148)
		(layer "In2.Cu")
		(net 255)
	)
	(segment
		(start 157.545537 159.310243)
		(end 157.545538 159.310242)
		(width 0.148)
		(layer "In2.Cu")
		(net 255)
	)
	(segment
		(start 158.699754 159.050244)
		(end 158.699755 159.050243)
		(width 0.148)
		(layer "In2.Cu")
		(net 255)
	)
	(segment
		(start 154.103553 164)
		(end 154.161754 164.058201)
		(width 0.148)
		(layer "In2.Cu")
		(net 255)
	)
	(segment
		(start 154.717105 162.138675)
		(end 154.717106 162.138674)
		(width 0.148)
		(layer "In2.Cu")
		(net 255)
	)
	(segment
		(start 155.777768 161.431566)
		(end 156.283079 161.936877)
		(width 0.148)
		(layer "In2.Cu")
		(net 255)
	)
	(segment
		(start 156.838429 160.017351)
		(end 156.83843 160.01735)
		(width 0.148)
		(layer "In2.Cu")
		(net 255)
	)
	(segment
		(start 157.191984 160.01735)
		(end 157.697295 160.522661)
		(width 0.148)
		(layer "In2.Cu")
		(net 255)
	)
	(segment
		(start 154.363552 162.845782)
		(end 154.868863 163.351093)
		(width 0.148)
		(layer "In2.Cu")
		(net 255)
	)
	(segment
		(start 155.424214 161.78512)
		(end 155.929525 162.290431)
		(width 0.148)
		(layer "In2.Cu")
		(net 255)
	)
	(segment
		(start 154.009997 162.845783)
		(end 154.009998 162.845782)
		(width 0.148)
		(layer "In2.Cu")
		(net 255)
	)
	(segment
		(start 154.515308 163.704647)
		(end 154.457106 163.646445)
		(width 0.148)
		(layer "In2.Cu")
		(net 255)
	)
	(segment
		(start 156.484876 160.724458)
		(end 156.990187 161.229769)
		(width 0.148)
		(layer "In2.Cu")
		(net 255)
	)
	(segment
		(start 155.07066 162.138674)
		(end 155.575971 162.643985)
		(width 0.148)
		(layer "In2.Cu")
		(net 255)
	)
	(segment
		(start 157.899092 159.310242)
		(end 158.404403 159.815553)
		(width 0.148)
		(layer "In2.Cu")
		(net 255)
	)
	(segment
		(start 160.875001 147.3025)
		(end 160.900001 147.2775)
		(width 0.148)
		(layer "In2.Cu")
		(net 255)
	)
	(segment
		(start 153.4475 164.3025)
		(end 153.75 164)
		(width 0.148)
		(layer "In2.Cu")
		(net 255)
	)
	(segment
		(start 159 151.75)
		(end 160.875001 149.874999)
		(width 0.148)
		(layer "In2.Cu")
		(net 255)
	)
	(segment
		(start 158.757957 159.461999)
		(end 158.699755 159.403797)
		(width 0.148)
		(layer "In2.Cu")
		(net 255)
	)
	(segment
		(start 154.717106 162.492228)
		(end 155.222417 162.997539)
		(width 0.148)
		(layer "In2.Cu")
		(net 255)
	)
	(arc
		(start 155.222417 163.351093)
		(mid 155.29564 163.174316)
		(end 155.222417 162.997539)
		(width 0.148)
		(layer "In2.Cu")
		(net 255)
	)
	(arc
		(start 157.697295 160.522661)
		(mid 157.874072 160.595884)
		(end 158.050849 160.522661)
		(width 0.148)
		(layer "In2.Cu")
		(net 255)
	)
	(arc
		(start 156.131322 160.724458)
		(mid 156.308099 160.651235)
		(end 156.484876 160.724458)
		(width 0.148)
		(layer "In2.Cu")
		(net 255)
	)
	(arc
		(start 156.990187 161.229769)
		(mid 157.166964 161.302992)
		(end 157.343741 161.229769)
		(width 0.148)
		(layer "In2.Cu")
		(net 255)
	)
	(arc
		(start 154.009998 162.845782)
		(mid 154.186775 162.772559)
		(end 154.363552 162.845782)
		(width 0.148)
		(layer "In2.Cu")
		(net 255)
	)
	(arc
		(start 158.404403 159.815553)
		(mid 158.58118 159.888776)
		(end 158.757957 159.815553)
		(width 0.148)
		(layer "In2.Cu")
		(net 255)
	)
	(arc
		(start 154.009998 163.199336)
		(mid 153.936774 163.02256)
		(end 154.009997 162.845783)
		(width 0.148)
		(layer "In2.Cu")
		(net 255)
	)
	(arc
		(start 155.929525 162.643985)
		(mid 156.002748 162.467208)
		(end 155.929525 162.290431)
		(width 0.148)
		(layer "In2.Cu")
		(net 255)
	)
	(arc
		(start 157.545538 159.310242)
		(mid 157.722315 159.237019)
		(end 157.899092 159.310242)
		(width 0.148)
		(layer "In2.Cu")
		(net 255)
	)
	(arc
		(start 154.717106 162.138674)
		(mid 154.893883 162.065451)
		(end 155.07066 162.138674)
		(width 0.148)
		(layer "In2.Cu")
		(net 255)
	)
	(arc
		(start 157.343741 161.229769)
		(mid 157.416964 161.052992)
		(end 157.343741 160.876215)
		(width 0.148)
		(layer "In2.Cu")
		(net 255)
	)
	(arc
		(start 155.424214 161.431566)
		(mid 155.600991 161.358343)
		(end 155.777768 161.431566)
		(width 0.148)
		(layer "In2.Cu")
		(net 255)
	)
	(arc
		(start 155.575971 162.643985)
		(mid 155.752748 162.717208)
		(end 155.929525 162.643985)
		(width 0.148)
		(layer "In2.Cu")
		(net 255)
	)
	(arc
		(start 154.868863 163.351093)
		(mid 155.04564 163.424316)
		(end 155.222417 163.351093)
		(width 0.148)
		(layer "In2.Cu")
		(net 255)
	)
	(arc
		(start 157.545538 159.663796)
		(mid 157.472314 159.48702)
		(end 157.545537 159.310243)
		(width 0.148)
		(layer "In2.Cu")
		(net 255)
	)
	(arc
		(start 153.75 164)
		(mid 153.926776 163.926777)
		(end 154.103552 164)
		(width 0.148)
		(layer "In2.Cu")
		(net 255)
	)
	(arc
		(start 158.757957 159.815553)
		(mid 158.83118 159.638776)
		(end 158.757957 159.461999)
		(width 0.148)
		(layer "In2.Cu")
		(net 255)
	)
	(arc
		(start 158.050849 160.522661)
		(mid 158.124072 160.345884)
		(end 158.050849 160.169107)
		(width 0.148)
		(layer "In2.Cu")
		(net 255)
	)
	(arc
		(start 154.717106 162.492228)
		(mid 154.643882 162.315452)
		(end 154.717105 162.138675)
		(width 0.148)
		(layer "In2.Cu")
		(net 255)
	)
	(arc
		(start 156.131322 161.078012)
		(mid 156.058098 160.901236)
		(end 156.131321 160.724459)
		(width 0.148)
		(layer "In2.Cu")
		(net 255)
	)
	(arc
		(start 156.283079 161.936877)
		(mid 156.459856 162.0101)
		(end 156.636633 161.936877)
		(width 0.148)
		(layer "In2.Cu")
		(net 255)
	)
	(arc
		(start 154.515308 164.058201)
		(mid 154.588531 163.881424)
		(end 154.515308 163.704647)
		(width 0.148)
		(layer "In2.Cu")
		(net 255)
	)
	(arc
		(start 155.424214 161.78512)
		(mid 155.35099 161.608344)
		(end 155.424213 161.431567)
		(width 0.148)
		(layer "In2.Cu")
		(net 255)
	)
	(arc
		(start 158.699755 159.403797)
		(mid 158.626531 159.227021)
		(end 158.699754 159.050244)
		(width 0.148)
		(layer "In2.Cu")
		(net 255)
	)
	(arc
		(start 156.636633 161.936877)
		(mid 156.709856 161.7601)
		(end 156.636633 161.583323)
		(width 0.148)
		(layer "In2.Cu")
		(net 255)
	)
	(arc
		(start 156.83843 160.370904)
		(mid 156.765206 160.194128)
		(end 156.838429 160.017351)
		(width 0.148)
		(layer "In2.Cu")
		(net 255)
	)
	(arc
		(start 154.161754 164.058201)
		(mid 154.33853 164.131425)
		(end 154.515307 164.058202)
		(width 0.148)
		(layer "In2.Cu")
		(net 255)
	)
	(arc
		(start 156.83843 160.01735)
		(mid 157.015207 159.944127)
		(end 157.191984 160.01735)
		(width 0.148)
		(layer "In2.Cu")
		(net 255)
	)
	(segment
		(start 161.150002 138.8025)
		(end 161.150002 139.8775)
		(width 0.201)
		(layer "F.Cu")
		(net 256)
	)
	(segment
		(start 148.375501 165.302)
		(end 148.875001 164.802501)
		(width 0.256)
		(layer "F.Cu")
		(net 256)
	)
	(via
		(at 161.150002 139.8775)
		(size 0.45)
		(drill 0.1)
		(layers "F.Cu" "B.Cu")
		(net 256)
	)
	(via
		(at 148.875001 164.802501)
		(size 0.45)
		(drill 0.1)
		(layers "F.Cu" "B.Cu")
		(net 256)
	)
	(segment
		(start 160.9 145.801625)
		(end 161.375001 146.276626)
		(width 0.148)
		(layer "In2.Cu")
		(net 256)
	)
	(segment
		(start 153.7475 165.2525)
		(end 149.325 165.2525)
		(width 0.148)
		(layer "In2.Cu")
		(net 256)
	)
	(segment
		(start 161.375001 146.276626)
		(end 161.375001 150.124999)
		(width 0.148)
		(layer "In2.Cu")
		(net 256)
	)
	(segment
		(start 161.172213 143.35)
		(end 161.15 143.35)
		(width 0.148)
		(layer "In2.Cu")
		(net 256)
	)
	(segment
		(start 160.627787 142.35)
		(end 161.172213 142.35)
		(width 0.148)
		(layer "In2.Cu")
		(net 256)
	)
	(segment
		(start 160.9 140.127502)
		(end 160.9 141.1)
		(width 0.148)
		(layer "In2.Cu")
		(net 256)
	)
	(segment
		(start 161.375001 150.124999)
		(end 160 151.5)
		(width 0.148)
		(layer "In2.Cu")
		(net 256)
	)
	(segment
		(start 160.9 143.6)
		(end 160.9 145.801625)
		(width 0.148)
		(layer "In2.Cu")
		(net 256)
	)
	(segment
		(start 160.65 141.85)
		(end 161.172213 141.85)
		(width 0.148)
		(layer "In2.Cu")
		(net 256)
	)
	(segment
		(start 160 151.5)
		(end 160 159)
		(width 0.148)
		(layer "In2.Cu")
		(net 256)
	)
	(segment
		(start 160.65 141.35)
		(end 160.627787 141.35)
		(width 0.148)
		(layer "In2.Cu")
		(net 256)
	)
	(segment
		(start 160 159)
		(end 153.7475 165.2525)
		(width 0.148)
		(layer "In2.Cu")
		(net 256)
	)
	(segment
		(start 160.627787 141.85)
		(end 160.65 141.85)
		(width 0.148)
		(layer "In2.Cu")
		(net 256)
	)
	(segment
		(start 149.325 165.2525)
		(end 148.875001 164.802501)
		(width 0.148)
		(layer "In2.Cu")
		(net 256)
	)
	(segment
		(start 161.150002 139.8775)
		(end 160.9 140.127502)
		(width 0.148)
		(layer "In2.Cu")
		(net 256)
	)
	(segment
		(start 160.627787 142.85)
		(end 161.172213 142.85)
		(width 0.148)
		(layer "In2.Cu")
		(net 256)
	)
	(arc
		(start 160.627787 142.35)
		(mid 160.45101 142.423223)
		(end 160.377787 142.6)
		(width 0.148)
		(layer "In2.Cu")
		(net 256)
	)
	(arc
		(start 161.15 143.35)
		(mid 160.973223 143.423223)
		(end 160.9 143.6)
		(width 0.148)
		(layer "In2.Cu")
		(net 256)
	)
	(arc
		(start 160.377787 142.6)
		(mid 160.45101 142.776777)
		(end 160.627787 142.85)
		(width 0.148)
		(layer "In2.Cu")
		(net 256)
	)
	(arc
		(start 160.627787 141.35)
		(mid 160.45101 141.423223)
		(end 160.377787 141.6)
		(width 0.148)
		(layer "In2.Cu")
		(net 256)
	)
	(arc
		(start 161.422213 142.1)
		(mid 161.34899 142.276777)
		(end 161.172213 142.35)
		(width 0.148)
		(layer "In2.Cu")
		(net 256)
	)
	(arc
		(start 161.422213 143.1)
		(mid 161.34899 143.276777)
		(end 161.172213 143.35)
		(width 0.148)
		(layer "In2.Cu")
		(net 256)
	)
	(arc
		(start 161.172213 142.85)
		(mid 161.34899 142.923223)
		(end 161.422213 143.1)
		(width 0.148)
		(layer "In2.Cu")
		(net 256)
	)
	(arc
		(start 160.9 141.1)
		(mid 160.826777 141.276777)
		(end 160.65 141.35)
		(width 0.148)
		(layer "In2.Cu")
		(net 256)
	)
	(arc
		(start 160.377787 141.6)
		(mid 160.45101 141.776777)
		(end 160.627787 141.85)
		(width 0.148)
		(layer "In2.Cu")
		(net 256)
	)
	(arc
		(start 161.172213 141.85)
		(mid 161.34899 141.923223)
		(end 161.422213 142.1)
		(width 0.148)
		(layer "In2.Cu")
		(net 256)
	)
	(segment
		(start 161.900001 146.2025)
		(end 161.900001 147.2775)
		(width 0.201)
		(layer "F.Cu")
		(net 257)
	)
	(segment
		(start 148.375501 166.302)
		(end 148.875001 165.8025)
		(width 0.256)
		(layer "F.Cu")
		(net 257)
	)
	(via
		(at 148.875001 165.8025)
		(size 0.45)
		(drill 0.1)
		(layers "F.Cu" "B.Cu")
		(net 257)
	)
	(via
		(at 161.900001 147.2775)
		(size 0.45)
		(drill 0.1)
		(layers "F.Cu" "B.Cu")
		(net 257)
	)
	(segment
		(start 159.324762 160.925241)
		(end 159.32476 160.925242)
		(width 0.148)
		(layer "In2.Cu")
		(net 257)
	)
	(segment
		(start 156.157077 164.828645)
		(end 156.157077 164.828646)
		(width 0.148)
		(layer "In2.Cu")
		(net 257)
	)
	(segment
		(start 157.571295 163.414427)
		(end 157.571295 163.414428)
		(width 0.148)
		(layer "In2.Cu")
		(net 257)
	)
	(segment
		(start 154.714246 165.153586)
		(end 154.728555 165.167895)
		(width 0.148)
		(layer "In2.Cu")
		(net 257)
	)
	(segment
		(start 156.482018 163.03226)
		(end 156.482018 163.032259)
		(width 0.148)
		(layer "In2.Cu")
		(net 257)
	)
	(segment
		(start 155.449968 165.535754)
		(end 155.449968 165.535755)
		(width 0.148)
		(layer "In2.Cu")
		(net 257)
	)
	(segment
		(start 155.0678 164.446478)
		(end 155.0678 164.446477)
		(width 0.148)
		(layer "In2.Cu")
		(net 257)
	)
	(segment
		(start 154.375 165.521448)
		(end 154.375001 165.521446)
		(width 0.148)
		(layer "In2.Cu")
		(net 257)
	)
	(segment
		(start 154.360693 165.153584)
		(end 154.360692 165.153586)
		(width 0.148)
		(layer "In2.Cu")
		(net 257)
	)
	(segment
		(start 158.603344 161.264486)
		(end 158.985513 161.646656)
		(width 0.148)
		(layer "In2.Cu")
		(net 257)
	)
	(segment
		(start 161.900001 150.349999)
		(end 161.900001 147.2775)
		(width 0.148)
		(layer "In2.Cu")
		(net 257)
	)
	(segment
		(start 159.32476 160.925242)
		(end 161 159.25)
		(width 0.148)
		(layer "In2.Cu")
		(net 257)
	)
	(segment
		(start 156.864186 164.121536)
		(end 156.864186 164.121537)
		(width 0.148)
		(layer "In2.Cu")
		(net 257)
	)
	(segment
		(start 148.875001 165.8025)
		(end 149.375001 166.3025)
		(width 0.148)
		(layer "In2.Cu")
		(net 257)
	)
	(segment
		(start 157.189127 162.325151)
		(end 157.189127 162.32515)
		(width 0.148)
		(layer "In2.Cu")
		(net 257)
	)
	(segment
		(start 158.985513 162.000209)
		(end 158.985513 162.00021)
		(width 0.148)
		(layer "In2.Cu")
		(net 257)
	)
	(segment
		(start 156.482017 163.385813)
		(end 156.864186 163.767983)
		(width 0.148)
		(layer "In2.Cu")
		(net 257)
	)
	(segment
		(start 154.375001 165.521446)
		(end 154.360693 165.507138)
		(width 0.148)
		(layer "In2.Cu")
		(net 257)
	)
	(segment
		(start 153.9475 166.3025)
		(end 154.375 165.875)
		(width 0.148)
		(layer "In2.Cu")
		(net 257)
	)
	(segment
		(start 156.128463 163.739368)
		(end 156.510633 164.121537)
		(width 0.148)
		(layer "In2.Cu")
		(net 257)
	)
	(segment
		(start 157.542681 162.32515)
		(end 157.924851 162.707319)
		(width 0.148)
		(layer "In2.Cu")
		(net 257)
	)
	(segment
		(start 158.278404 162.707318)
		(end 158.278404 162.707319)
		(width 0.148)
		(layer "In2.Cu")
		(net 257)
	)
	(segment
		(start 157.896236 161.618042)
		(end 157.896236 161.618041)
		(width 0.148)
		(layer "In2.Cu")
		(net 257)
	)
	(segment
		(start 155.774908 164.092922)
		(end 156.157077 164.475092)
		(width 0.148)
		(layer "In2.Cu")
		(net 257)
	)
	(segment
		(start 158.603345 160.910933)
		(end 158.603345 160.910932)
		(width 0.148)
		(layer "In2.Cu")
		(net 257)
	)
	(segment
		(start 157.896235 161.971595)
		(end 158.278404 162.353765)
		(width 0.148)
		(layer "In2.Cu")
		(net 257)
	)
	(segment
		(start 155.067799 164.800031)
		(end 155.449968 165.182201)
		(width 0.148)
		(layer "In2.Cu")
		(net 257)
	)
	(segment
		(start 156.835572 163.032259)
		(end 157.217742 163.414428)
		(width 0.148)
		(layer "In2.Cu")
		(net 257)
	)
	(segment
		(start 154.728555 165.167895)
		(end 155.096415 165.535755)
		(width 0.148)
		(layer "In2.Cu")
		(net 257)
	)
	(segment
		(start 161 159.25)
		(end 161 151.25)
		(width 0.148)
		(layer "In2.Cu")
		(net 257)
	)
	(segment
		(start 158.956899 160.910932)
		(end 158.971208 160.925241)
		(width 0.148)
		(layer "In2.Cu")
		(net 257)
	)
	(segment
		(start 155.774909 163.739369)
		(end 155.774909 163.739368)
		(width 0.148)
		(layer "In2.Cu")
		(net 257)
	)
	(segment
		(start 161 151.25)
		(end 161.900001 150.349999)
		(width 0.148)
		(layer "In2.Cu")
		(net 257)
	)
	(segment
		(start 158.24979 161.618041)
		(end 158.63196 162.00021)
		(width 0.148)
		(layer "In2.Cu")
		(net 257)
	)
	(segment
		(start 157.189126 162.678704)
		(end 157.571295 163.060874)
		(width 0.148)
		(layer "In2.Cu")
		(net 257)
	)
	(segment
		(start 149.375001 166.3025)
		(end 153.9475 166.3025)
		(width 0.148)
		(layer "In2.Cu")
		(net 257)
	)
	(segment
		(start 155.421354 164.446477)
		(end 155.803524 164.828646)
		(width 0.148)
		(layer "In2.Cu")
		(net 257)
	)
	(arc
		(start 156.482017 163.385813)
		(mid 156.408794 163.209036)
		(end 156.482018 163.03226)
		(width 0.148)
		(layer "In2.Cu")
		(net 257)
	)
	(arc
		(start 155.774909 163.739368)
		(mid 155.951686 163.666145)
		(end 156.128463 163.739368)
		(width 0.148)
		(layer "In2.Cu")
		(net 257)
	)
	(arc
		(start 158.603345 160.910932)
		(mid 158.780122 160.837709)
		(end 158.956899 160.910932)
		(width 0.148)
		(layer "In2.Cu")
		(net 257)
	)
	(arc
		(start 156.864186 164.121537)
		(mid 156.937409 163.94476)
		(end 156.864186 163.767983)
		(width 0.148)
		(layer "In2.Cu")
		(net 257)
	)
	(arc
		(start 156.157077 164.828646)
		(mid 156.2303 164.651869)
		(end 156.157077 164.475092)
		(width 0.148)
		(layer "In2.Cu")
		(net 257)
	)
	(arc
		(start 157.189127 162.32515)
		(mid 157.365904 162.251927)
		(end 157.542681 162.32515)
		(width 0.148)
		(layer "In2.Cu")
		(net 257)
	)
	(arc
		(start 155.0678 164.446477)
		(mid 155.244577 164.373254)
		(end 155.421354 164.446477)
		(width 0.148)
		(layer "In2.Cu")
		(net 257)
	)
	(arc
		(start 158.278404 162.707319)
		(mid 158.351627 162.530542)
		(end 158.278404 162.353765)
		(width 0.148)
		(layer "In2.Cu")
		(net 257)
	)
	(arc
		(start 157.217742 163.414428)
		(mid 157.394519 163.487651)
		(end 157.571295 163.414427)
		(width 0.148)
		(layer "In2.Cu")
		(net 257)
	)
	(arc
		(start 155.067799 164.800031)
		(mid 154.994576 164.623254)
		(end 155.0678 164.446478)
		(width 0.148)
		(layer "In2.Cu")
		(net 257)
	)
	(arc
		(start 158.971208 160.925241)
		(mid 159.147985 160.998464)
		(end 159.324762 160.925241)
		(width 0.148)
		(layer "In2.Cu")
		(net 257)
	)
	(arc
		(start 158.603344 161.264486)
		(mid 158.530121 161.087709)
		(end 158.603345 160.910933)
		(width 0.148)
		(layer "In2.Cu")
		(net 257)
	)
	(arc
		(start 154.360693 165.507138)
		(mid 154.28747 165.330361)
		(end 154.360693 165.153584)
		(width 0.148)
		(layer "In2.Cu")
		(net 257)
	)
	(arc
		(start 157.896235 161.971595)
		(mid 157.823012 161.794818)
		(end 157.896236 161.618042)
		(width 0.148)
		(layer "In2.Cu")
		(net 257)
	)
	(arc
		(start 157.571295 163.414428)
		(mid 157.644518 163.237651)
		(end 157.571295 163.060874)
		(width 0.148)
		(layer "In2.Cu")
		(net 257)
	)
	(arc
		(start 157.189126 162.678704)
		(mid 157.115903 162.501927)
		(end 157.189127 162.325151)
		(width 0.148)
		(layer "In2.Cu")
		(net 257)
	)
	(arc
		(start 157.896236 161.618041)
		(mid 158.073013 161.544818)
		(end 158.24979 161.618041)
		(width 0.148)
		(layer "In2.Cu")
		(net 257)
	)
	(arc
		(start 155.803524 164.828646)
		(mid 155.980301 164.901869)
		(end 156.157077 164.828645)
		(width 0.148)
		(layer "In2.Cu")
		(net 257)
	)
	(arc
		(start 157.924851 162.707319)
		(mid 158.101628 162.780542)
		(end 158.278404 162.707318)
		(width 0.148)
		(layer "In2.Cu")
		(net 257)
	)
	(arc
		(start 155.774908 164.092922)
		(mid 155.701685 163.916145)
		(end 155.774909 163.739369)
		(width 0.148)
		(layer "In2.Cu")
		(net 257)
	)
	(arc
		(start 154.375 165.875)
		(mid 154.448224 165.698223)
		(end 154.375 165.521448)
		(width 0.148)
		(layer "In2.Cu")
		(net 257)
	)
	(arc
		(start 155.096415 165.535755)
		(mid 155.273192 165.608978)
		(end 155.449968 165.535754)
		(width 0.148)
		(layer "In2.Cu")
		(net 257)
	)
	(arc
		(start 156.510633 164.121537)
		(mid 156.68741 164.19476)
		(end 156.864186 164.121536)
		(width 0.148)
		(layer "In2.Cu")
		(net 257)
	)
	(arc
		(start 154.360692 165.153586)
		(mid 154.537469 165.080363)
		(end 154.714246 165.153586)
		(width 0.148)
		(layer "In2.Cu")
		(net 257)
	)
	(arc
		(start 156.482018 163.032259)
		(mid 156.658795 162.959036)
		(end 156.835572 163.032259)
		(width 0.148)
		(layer "In2.Cu")
		(net 257)
	)
	(arc
		(start 158.63196 162.00021)
		(mid 158.808737 162.073433)
		(end 158.985513 162.000209)
		(width 0.148)
		(layer "In2.Cu")
		(net 257)
	)
	(arc
		(start 155.449968 165.535755)
		(mid 155.523191 165.358978)
		(end 155.449968 165.182201)
		(width 0.148)
		(layer "In2.Cu")
		(net 257)
	)
	(arc
		(start 158.985513 162.00021)
		(mid 159.058736 161.823433)
		(end 158.985513 161.646656)
		(width 0.148)
		(layer "In2.Cu")
		(net 257)
	)
	(segment
		(start 148.375501 167.302)
		(end 148.875001 166.8025)
		(width 0.256)
		(layer "F.Cu")
		(net 258)
	)
	(segment
		(start 162.150002 138.8025)
		(end 162.150002 139.8775)
		(width 0.201)
		(layer "F.Cu")
		(net 258)
	)
	(via
		(at 162.150002 139.8775)
		(size 0.45)
		(drill 0.1)
		(layers "F.Cu" "B.Cu")
		(net 258)
	)
	(via
		(at 148.875001 166.8025)
		(size 0.45)
		(drill 0.1)
		(layers "F.Cu" "B.Cu")
		(net 258)
	)
	(segment
		(start 162.5 150.5)
		(end 162 151)
		(width 0.148)
		(layer "In2.Cu")
		(net 258)
	)
	(segment
		(start 149.375001 167.3025)
		(end 148.875001 166.8025)
		(width 0.148)
		(layer "In2.Cu")
		(net 258)
	)
	(segment
		(start 152.6035 167)
		(end 152.301 167.3025)
		(width 0.148)
		(layer "In2.Cu")
		(net 258)
	)
	(segment
		(start 162 151)
		(end 162 159.5)
		(width 0.148)
		(layer "In2.Cu")
		(net 258)
	)
	(segment
		(start 163.488775 142.15)
		(end 163.15 142.15)
		(width 0.148)
		(layer "In2.Cu")
		(net 258)
	)
	(segment
		(start 154.5 167)
		(end 152.6035 167)
		(width 0.148)
		(layer "In2.Cu")
		(net 258)
	)
	(segment
		(start 162 159.5)
		(end 154.5 167)
		(width 0.148)
		(layer "In2.Cu")
		(net 258)
	)
	(segment
		(start 162.150002 139.8775)
		(end 162.9 140.627498)
		(width 0.148)
		(layer "In2.Cu")
		(net 258)
	)
	(segment
		(start 163.15 141.65)
		(end 163.488775 141.65)
		(width 0.148)
		(layer "In2.Cu")
		(net 258)
	)
	(segment
		(start 162.9 140.627498)
		(end 162.9 141.4)
		(width 0.148)
		(layer "In2.Cu")
		(net 258)
	)
	(segment
		(start 162.5 145.877501)
		(end 162.5 150.5)
		(width 0.148)
		(layer "In2.Cu")
		(net 258)
	)
	(segment
		(start 162.9 145.477501)
		(end 162.5 145.877501)
		(width 0.148)
		(layer "In2.Cu")
		(net 258)
	)
	(segment
		(start 152.301 167.3025)
		(end 149.375001 167.3025)
		(width 0.148)
		(layer "In2.Cu")
		(net 258)
	)
	(segment
		(start 162.9 142.4)
		(end 162.9 145.477501)
		(width 0.148)
		(layer "In2.Cu")
		(net 258)
	)
	(arc
		(start 163.738775 141.9)
		(mid 163.665552 142.076777)
		(end 163.488775 142.15)
		(width 0.148)
		(layer "In2.Cu")
		(net 258)
	)
	(arc
		(start 163.488775 141.65)
		(mid 163.665552 141.723223)
		(end 163.738775 141.9)
		(width 0.148)
		(layer "In2.Cu")
		(net 258)
	)
	(arc
		(start 162.9 141.4)
		(mid 162.973223 141.576777)
		(end 163.15 141.65)
		(width 0.148)
		(layer "In2.Cu")
		(net 258)
	)
	(arc
		(start 163.15 142.15)
		(mid 162.973223 142.223223)
		(end 162.9 142.4)
		(width 0.148)
		(layer "In2.Cu")
		(net 258)
	)
	(segment
		(start 162.900002 146.2025)
		(end 162.900002 147.277498)
		(width 0.201)
		(layer "F.Cu")
		(net 259)
	)
	(segment
		(start 150.375501 166.302)
		(end 150.875001 165.8025)
		(width 0.256)
		(layer "F.Cu")
		(net 259)
	)
	(via
		(at 150.875001 165.8025)
		(size 0.45)
		(drill 0.1)
		(layers "F.Cu" "B.Cu")
		(net 259)
	)
	(via
		(at 162.900002 147.277498)
		(size 0.45)
		(drill 0.1)
		(layers "F.Cu" "B.Cu")
		(net 259)
	)
	(segment
		(start 160.420599 151.821972)
		(end 160.420597 151.821973)
		(width 0.148)
		(layer "In4.Cu")
		(net 259)
	)
	(segment
		(start 150.875001 165.4205)
		(end 150.875001 165.8025)
		(width 0.148)
		(layer "In4.Cu")
		(net 259)
	)
	(segment
		(start 153.703062 158.893061)
		(end 153.703061 158.893062)
		(width 0.148)
		(layer "In4.Cu")
		(net 259)
	)
	(segment
		(start 156.673539 154.08534)
		(end 156.673538 154.085341)
		(width 0.148)
		(layer "In4.Cu")
		(net 259)
	)
	(segment
		(start 153.845103 156.913776)
		(end 153.845102 156.913777)
		(width 0.148)
		(layer "In4.Cu")
		(net 259)
	)
	(segment
		(start 160.209083 150.903348)
		(end 160.209083 150.903349)
		(width 0.148)
		(layer "In4.Cu")
		(net 259)
	)
	(segment
		(start 151.400501 162.116)
		(end 151.210501 162.306)
		(width 0.148)
		(layer "In4.Cu")
		(net 259)
	)
	(segment
		(start 160.209084 150.549795)
		(end 160.209083 150.549796)
		(width 0.148)
		(layer "In4.Cu")
		(net 259)
	)
	(segment
		(start 153.137993 157.974439)
		(end 153.703061 158.539508)
		(width 0.148)
		(layer "In4.Cu")
		(net 259)
	)
	(segment
		(start 159.359934 153.236189)
		(end 159.359933 153.23619)
		(width 0.148)
		(layer "In4.Cu")
		(net 259)
	)
	(segment
		(start 160.209083 150.903349)
		(end 160.774151 151.468418)
		(width 0.148)
		(layer "In4.Cu")
		(net 259)
	)
	(segment
		(start 151.210501 162.306)
		(end 150.670501 162.306)
		(width 0.148)
		(layer "In4.Cu")
		(net 259)
	)
	(segment
		(start 154.552211 156.560221)
		(end 155.117279 157.12529)
		(width 0.148)
		(layer "In4.Cu")
		(net 259)
	)
	(segment
		(start 156.177945 156.064626)
		(end 156.177943 156.064627)
		(width 0.148)
		(layer "In4.Cu")
		(net 259)
	)
	(segment
		(start 158.299272 153.943299)
		(end 158.29927 153.9433)
		(width 0.148)
		(layer "In4.Cu")
		(net 259)
	)
	(segment
		(start 158.087756 153.024675)
		(end 158.087756 153.024676)
		(width 0.148)
		(layer "In4.Cu")
		(net 259)
	)
	(segment
		(start 158.794865 152.317567)
		(end 159.359933 152.882636)
		(width 0.148)
		(layer "In4.Cu")
		(net 259)
	)
	(segment
		(start 155.470836 156.771735)
		(end 155.470834 156.771736)
		(width 0.148)
		(layer "In4.Cu")
		(net 259)
	)
	(segment
		(start 159.006381 153.23619)
		(end 159.006379 153.236191)
		(width 0.148)
		(layer "In4.Cu")
		(net 259)
	)
	(segment
		(start 157.380647 153.731785)
		(end 157.945715 154.296854)
		(width 0.148)
		(layer "In4.Cu")
		(net 259)
	)
	(segment
		(start 154.552211 156.56022)
		(end 154.552211 156.560221)
		(width 0.148)
		(layer "In4.Cu")
		(net 259)
	)
	(segment
		(start 155.25932 155.853111)
		(end 155.25932 155.853112)
		(width 0.148)
		(layer "In4.Cu")
		(net 259)
	)
	(segment
		(start 151.709729 159.967772)
		(end 151.709729 161.4035)
		(width 0.148)
		(layer "In4.Cu")
		(net 259)
	)
	(segment
		(start 155.966429 155.146003)
		(end 156.531497 155.711072)
		(width 0.148)
		(layer "In4.Cu")
		(net 259)
	)
	(segment
		(start 151.400501 161.712728)
		(end 151.400501 162.116)
		(width 0.148)
		(layer "In4.Cu")
		(net 259)
	)
	(segment
		(start 154.410171 158.185952)
		(end 154.41017 158.185953)
		(width 0.148)
		(layer "In4.Cu")
		(net 259)
	)
	(segment
		(start 154.763725 157.478845)
		(end 154.198656 156.913777)
		(width 0.148)
		(layer "In4.Cu")
		(net 259)
	)
	(segment
		(start 155.824389 156.771734)
		(end 155.824388 156.771735)
		(width 0.148)
		(layer "In4.Cu")
		(net 259)
	)
	(segment
		(start 150.380501 162.596)
		(end 150.380501 164.926)
		(width 0.148)
		(layer "In4.Cu")
		(net 259)
	)
	(segment
		(start 161.127706 151.114865)
		(end 160.562637 150.549796)
		(width 0.148)
		(layer "In4.Cu")
		(net 259)
	)
	(segment
		(start 157.945716 154.650407)
		(end 157.945715 154.650408)
		(width 0.148)
		(layer "In4.Cu")
		(net 259)
	)
	(segment
		(start 159.71349 152.529081)
		(end 159.713488 152.529082)
		(width 0.148)
		(layer "In4.Cu")
		(net 259)
	)
	(segment
		(start 155.96643 154.792449)
		(end 155.966429 154.79245)
		(width 0.148)
		(layer "In4.Cu")
		(net 259)
	)
	(segment
		(start 152.890197 158.787307)
		(end 152.890198 158.787305)
		(width 0.148)
		(layer "In4.Cu")
		(net 259)
	)
	(segment
		(start 159.501975 151.256904)
		(end 159.501974 151.256905)
		(width 0.148)
		(layer "In4.Cu")
		(net 259)
	)
	(segment
		(start 155.25932 155.853112)
		(end 155.824388 156.418181)
		(width 0.148)
		(layer "In4.Cu")
		(net 259)
	)
	(segment
		(start 157.380648 153.378231)
		(end 157.380647 153.378232)
		(width 0.148)
		(layer "In4.Cu")
		(net 259)
	)
	(segment
		(start 159.713488 152.529082)
		(end 159.148419 151.964014)
		(width 0.148)
		(layer "In4.Cu")
		(net 259)
	)
	(segment
		(start 158.29927 153.9433)
		(end 157.734201 153.378232)
		(width 0.148)
		(layer "In4.Cu")
		(net 259)
	)
	(segment
		(start 151.709729 161.4035)
		(end 151.400501 161.712728)
		(width 0.148)
		(layer "In4.Cu")
		(net 259)
	)
	(segment
		(start 154.763727 157.478844)
		(end 154.763725 157.478845)
		(width 0.148)
		(layer "In4.Cu")
		(net 259)
	)
	(segment
		(start 156.885054 155.357517)
		(end 156.885052 155.357518)
		(width 0.148)
		(layer "In4.Cu")
		(net 259)
	)
	(segment
		(start 153.845102 157.267329)
		(end 153.845102 157.26733)
		(width 0.148)
		(layer "In4.Cu")
		(net 259)
	)
	(segment
		(start 155.470834 156.771736)
		(end 154.905765 156.206668)
		(width 0.148)
		(layer "In4.Cu")
		(net 259)
	)
	(segment
		(start 153.349509 158.893062)
		(end 153.349507 158.893063)
		(width 0.148)
		(layer "In4.Cu")
		(net 259)
	)
	(segment
		(start 154.552212 156.206667)
		(end 154.552211 156.206668)
		(width 0.148)
		(layer "In4.Cu")
		(net 259)
	)
	(segment
		(start 156.177943 156.064627)
		(end 155.612874 155.499559)
		(width 0.148)
		(layer "In4.Cu")
		(net 259)
	)
	(segment
		(start 161.127706 151.114866)
		(end 161.127706 151.114865)
		(width 0.148)
		(layer "In4.Cu")
		(net 259)
	)
	(segment
		(start 158.794865 152.317566)
		(end 158.794865 152.317567)
		(width 0.148)
		(layer "In4.Cu")
		(net 259)
	)
	(segment
		(start 158.794866 151.964013)
		(end 158.794865 151.964014)
		(width 0.148)
		(layer "In4.Cu")
		(net 259)
	)
	(segment
		(start 155.11728 157.478843)
		(end 155.117279 157.478844)
		(width 0.148)
		(layer "In4.Cu")
		(net 259)
	)
	(segment
		(start 156.531498 156.064625)
		(end 156.531497 156.064626)
		(width 0.148)
		(layer "In4.Cu")
		(net 259)
	)
	(segment
		(start 156.673538 154.438893)
		(end 156.673538 154.438894)
		(width 0.148)
		(layer "In4.Cu")
		(net 259)
	)
	(segment
		(start 153.137994 157.620885)
		(end 153.137993 157.620886)
		(width 0.148)
		(layer "In4.Cu")
		(net 259)
	)
	(segment
		(start 156.673538 154.438894)
		(end 157.238606 155.003963)
		(width 0.148)
		(layer "In4.Cu")
		(net 259)
	)
	(segment
		(start 160.067043 152.52908)
		(end 160.067042 152.529081)
		(width 0.148)
		(layer "In4.Cu")
		(net 259)
	)
	(segment
		(start 159.501974 151.610457)
		(end 159.501974 151.610458)
		(width 0.148)
		(layer "In4.Cu")
		(net 259)
	)
	(segment
		(start 161.375501 148.801999)
		(end 161.375501 150.302)
		(width 0.148)
		(layer "In4.Cu")
		(net 259)
	)
	(segment
		(start 154.056616 158.185954)
		(end 153.491547 157.620886)
		(width 0.148)
		(layer "In4.Cu")
		(net 259)
	)
	(segment
		(start 150.380501 164.926)
		(end 150.875001 165.4205)
		(width 0.148)
		(layer "In4.Cu")
		(net 259)
	)
	(segment
		(start 161.375501 150.655554)
		(end 161.481259 150.761312)
		(width 0.148)
		(layer "In4.Cu")
		(net 259)
	)
	(segment
		(start 158.652825 153.943298)
		(end 158.652824 153.943299)
		(width 0.148)
		(layer "In4.Cu")
		(net 259)
	)
	(segment
		(start 153.349507 158.893063)
		(end 153.24375 158.787306)
		(width 0.148)
		(layer "In4.Cu")
		(net 259)
	)
	(segment
		(start 157.592163 154.650408)
		(end 157.592161 154.650409)
		(width 0.148)
		(layer "In4.Cu")
		(net 259)
	)
	(segment
		(start 159.006379 153.236191)
		(end 158.44131 152.671123)
		(width 0.148)
		(layer "In4.Cu")
		(net 259)
	)
	(segment
		(start 160.420597 151.821973)
		(end 159.855528 151.256905)
		(width 0.148)
		(layer "In4.Cu")
		(net 259)
	)
	(segment
		(start 156.885052 155.357518)
		(end 156.319983 154.79245)
		(width 0.148)
		(layer "In4.Cu")
		(net 259)
	)
	(segment
		(start 162.900002 147.277498)
		(end 161.375501 148.801999)
		(width 0.148)
		(layer "In4.Cu")
		(net 259)
	)
	(segment
		(start 154.056618 158.185953)
		(end 154.056616 158.185954)
		(width 0.148)
		(layer "In4.Cu")
		(net 259)
	)
	(segment
		(start 158.087756 153.024676)
		(end 158.652824 153.589745)
		(width 0.148)
		(layer "In4.Cu")
		(net 259)
	)
	(segment
		(start 152.890198 158.787305)
		(end 151.709729 159.967772)
		(width 0.148)
		(layer "In4.Cu")
		(net 259)
	)
	(segment
		(start 157.238607 155.357516)
		(end 157.238606 155.357517)
		(width 0.148)
		(layer "In4.Cu")
		(net 259)
	)
	(segment
		(start 155.966429 155.146002)
		(end 155.966429 155.146003)
		(width 0.148)
		(layer "In4.Cu")
		(net 259)
	)
	(segment
		(start 158.087757 152.671122)
		(end 158.087756 152.671123)
		(width 0.148)
		(layer "In4.Cu")
		(net 259)
	)
	(segment
		(start 155.259321 155.499558)
		(end 155.25932 155.499559)
		(width 0.148)
		(layer "In4.Cu")
		(net 259)
	)
	(segment
		(start 159.501974 151.610458)
		(end 160.067042 152.175527)
		(width 0.148)
		(layer "In4.Cu")
		(net 259)
	)
	(segment
		(start 153.137993 157.974438)
		(end 153.137993 157.974439)
		(width 0.148)
		(layer "In4.Cu")
		(net 259)
	)
	(segment
		(start 157.380647 153.731784)
		(end 157.380647 153.731785)
		(width 0.148)
		(layer "In4.Cu")
		(net 259)
	)
	(segment
		(start 150.670501 162.306)
		(end 150.380501 162.596)
		(width 0.148)
		(layer "In4.Cu")
		(net 259)
	)
	(segment
		(start 157.592161 154.650409)
		(end 157.027092 154.085341)
		(width 0.148)
		(layer "In4.Cu")
		(net 259)
	)
	(segment
		(start 161.481258 151.114865)
		(end 161.481258 151.114866)
		(width 0.148)
		(layer "In4.Cu")
		(net 259)
	)
	(segment
		(start 153.845102 157.26733)
		(end 154.41017 157.832399)
		(width 0.148)
		(layer "In4.Cu")
		(net 259)
	)
	(segment
		(start 160.774152 151.821971)
		(end 160.774151 151.821972)
		(width 0.148)
		(layer "In4.Cu")
		(net 259)
	)
	(arc
		(start 155.966429 154.79245)
		(mid 155.893206 154.969226)
		(end 155.966429 155.146002)
		(width 0.148)
		(layer "In4.Cu")
		(net 259)
	)
	(arc
		(start 160.774151 151.468418)
		(mid 160.847375 151.645194)
		(end 160.774152 151.821971)
		(width 0.148)
		(layer "In4.Cu")
		(net 259)
	)
	(arc
		(start 153.491547 157.620886)
		(mid 153.314771 157.547662)
		(end 153.137994 157.620885)
		(width 0.148)
		(layer "In4.Cu")
		(net 259)
	)
	(arc
		(start 155.824388 156.418181)
		(mid 155.897612 156.594957)
		(end 155.824389 156.771734)
		(width 0.148)
		(layer "In4.Cu")
		(net 259)
	)
	(arc
		(start 158.44131 152.671123)
		(mid 158.264534 152.597899)
		(end 158.087757 152.671122)
		(width 0.148)
		(layer "In4.Cu")
		(net 259)
	)
	(arc
		(start 155.824388 156.771735)
		(mid 155.647611 156.844959)
		(end 155.470836 156.771735)
		(width 0.148)
		(layer "In4.Cu")
		(net 259)
	)
	(arc
		(start 159.501974 151.256905)
		(mid 159.428751 151.433681)
		(end 159.501974 151.610457)
		(width 0.148)
		(layer "In4.Cu")
		(net 259)
	)
	(arc
		(start 161.481258 151.114866)
		(mid 161.304483 151.188088)
		(end 161.127706 151.114866)
		(width 0.148)
		(layer "In4.Cu")
		(net 259)
	)
	(arc
		(start 159.855528 151.256905)
		(mid 159.678752 151.183681)
		(end 159.501975 151.256904)
		(width 0.148)
		(layer "In4.Cu")
		(net 259)
	)
	(arc
		(start 155.612874 155.499559)
		(mid 155.436098 155.426335)
		(end 155.259321 155.499558)
		(width 0.148)
		(layer "In4.Cu")
		(net 259)
	)
	(arc
		(start 161.481259 150.761312)
		(mid 161.554482 150.938089)
		(end 161.481258 151.114865)
		(width 0.148)
		(layer "In4.Cu")
		(net 259)
	)
	(arc
		(start 158.087756 152.671123)
		(mid 158.014533 152.847899)
		(end 158.087756 153.024675)
		(width 0.148)
		(layer "In4.Cu")
		(net 259)
	)
	(arc
		(start 159.359933 152.882636)
		(mid 159.433157 153.059412)
		(end 159.359934 153.236189)
		(width 0.148)
		(layer "In4.Cu")
		(net 259)
	)
	(arc
		(start 157.380647 153.378232)
		(mid 157.307424 153.555008)
		(end 157.380647 153.731784)
		(width 0.148)
		(layer "In4.Cu")
		(net 259)
	)
	(arc
		(start 161.375501 150.302)
		(mid 161.302278 150.478777)
		(end 161.375501 150.655554)
		(width 0.148)
		(layer "In4.Cu")
		(net 259)
	)
	(arc
		(start 158.794865 151.964014)
		(mid 158.721642 152.14079)
		(end 158.794865 152.317566)
		(width 0.148)
		(layer "In4.Cu")
		(net 259)
	)
	(arc
		(start 158.652824 153.589745)
		(mid 158.726048 153.766521)
		(end 158.652825 153.943298)
		(width 0.148)
		(layer "In4.Cu")
		(net 259)
	)
	(arc
		(start 156.319983 154.79245)
		(mid 156.143207 154.719226)
		(end 155.96643 154.792449)
		(width 0.148)
		(layer "In4.Cu")
		(net 259)
	)
	(arc
		(start 160.774151 151.821972)
		(mid 160.597374 151.895196)
		(end 160.420599 151.821972)
		(width 0.148)
		(layer "In4.Cu")
		(net 259)
	)
	(arc
		(start 159.148419 151.964014)
		(mid 158.971643 151.89079)
		(end 158.794866 151.964013)
		(width 0.148)
		(layer "In4.Cu")
		(net 259)
	)
	(arc
		(start 154.198656 156.913777)
		(mid 154.02188 156.840553)
		(end 153.845103 156.913776)
		(width 0.148)
		(layer "In4.Cu")
		(net 259)
	)
	(arc
		(start 156.531497 155.711072)
		(mid 156.604721 155.887848)
		(end 156.531498 156.064625)
		(width 0.148)
		(layer "In4.Cu")
		(net 259)
	)
	(arc
		(start 154.905765 156.206668)
		(mid 154.728989 156.133444)
		(end 154.552212 156.206667)
		(width 0.148)
		(layer "In4.Cu")
		(net 259)
	)
	(arc
		(start 156.531497 156.064626)
		(mid 156.35472 156.13785)
		(end 156.177945 156.064626)
		(width 0.148)
		(layer "In4.Cu")
		(net 259)
	)
	(arc
		(start 153.137993 157.620886)
		(mid 153.06477 157.797662)
		(end 153.137993 157.974438)
		(width 0.148)
		(layer "In4.Cu")
		(net 259)
	)
	(arc
		(start 153.703061 158.539508)
		(mid 153.776285 158.716284)
		(end 153.703062 158.893061)
		(width 0.148)
		(layer "In4.Cu")
		(net 259)
	)
	(arc
		(start 157.238606 155.003963)
		(mid 157.31183 155.180739)
		(end 157.238607 155.357516)
		(width 0.148)
		(layer "In4.Cu")
		(net 259)
	)
	(arc
		(start 153.703061 158.893062)
		(mid 153.526284 158.966286)
		(end 153.349509 158.893062)
		(width 0.148)
		(layer "In4.Cu")
		(net 259)
	)
	(arc
		(start 157.027092 154.085341)
		(mid 156.850316 154.012117)
		(end 156.673539 154.08534)
		(width 0.148)
		(layer "In4.Cu")
		(net 259)
	)
	(arc
		(start 157.238606 155.357517)
		(mid 157.061829 155.430741)
		(end 156.885054 155.357517)
		(width 0.148)
		(layer "In4.Cu")
		(net 259)
	)
	(arc
		(start 154.41017 157.832399)
		(mid 154.483394 158.009175)
		(end 154.410171 158.185952)
		(width 0.148)
		(layer "In4.Cu")
		(net 259)
	)
	(arc
		(start 159.359933 153.23619)
		(mid 159.183156 153.309414)
		(end 159.006381 153.23619)
		(width 0.148)
		(layer "In4.Cu")
		(net 259)
	)
	(arc
		(start 153.845102 156.913777)
		(mid 153.771879 157.090553)
		(end 153.845102 157.267329)
		(width 0.148)
		(layer "In4.Cu")
		(net 259)
	)
	(arc
		(start 160.562637 150.549796)
		(mid 160.385861 150.476572)
		(end 160.209084 150.549795)
		(width 0.148)
		(layer "In4.Cu")
		(net 259)
	)
	(arc
		(start 156.673538 154.085341)
		(mid 156.600315 154.262117)
		(end 156.673538 154.438893)
		(width 0.148)
		(layer "In4.Cu")
		(net 259)
	)
	(arc
		(start 160.067042 152.175527)
		(mid 160.140266 152.352303)
		(end 160.067043 152.52908)
		(width 0.148)
		(layer "In4.Cu")
		(net 259)
	)
	(arc
		(start 155.117279 157.478844)
		(mid 154.940502 157.552068)
		(end 154.763727 157.478844)
		(width 0.148)
		(layer "In4.Cu")
		(net 259)
	)
	(arc
		(start 158.652824 153.943299)
		(mid 158.476047 154.016523)
		(end 158.299272 153.943299)
		(width 0.148)
		(layer "In4.Cu")
		(net 259)
	)
	(arc
		(start 153.24375 158.787306)
		(mid 153.066973 158.714083)
		(end 152.890197 158.787307)
		(width 0.148)
		(layer "In4.Cu")
		(net 259)
	)
	(arc
		(start 155.25932 155.499559)
		(mid 155.186097 155.676335)
		(end 155.25932 155.853111)
		(width 0.148)
		(layer "In4.Cu")
		(net 259)
	)
	(arc
		(start 154.552211 156.206668)
		(mid 154.478988 156.383444)
		(end 154.552211 156.56022)
		(width 0.148)
		(layer "In4.Cu")
		(net 259)
	)
	(arc
		(start 154.41017 158.185953)
		(mid 154.233393 158.259177)
		(end 154.056618 158.185953)
		(width 0.148)
		(layer "In4.Cu")
		(net 259)
	)
	(arc
		(start 157.945715 154.650408)
		(mid 157.768938 154.723632)
		(end 157.592163 154.650408)
		(width 0.148)
		(layer "In4.Cu")
		(net 259)
	)
	(arc
		(start 155.117279 157.12529)
		(mid 155.190503 157.302066)
		(end 155.11728 157.478843)
		(width 0.148)
		(layer "In4.Cu")
		(net 259)
	)
	(arc
		(start 157.734201 153.378232)
		(mid 157.557425 153.305008)
		(end 157.380648 153.378231)
		(width 0.148)
		(layer "In4.Cu")
		(net 259)
	)
	(arc
		(start 160.209083 150.549796)
		(mid 160.13586 150.726572)
		(end 160.209083 150.903348)
		(width 0.148)
		(layer "In4.Cu")
		(net 259)
	)
	(arc
		(start 157.945715 154.296854)
		(mid 158.018939 154.47363)
		(end 157.945716 154.650407)
		(width 0.148)
		(layer "In4.Cu")
		(net 259)
	)
	(arc
		(start 160.067042 152.529081)
		(mid 159.890265 152.602305)
		(end 159.71349 152.529081)
		(width 0.148)
		(layer "In4.Cu")
		(net 259)
	)
	(segment
		(start 163.150003 138.8025)
		(end 163.150003 139.877498)
		(width 0.201)
		(layer "F.Cu")
		(net 260)
	)
	(segment
		(start 150.375501 167.302)
		(end 150.875001 166.802501)
		(width 0.256)
		(layer "F.Cu")
		(net 260)
	)
	(via
		(at 150.875001 166.802501)
		(size 0.45)
		(drill 0.1)
		(layers "F.Cu" "B.Cu")
		(net 260)
	)
	(via
		(at 163.150003 139.877498)
		(size 0.45)
		(drill 0.1)
		(layers "F.Cu" "B.Cu")
		(net 260)
	)
	(segment
		(start 154.247999 155.591748)
		(end 153.835753 155.179502)
		(width 0.148)
		(layer "In4.Cu")
		(net 260)
	)
	(segment
		(start 150.110501 162.266)
		(end 149.680501 162.266)
		(width 0.148)
		(layer "In4.Cu")
		(net 260)
	)
	(segment
		(start 154.896412 154.118842)
		(end 154.896412 154.118843)
		(width 0.148)
		(layer "In4.Cu")
		(net 260)
	)
	(segment
		(start 158.431942 150.583312)
		(end 158.431942 150.583313)
		(width 0.148)
		(layer "In4.Cu")
		(net 260)
	)
	(segment
		(start 152.775094 156.24016)
		(end 152.775094 156.240161)
		(width 0.148)
		(layer "In4.Cu")
		(net 260)
	)
	(segment
		(start 159.139047 149.876207)
		(end 159.551294 150.288453)
		(width 0.148)
		(layer "In4.Cu")
		(net 260)
	)
	(segment
		(start 154.189305 154.472396)
		(end 154.189306 154.472396)
		(width 0.148)
		(layer "In4.Cu")
		(net 260)
	)
	(segment
		(start 154.896411 153.76529)
		(end 154.896412 153.76529)
		(width 0.148)
		(layer "In4.Cu")
		(net 260)
	)
	(segment
		(start 159.521947 149.552)
		(end 159.492601 149.522654)
		(width 0.148)
		(layer "In4.Cu")
		(net 260)
	)
	(segment
		(start 160.375501 149.052)
		(end 159.875501 149.552)
		(width 0.148)
		(layer "In4.Cu")
		(net 260)
	)
	(segment
		(start 152.775094 156.240161)
		(end 153.18734 156.652407)
		(width 0.148)
		(layer "In4.Cu")
		(net 260)
	)
	(segment
		(start 155.308658 154.884643)
		(end 155.308657 154.884643)
		(width 0.148)
		(layer "In4.Cu")
		(net 260)
	)
	(segment
		(start 152.450888 156.976615)
		(end 150.390501 159.037)
		(width 0.148)
		(layer "In4.Cu")
		(net 260)
	)
	(segment
		(start 157.724836 151.290418)
		(end 157.724836 151.290419)
		(width 0.148)
		(layer "In4.Cu")
		(net 260)
	)
	(segment
		(start 160.375501 147.019864)
		(end 160.375501 149.052)
		(width 0.148)
		(layer "In4.Cu")
		(net 260)
	)
	(segment
		(start 155.603518 153.411737)
		(end 156.015764 153.823983)
		(width 0.148)
		(layer "In4.Cu")
		(net 260)
	)
	(segment
		(start 154.601552 155.591749)
		(end 154.601551 155.591749)
		(width 0.148)
		(layer "In4.Cu")
		(net 260)
	)
	(segment
		(start 155.662211 154.177537)
		(end 155.662211 154.177536)
		(width 0.148)
		(layer "In4.Cu")
		(net 260)
	)
	(segment
		(start 158.431941 150.22976)
		(end 158.431942 150.22976)
		(width 0.148)
		(layer "In4.Cu")
		(net 260)
	)
	(segment
		(start 156.310624 152.704631)
		(end 156.72287 153.116877)
		(width 0.148)
		(layer "In4.Cu")
		(net 260)
	)
	(segment
		(start 154.955105 154.884642)
		(end 154.542859 154.472396)
		(width 0.148)
		(layer "In4.Cu")
		(net 260)
	)
	(segment
		(start 149.380501 165.116)
		(end 149.640501 165.376)
		(width 0.148)
		(layer "In4.Cu")
		(net 260)
	)
	(segment
		(start 154.896412 154.118843)
		(end 155.308658 154.531089)
		(width 0.148)
		(layer "In4.Cu")
		(net 260)
	)
	(segment
		(start 157.429976 152.763325)
		(end 157.429975 152.763325)
		(width 0.148)
		(layer "In4.Cu")
		(net 260)
	)
	(segment
		(start 156.369317 153.47043)
		(end 155.957071 153.058184)
		(width 0.148)
		(layer "In4.Cu")
		(net 260)
	)
	(segment
		(start 153.540893 156.298855)
		(end 153.540893 156.298854)
		(width 0.148)
		(layer "In4.Cu")
		(net 260)
	)
	(segment
		(start 152.833787 157.005961)
		(end 152.833787 157.00596)
		(width 0.148)
		(layer "In4.Cu")
		(net 260)
	)
	(segment
		(start 157.01773 151.997525)
		(end 157.429976 152.409771)
		(width 0.148)
		(layer "In4.Cu")
		(net 260)
	)
	(segment
		(start 153.482199 155.179502)
		(end 153.4822 155.179502)
		(width 0.148)
		(layer "In4.Cu")
		(net 260)
	)
	(segment
		(start 150.390501 161.986)
		(end 150.110501 162.266)
		(width 0.148)
		(layer "In4.Cu")
		(net 260)
	)
	(segment
		(start 156.015764 154.177537)
		(end 156.015763 154.177537)
		(width 0.148)
		(layer "In4.Cu")
		(net 260)
	)
	(segment
		(start 155.603517 153.058184)
		(end 155.603518 153.058184)
		(width 0.148)
		(layer "In4.Cu")
		(net 260)
	)
	(segment
		(start 153.540893 156.298854)
		(end 153.128647 155.886608)
		(width 0.148)
		(layer "In4.Cu")
		(net 260)
	)
	(segment
		(start 157.076423 152.763324)
		(end 156.664177 152.351078)
		(width 0.148)
		(layer "In4.Cu")
		(net 260)
	)
	(segment
		(start 163.150003 139.877498)
		(end 161.875501 141.152)
		(width 0.148)
		(layer "In4.Cu")
		(net 260)
	)
	(segment
		(start 156.310623 152.351078)
		(end 156.310624 152.351078)
		(width 0.148)
		(layer "In4.Cu")
		(net 260)
	)
	(segment
		(start 158.490635 151.349112)
		(end 158.078389 150.936866)
		(width 0.148)
		(layer "In4.Cu")
		(net 260)
	)
	(segment
		(start 154.247999 155.591749)
		(end 154.247999 155.591748)
		(width 0.148)
		(layer "In4.Cu")
		(net 260)
	)
	(segment
		(start 161.875501 141.152)
		(end 161.875501 145.519864)
		(width 0.148)
		(layer "In4.Cu")
		(net 260)
	)
	(segment
		(start 155.662211 154.177536)
		(end 155.249965 153.76529)
		(width 0.148)
		(layer "In4.Cu")
		(net 260)
	)
	(segment
		(start 153.4822 155.533055)
		(end 153.894446 155.945301)
		(width 0.148)
		(layer "In4.Cu")
		(net 260)
	)
	(segment
		(start 158.844188 151.349113)
		(end 158.844187 151.349113)
		(width 0.148)
		(layer "In4.Cu")
		(net 260)
	)
	(segment
		(start 149.640501 165.376)
		(end 150.110501 165.376)
		(width 0.148)
		(layer "In4.Cu")
		(net 260)
	)
	(segment
		(start 159.197741 150.642006)
		(end 158.785495 150.22976)
		(width 0.148)
		(layer "In4.Cu")
		(net 260)
	)
	(segment
		(start 153.894446 156.298855)
		(end 153.894445 156.298855)
		(width 0.148)
		(layer "In4.Cu")
		(net 260)
	)
	(segment
		(start 149.680501 162.266)
		(end 149.380501 162.566)
		(width 0.148)
		(layer "In4.Cu")
		(net 260)
	)
	(segment
		(start 157.01773 151.997524)
		(end 157.01773 151.997525)
		(width 0.148)
		(layer "In4.Cu")
		(net 260)
	)
	(segment
		(start 161.875501 145.519864)
		(end 160.375501 147.019864)
		(width 0.148)
		(layer "In4.Cu")
		(net 260)
	)
	(segment
		(start 153.4822 155.533054)
		(end 153.4822 155.533055)
		(width 0.148)
		(layer "In4.Cu")
		(net 260)
	)
	(segment
		(start 152.775093 155.886608)
		(end 152.775094 155.886608)
		(width 0.148)
		(layer "In4.Cu")
		(net 260)
	)
	(segment
		(start 156.72287 153.470431)
		(end 156.722869 153.470431)
		(width 0.148)
		(layer "In4.Cu")
		(net 260)
	)
	(segment
		(start 150.330501 165.596)
		(end 150.330501 166.258001)
		(width 0.148)
		(layer "In4.Cu")
		(net 260)
	)
	(segment
		(start 155.603518 153.411736)
		(end 155.603518 153.411737)
		(width 0.148)
		(layer "In4.Cu")
		(net 260)
	)
	(segment
		(start 158.137082 152.056219)
		(end 158.137081 152.056219)
		(width 0.148)
		(layer "In4.Cu")
		(net 260)
	)
	(segment
		(start 156.310624 152.70463)
		(end 156.310624 152.704631)
		(width 0.148)
		(layer "In4.Cu")
		(net 260)
	)
	(segment
		(start 154.955105 154.884643)
		(end 154.955105 154.884642)
		(width 0.148)
		(layer "In4.Cu")
		(net 260)
	)
	(segment
		(start 154.189306 154.825948)
		(end 154.189306 154.825949)
		(width 0.148)
		(layer "In4.Cu")
		(net 260)
	)
	(segment
		(start 159.197741 150.642007)
		(end 159.197741 150.642006)
		(width 0.148)
		(layer "In4.Cu")
		(net 260)
	)
	(segment
		(start 157.076423 152.763325)
		(end 157.076423 152.763324)
		(width 0.148)
		(layer "In4.Cu")
		(net 260)
	)
	(segment
		(start 157.724836 151.290419)
		(end 158.137082 151.702665)
		(width 0.148)
		(layer "In4.Cu")
		(net 260)
	)
	(segment
		(start 159.139047 149.876206)
		(end 159.139047 149.876207)
		(width 0.148)
		(layer "In4.Cu")
		(net 260)
	)
	(segment
		(start 157.783529 152.056218)
		(end 157.371283 151.643972)
		(width 0.148)
		(layer "In4.Cu")
		(net 260)
	)
	(segment
		(start 156.369317 153.470431)
		(end 156.369317 153.47043)
		(width 0.148)
		(layer "In4.Cu")
		(net 260)
	)
	(segment
		(start 157.017729 151.643972)
		(end 157.01773 151.643972)
		(width 0.148)
		(layer "In4.Cu")
		(net 260)
	)
	(segment
		(start 153.18734 157.005961)
		(end 153.187339 157.005961)
		(width 0.148)
		(layer "In4.Cu")
		(net 260)
	)
	(segment
		(start 159.551294 150.642007)
		(end 159.551293 150.642007)
		(width 0.148)
		(layer "In4.Cu")
		(net 260)
	)
	(segment
		(start 157.724835 150.936866)
		(end 157.724836 150.936866)
		(width 0.148)
		(layer "In4.Cu")
		(net 260)
	)
	(segment
		(start 150.390501 159.037)
		(end 150.390501 161.986)
		(width 0.148)
		(layer "In4.Cu")
		(net 260)
	)
	(segment
		(start 158.490635 151.349113)
		(end 158.490635 151.349112)
		(width 0.148)
		(layer "In4.Cu")
		(net 260)
	)
	(segment
		(start 149.380501 162.566)
		(end 149.380501 165.116)
		(width 0.148)
		(layer "In4.Cu")
		(net 260)
	)
	(segment
		(start 157.783529 152.056219)
		(end 157.783529 152.056218)
		(width 0.148)
		(layer "In4.Cu")
		(net 260)
	)
	(segment
		(start 154.189306 154.825949)
		(end 154.601552 155.238195)
		(width 0.148)
		(layer "In4.Cu")
		(net 260)
	)
	(segment
		(start 150.330501 166.258001)
		(end 150.875001 166.802501)
		(width 0.148)
		(layer "In4.Cu")
		(net 260)
	)
	(segment
		(start 152.833787 157.00596)
		(end 152.804442 156.976615)
		(width 0.148)
		(layer "In4.Cu")
		(net 260)
	)
	(segment
		(start 150.110501 165.376)
		(end 150.330501 165.596)
		(width 0.148)
		(layer "In4.Cu")
		(net 260)
	)
	(segment
		(start 158.431942 150.583313)
		(end 158.844188 150.995559)
		(width 0.148)
		(layer "In4.Cu")
		(net 260)
	)
	(arc
		(start 158.078389 150.936866)
		(mid 157.901612 150.863643)
		(end 157.724835 150.936866)
		(width 0.148)
		(layer "In4.Cu")
		(net 260)
	)
	(arc
		(start 155.249965 153.76529)
		(mid 155.073188 153.692067)
		(end 154.896411 153.76529)
		(width 0.148)
		(layer "In4.Cu")
		(net 260)
	)
	(arc
		(start 154.601551 155.591749)
		(mid 154.424776 155.664971)
		(end 154.247999 155.591749)
		(width 0.148)
		(layer "In4.Cu")
		(net 260)
	)
	(arc
		(start 158.431942 150.22976)
		(mid 158.358719 150.406536)
		(end 158.431942 150.583312)
		(width 0.148)
		(layer "In4.Cu")
		(net 260)
	)
	(arc
		(start 156.015763 154.177537)
		(mid 155.838988 154.250759)
		(end 155.662211 154.177537)
		(width 0.148)
		(layer "In4.Cu")
		(net 260)
	)
	(arc
		(start 157.724836 150.936866)
		(mid 157.651613 151.113642)
		(end 157.724836 151.290418)
		(width 0.148)
		(layer "In4.Cu")
		(net 260)
	)
	(arc
		(start 159.492601 149.522654)
		(mid 159.315824 149.449431)
		(end 159.139047 149.522654)
		(width 0.148)
		(layer "In4.Cu")
		(net 260)
	)
	(arc
		(start 154.542859 154.472396)
		(mid 154.366082 154.399173)
		(end 154.189305 154.472396)
		(width 0.148)
		(layer "In4.Cu")
		(net 260)
	)
	(arc
		(start 153.128647 155.886608)
		(mid 152.95187 155.813385)
		(end 152.775093 155.886608)
		(width 0.148)
		(layer "In4.Cu")
		(net 260)
	)
	(arc
		(start 155.308657 154.884643)
		(mid 155.131882 154.957865)
		(end 154.955105 154.884643)
		(width 0.148)
		(layer "In4.Cu")
		(net 260)
	)
	(arc
		(start 153.187339 157.005961)
		(mid 153.010564 157.079183)
		(end 152.833787 157.005961)
		(width 0.148)
		(layer "In4.Cu")
		(net 260)
	)
	(arc
		(start 158.137081 152.056219)
		(mid 157.960306 152.129441)
		(end 157.783529 152.056219)
		(width 0.148)
		(layer "In4.Cu")
		(net 260)
	)
	(arc
		(start 158.137082 151.702665)
		(mid 158.210305 151.879442)
		(end 158.137082 152.056219)
		(width 0.148)
		(layer "In4.Cu")
		(net 260)
	)
	(arc
		(start 157.429975 152.763325)
		(mid 157.2532 152.836547)
		(end 157.076423 152.763325)
		(width 0.148)
		(layer "In4.Cu")
		(net 260)
	)
	(arc
		(start 158.844188 150.995559)
		(mid 158.917411 151.172336)
		(end 158.844188 151.349113)
		(width 0.148)
		(layer "In4.Cu")
		(net 260)
	)
	(arc
		(start 157.429976 152.409771)
		(mid 157.503199 152.586548)
		(end 157.429976 152.763325)
		(width 0.148)
		(layer "In4.Cu")
		(net 260)
	)
	(arc
		(start 154.601552 155.238195)
		(mid 154.674775 155.414972)
		(end 154.601552 155.591749)
		(width 0.148)
		(layer "In4.Cu")
		(net 260)
	)
	(arc
		(start 156.664177 152.351078)
		(mid 156.4874 152.277855)
		(end 156.310623 152.351078)
		(width 0.148)
		(layer "In4.Cu")
		(net 260)
	)
	(arc
		(start 159.551294 150.288453)
		(mid 159.624517 150.46523)
		(end 159.551294 150.642007)
		(width 0.148)
		(layer "In4.Cu")
		(net 260)
	)
	(arc
		(start 157.371283 151.643972)
		(mid 157.194506 151.570749)
		(end 157.017729 151.643972)
		(width 0.148)
		(layer "In4.Cu")
		(net 260)
	)
	(arc
		(start 156.310624 152.351078)
		(mid 156.237401 152.527854)
		(end 156.310624 152.70463)
		(width 0.148)
		(layer "In4.Cu")
		(net 260)
	)
	(arc
		(start 156.722869 153.470431)
		(mid 156.546094 153.543653)
		(end 156.369317 153.470431)
		(width 0.148)
		(layer "In4.Cu")
		(net 260)
	)
	(arc
		(start 158.785495 150.22976)
		(mid 158.608718 150.156537)
		(end 158.431941 150.22976)
		(width 0.148)
		(layer "In4.Cu")
		(net 260)
	)
	(arc
		(start 153.835753 155.179502)
		(mid 153.658976 155.106279)
		(end 153.482199 155.179502)
		(width 0.148)
		(layer "In4.Cu")
		(net 260)
	)
	(arc
		(start 153.18734 156.652407)
		(mid 153.260563 156.829184)
		(end 153.18734 157.005961)
		(width 0.148)
		(layer "In4.Cu")
		(net 260)
	)
	(arc
		(start 152.775094 155.886608)
		(mid 152.701871 156.063384)
		(end 152.775094 156.24016)
		(width 0.148)
		(layer "In4.Cu")
		(net 260)
	)
	(arc
		(start 155.957071 153.058184)
		(mid 155.780294 152.984961)
		(end 155.603517 153.058184)
		(width 0.148)
		(layer "In4.Cu")
		(net 260)
	)
	(arc
		(start 155.308658 154.531089)
		(mid 155.381881 154.707866)
		(end 155.308658 154.884643)
		(width 0.148)
		(layer "In4.Cu")
		(net 260)
	)
	(arc
		(start 153.894446 155.945301)
		(mid 153.967669 156.122078)
		(end 153.894446 156.298855)
		(width 0.148)
		(layer "In4.Cu")
		(net 260)
	)
	(arc
		(start 154.189306 154.472396)
		(mid 154.116083 154.649172)
		(end 154.189306 154.825948)
		(width 0.148)
		(layer "In4.Cu")
		(net 260)
	)
	(arc
		(start 154.896412 153.76529)
		(mid 154.823189 153.942066)
		(end 154.896412 154.118842)
		(width 0.148)
		(layer "In4.Cu")
		(net 260)
	)
	(arc
		(start 159.875501 149.552)
		(mid 159.698724 149.625223)
		(end 159.521947 149.552)
		(width 0.148)
		(layer "In4.Cu")
		(net 260)
	)
	(arc
		(start 153.4822 155.179502)
		(mid 153.408977 155.356278)
		(end 153.4822 155.533054)
		(width 0.148)
		(layer "In4.Cu")
		(net 260)
	)
	(arc
		(start 159.139047 149.522654)
		(mid 159.065824 149.69943)
		(end 159.139047 149.876206)
		(width 0.148)
		(layer "In4.Cu")
		(net 260)
	)
	(arc
		(start 156.72287 153.116877)
		(mid 156.796093 153.293654)
		(end 156.72287 153.470431)
		(width 0.148)
		(layer "In4.Cu")
		(net 260)
	)
	(arc
		(start 157.01773 151.643972)
		(mid 156.944507 151.820748)
		(end 157.01773 151.997524)
		(width 0.148)
		(layer "In4.Cu")
		(net 260)
	)
	(arc
		(start 156.015764 153.823983)
		(mid 156.088987 154.00076)
		(end 156.015764 154.177537)
		(width 0.148)
		(layer "In4.Cu")
		(net 260)
	)
	(arc
		(start 152.804442 156.976615)
		(mid 152.627665 156.903392)
		(end 152.450888 156.976615)
		(width 0.148)
		(layer "In4.Cu")
		(net 260)
	)
	(arc
		(start 159.551293 150.642007)
		(mid 159.374518 150.715229)
		(end 159.197741 150.642007)
		(width 0.148)
		(layer "In4.Cu")
		(net 260)
	)
	(arc
		(start 158.844187 151.349113)
		(mid 158.667412 151.422335)
		(end 158.490635 151.349113)
		(width 0.148)
		(layer "In4.Cu")
		(net 260)
	)
	(arc
		(start 155.603518 153.058184)
		(mid 155.530295 153.23496)
		(end 155.603518 153.411736)
		(width 0.148)
		(layer "In4.Cu")
		(net 260)
	)
	(arc
		(start 153.894445 156.298855)
		(mid 153.71767 156.372077)
		(end 153.540893 156.298855)
		(width 0.148)
		(layer "In4.Cu")
		(net 260)
	)
	(segment
		(start 163.9 146.2025)
		(end 163.900001 147.277499)
		(width 0.201)
		(layer "F.Cu")
		(net 261)
	)
	(segment
		(start 149.375501 168.302)
		(end 149.875001 167.8025)
		(width 0.256)
		(layer "F.Cu")
		(net 261)
	)
	(via
		(at 163.900001 147.277499)
		(size 0.45)
		(drill 0.1)
		(layers "F.Cu" "B.Cu")
		(net 261)
	)
	(via
		(at 149.875001 167.8025)
		(size 0.45)
		(drill 0.1)
		(layers "F.Cu" "B.Cu")
		(net 261)
	)
	(segment
		(start 160.827405 155.100096)
		(end 160.58401 154.856701)
		(width 0.148)
		(layer "In4.Cu")
		(net 261)
	)
	(segment
		(start 156.694926 158.745784)
		(end 157.181717 159.232574)
		(width 0.148)
		(layer "In4.Cu")
		(net 261)
	)
	(segment
		(start 159.656589 156.757704)
		(end 159.656587 156.757705)
		(width 0.148)
		(layer "In4.Cu")
		(net 261)
	)
	(segment
		(start 159.52335 155.917359)
		(end 159.52335 155.91736)
		(width 0.148)
		(layer "In4.Cu")
		(net 261)
	)
	(segment
		(start 153.999739 162.414553)
		(end 153.933122 162.347936)
		(width 0.148)
		(layer "In4.Cu")
		(net 261)
	)
	(segment
		(start 156.584769 159.342735)
		(end 156.584769 159.342732)
		(width 0.148)
		(layer "In4.Cu")
		(net 261)
	)
	(segment
		(start 159.413193 156.514311)
		(end 159.413193 156.514308)
		(width 0.148)
		(layer "In4.Cu")
		(net 261)
	)
	(segment
		(start 155.170557 160.756947)
		(end 155.170557 160.756944)
		(width 0.148)
		(layer "In4.Cu")
		(net 261)
	)
	(segment
		(start 154.463451 161.46405)
		(end 154.220056 161.220655)
		(width 0.148)
		(layer "In4.Cu")
		(net 261)
	)
	(segment
		(start 158.242377 158.171916)
		(end 158.242375 158.171917)
		(width 0.148)
		(layer "In4.Cu")
		(net 261)
	)
	(segment
		(start 158.816244 156.624465)
		(end 158.816244 156.624466)
		(width 0.148)
		(layer "In4.Cu")
		(net 261)
	)
	(segment
		(start 151.630501 164.286)
		(end 151.360501 164.556)
		(width 0.148)
		(layer "In4.Cu")
		(net 261)
	)
	(segment
		(start 154.573608 160.867102)
		(end 155.060399 161.353892)
		(width 0.148)
		(layer "In4.Cu")
		(net 261)
	)
	(segment
		(start 154.706845 161.707447)
		(end 154.463451 161.464053)
		(width 0.148)
		(layer "In4.Cu")
		(net 261)
	)
	(segment
		(start 160.937562 154.503147)
		(end 160.937562 154.503148)
		(width 0.148)
		(layer "In4.Cu")
		(net 261)
	)
	(segment
		(start 160.827405 155.100099)
		(end 160.827405 155.100096)
		(width 0.148)
		(layer "In4.Cu")
		(net 261)
	)
	(segment
		(start 153.866502 161.574208)
		(end 154.353293 162.060998)
		(width 0.148)
		(layer "In4.Cu")
		(net 261)
	)
	(segment
		(start 160.937562 154.503148)
		(end 161.424353 154.989938)
		(width 0.148)
		(layer "In4.Cu")
		(net 261)
	)
	(segment
		(start 161.777905 154.636387)
		(end 161.534511 154.392993)
		(width 0.148)
		(layer "In4.Cu")
		(net 261)
	)
	(segment
		(start 151.360501 164.556)
		(end 151.360501 166.976)
		(width 0.148)
		(layer "In4.Cu")
		(net 261)
	)
	(segment
		(start 158.949483 157.46481)
		(end 158.949481 157.464811)
		(width 0.148)
		(layer "In4.Cu")
		(net 261)
	)
	(segment
		(start 160.120299 155.807205)
		(end 160.120299 155.807202)
		(width 0.148)
		(layer "In4.Cu")
		(net 261)
	)
	(segment
		(start 153.999741 162.414552)
		(end 153.999739 162.414553)
		(width 0.148)
		(layer "In4.Cu")
		(net 261)
	)
	(segment
		(start 163.375501 148.802)
		(end 163.375501 152.552)
		(width 0.148)
		(layer "In4.Cu")
		(net 261)
	)
	(segment
		(start 156.828165 159.586128)
		(end 156.828163 159.586129)
		(width 0.148)
		(layer "In4.Cu")
		(net 261)
	)
	(segment
		(start 158.706087 157.221414)
		(end 158.462692 156.978019)
		(width 0.148)
		(layer "In4.Cu")
		(net 261)
	)
	(segment
		(start 151.080501 167.256)
		(end 150.421501 167.256)
		(width 0.148)
		(layer "In4.Cu")
		(net 261)
	)
	(segment
		(start 160.363695 156.050598)
		(end 160.363693 156.050599)
		(width 0.148)
		(layer "In4.Cu")
		(net 261)
	)
	(segment
		(start 156.694926 158.745783)
		(end 156.694926 158.745784)
		(width 0.148)
		(layer "In4.Cu")
		(net 261)
	)
	(segment
		(start 157.998981 157.928523)
		(end 157.998981 157.92852)
		(width 0.148)
		(layer "In4.Cu")
		(net 261)
	)
	(segment
		(start 158.242375 158.171917)
		(end 157.998981 157.928523)
		(width 0.148)
		(layer "In4.Cu")
		(net 261)
	)
	(segment
		(start 162.485011 153.929281)
		(end 162.241617 153.685887)
		(width 0.148)
		(layer "In4.Cu")
		(net 261)
	)
	(segment
		(start 160.120299 155.807202)
		(end 159.876904 155.563807)
		(width 0.148)
		(layer "In4.Cu")
		(net 261)
	)
	(segment
		(start 154.573608 160.867101)
		(end 154.573608 160.867102)
		(width 0.148)
		(layer "In4.Cu")
		(net 261)
	)
	(segment
		(start 161.644668 153.796041)
		(end 161.644668 153.796042)
		(width 0.148)
		(layer "In4.Cu")
		(net 261)
	)
	(segment
		(start 162.351775 153.088935)
		(end 162.838565 153.575726)
		(width 0.148)
		(layer "In4.Cu")
		(net 261)
	)
	(segment
		(start 161.070799 155.343493)
		(end 160.827405 155.100099)
		(width 0.148)
		(layer "In4.Cu")
		(net 261)
	)
	(segment
		(start 152.190501 164.286)
		(end 151.630501 164.286)
		(width 0.148)
		(layer "In4.Cu")
		(net 261)
	)
	(segment
		(start 163.900001 147.277499)
		(end 163.900001 148.2775)
		(width 0.148)
		(layer "In4.Cu")
		(net 261)
	)
	(segment
		(start 155.413951 161.000341)
		(end 155.170557 160.756947)
		(width 0.148)
		(layer "In4.Cu")
		(net 261)
	)
	(segment
		(start 155.280714 160.159995)
		(end 155.280714 160.159996)
		(width 0.148)
		(layer "In4.Cu")
		(net 261)
	)
	(segment
		(start 161.070801 155.343492)
		(end 161.070799 155.343493)
		(width 0.148)
		(layer "In4.Cu")
		(net 261)
	)
	(segment
		(start 162.351775 153.088934)
		(end 162.351775 153.088935)
		(width 0.148)
		(layer "In4.Cu")
		(net 261)
	)
	(segment
		(start 151.360501 166.976)
		(end 151.080501 167.256)
		(width 0.148)
		(layer "In4.Cu")
		(net 261)
	)
	(segment
		(start 153.579568 162.347936)
		(end 152.875501 163.052)
		(width 0.148)
		(layer "In4.Cu")
		(net 261)
	)
	(segment
		(start 157.402032 158.038677)
		(end 157.402032 158.038678)
		(width 0.148)
		(layer "In4.Cu")
		(net 261)
	)
	(segment
		(start 158.949481 157.464811)
		(end 158.706087 157.221417)
		(width 0.148)
		(layer "In4.Cu")
		(net 261)
	)
	(segment
		(start 161.777907 154.636386)
		(end 161.777905 154.636387)
		(width 0.148)
		(layer "In4.Cu")
		(net 261)
	)
	(segment
		(start 159.413193 156.514308)
		(end 159.169798 156.270913)
		(width 0.148)
		(layer "In4.Cu")
		(net 261)
	)
	(segment
		(start 160.363693 156.050599)
		(end 160.120299 155.807205)
		(width 0.148)
		(layer "In4.Cu")
		(net 261)
	)
	(segment
		(start 158.816244 156.624466)
		(end 159.303035 157.111256)
		(width 0.148)
		(layer "In4.Cu")
		(net 261)
	)
	(segment
		(start 156.121057 160.293235)
		(end 155.877663 160.049841)
		(width 0.148)
		(layer "In4.Cu")
		(net 261)
	)
	(segment
		(start 160.230456 155.210254)
		(end 160.717247 155.697044)
		(width 0.148)
		(layer "In4.Cu")
		(net 261)
	)
	(segment
		(start 158.706087 157.221417)
		(end 158.706087 157.221414)
		(width 0.148)
		(layer "In4.Cu")
		(net 261)
	)
	(segment
		(start 152.875501 163.601)
		(end 152.190501 164.286)
		(width 0.148)
		(layer "In4.Cu")
		(net 261)
	)
	(segment
		(start 156.584769 159.342732)
		(end 156.341374 159.099337)
		(width 0.148)
		(layer "In4.Cu")
		(net 261)
	)
	(segment
		(start 158.109138 157.331571)
		(end 158.109138 157.331572)
		(width 0.148)
		(layer "In4.Cu")
		(net 261)
	)
	(segment
		(start 155.170557 160.756944)
		(end 154.927162 160.513549)
		(width 0.148)
		(layer "In4.Cu")
		(net 261)
	)
	(segment
		(start 163.900001 148.2775)
		(end 163.375501 148.802)
		(width 0.148)
		(layer "In4.Cu")
		(net 261)
	)
	(segment
		(start 157.402032 158.038678)
		(end 157.888823 158.525468)
		(width 0.148)
		(layer "In4.Cu")
		(net 261)
	)
	(segment
		(start 150.421501 167.256)
		(end 149.875001 167.8025)
		(width 0.148)
		(layer "In4.Cu")
		(net 261)
	)
	(segment
		(start 155.280714 160.159996)
		(end 155.767505 160.646786)
		(width 0.148)
		(layer "In4.Cu")
		(net 261)
	)
	(segment
		(start 153.579569 162.347935)
		(end 153.579568 162.347936)
		(width 0.148)
		(layer "In4.Cu")
		(net 261)
	)
	(segment
		(start 157.291875 158.635626)
		(end 157.04848 158.392231)
		(width 0.148)
		(layer "In4.Cu")
		(net 261)
	)
	(segment
		(start 157.535271 158.879022)
		(end 157.535269 158.879023)
		(width 0.148)
		(layer "In4.Cu")
		(net 261)
	)
	(segment
		(start 162.351776 152.735381)
		(end 162.351775 152.735382)
		(width 0.148)
		(layer "In4.Cu")
		(net 261)
	)
	(segment
		(start 158.109138 157.331572)
		(end 158.595929 157.818362)
		(width 0.148)
		(layer "In4.Cu")
		(net 261)
	)
	(segment
		(start 157.291875 158.635629)
		(end 157.291875 158.635626)
		(width 0.148)
		(layer "In4.Cu")
		(net 261)
	)
	(segment
		(start 161.534511 154.39299)
		(end 161.291116 154.149595)
		(width 0.148)
		(layer "In4.Cu")
		(net 261)
	)
	(segment
		(start 162.771947 152.802)
		(end 162.705329 152.735382)
		(width 0.148)
		(layer "In4.Cu")
		(net 261)
	)
	(segment
		(start 160.230456 155.210253)
		(end 160.230456 155.210254)
		(width 0.148)
		(layer "In4.Cu")
		(net 261)
	)
	(segment
		(start 159.52335 155.91736)
		(end 160.010141 156.40415)
		(width 0.148)
		(layer "In4.Cu")
		(net 261)
	)
	(segment
		(start 157.535269 158.879023)
		(end 157.291875 158.635629)
		(width 0.148)
		(layer "In4.Cu")
		(net 261)
	)
	(segment
		(start 157.998981 157.92852)
		(end 157.755586 157.685125)
		(width 0.148)
		(layer "In4.Cu")
		(net 261)
	)
	(segment
		(start 159.656587 156.757705)
		(end 159.413193 156.514311)
		(width 0.148)
		(layer "In4.Cu")
		(net 261)
	)
	(segment
		(start 155.877663 160.049838)
		(end 155.634268 159.806443)
		(width 0.148)
		(layer "In4.Cu")
		(net 261)
	)
	(segment
		(start 156.828163 159.586129)
		(end 156.584769 159.342735)
		(width 0.148)
		(layer "In4.Cu")
		(net 261)
	)
	(segment
		(start 156.121059 160.293234)
		(end 156.121057 160.293235)
		(width 0.148)
		(layer "In4.Cu")
		(net 261)
	)
	(segment
		(start 162.485013 153.92928)
		(end 162.485011 153.929281)
		(width 0.148)
		(layer "In4.Cu")
		(net 261)
	)
	(segment
		(start 161.534511 154.392993)
		(end 161.534511 154.39299)
		(width 0.148)
		(layer "In4.Cu")
		(net 261)
	)
	(segment
		(start 155.877663 160.049841)
		(end 155.877663 160.049838)
		(width 0.148)
		(layer "In4.Cu")
		(net 261)
	)
	(segment
		(start 162.241617 153.685884)
		(end 161.998222 153.442489)
		(width 0.148)
		(layer "In4.Cu")
		(net 261)
	)
	(segment
		(start 153.866502 161.574207)
		(end 153.866502 161.574208)
		(width 0.148)
		(layer "In4.Cu")
		(net 261)
	)
	(segment
		(start 155.98782 159.45289)
		(end 156.474611 159.93968)
		(width 0.148)
		(layer "In4.Cu")
		(net 261)
	)
	(segment
		(start 154.706847 161.707446)
		(end 154.706845 161.707447)
		(width 0.148)
		(layer "In4.Cu")
		(net 261)
	)
	(segment
		(start 155.413953 161.00034)
		(end 155.413951 161.000341)
		(width 0.148)
		(layer "In4.Cu")
		(net 261)
	)
	(segment
		(start 152.875501 163.052)
		(end 152.875501 163.601)
		(width 0.148)
		(layer "In4.Cu")
		(net 261)
	)
	(segment
		(start 162.241617 153.685887)
		(end 162.241617 153.685884)
		(width 0.148)
		(layer "In4.Cu")
		(net 261)
	)
	(segment
		(start 163.375501 152.552)
		(end 163.125501 152.802)
		(width 0.148)
		(layer "In4.Cu")
		(net 261)
	)
	(segment
		(start 154.463451 161.464053)
		(end 154.463451 161.46405)
		(width 0.148)
		(layer "In4.Cu")
		(net 261)
	)
	(segment
		(start 155.98782 159.452889)
		(end 155.98782 159.45289)
		(width 0.148)
		(layer "In4.Cu")
		(net 261)
	)
	(segment
		(start 161.644668 153.796042)
		(end 162.131459 154.282832)
		(width 0.148)
		(layer "In4.Cu")
		(net 261)
	)
	(arc
		(start 161.998222 153.442489)
		(mid 161.821445 153.369266)
		(end 161.644668 153.442489)
		(width 0.148)
		(layer "In4.Cu")
		(net 261)
	)
	(arc
		(start 160.230456 154.856701)
		(mid 160.157233 155.033477)
		(end 160.230456 155.210253)
		(width 0.148)
		(layer "In4.Cu")
		(net 261)
	)
	(arc
		(start 162.838565 153.92928)
		(mid 162.661788 154.002504)
		(end 162.485013 153.92928)
		(width 0.148)
		(layer "In4.Cu")
		(net 261)
	)
	(arc
		(start 155.634268 159.806443)
		(mid 155.457491 159.73322)
		(end 155.280714 159.806443)
		(width 0.148)
		(layer "In4.Cu")
		(net 261)
	)
	(arc
		(start 155.060399 161.707446)
		(mid 154.883622 161.78067)
		(end 154.706847 161.707446)
		(width 0.148)
		(layer "In4.Cu")
		(net 261)
	)
	(arc
		(start 159.303035 157.46481)
		(mid 159.126258 157.538034)
		(end 158.949483 157.46481)
		(width 0.148)
		(layer "In4.Cu")
		(net 261)
	)
	(arc
		(start 157.888823 158.525468)
		(mid 157.962046 158.702245)
		(end 157.888823 158.879022)
		(width 0.148)
		(layer "In4.Cu")
		(net 261)
	)
	(arc
		(start 162.131459 154.636386)
		(mid 161.954682 154.70961)
		(end 161.777907 154.636386)
		(width 0.148)
		(layer "In4.Cu")
		(net 261)
	)
	(arc
		(start 162.131459 154.282832)
		(mid 162.204682 154.459609)
		(end 162.131459 154.636386)
		(width 0.148)
		(layer "In4.Cu")
		(net 261)
	)
	(arc
		(start 161.424353 155.343492)
		(mid 161.247576 155.416716)
		(end 161.070801 155.343492)
		(width 0.148)
		(layer "In4.Cu")
		(net 261)
	)
	(arc
		(start 159.303035 157.111256)
		(mid 159.376258 157.288033)
		(end 159.303035 157.46481)
		(width 0.148)
		(layer "In4.Cu")
		(net 261)
	)
	(arc
		(start 154.927162 160.513549)
		(mid 154.750385 160.440326)
		(end 154.573608 160.513549)
		(width 0.148)
		(layer "In4.Cu")
		(net 261)
	)
	(arc
		(start 161.424353 154.989938)
		(mid 161.497576 155.166715)
		(end 161.424353 155.343492)
		(width 0.148)
		(layer "In4.Cu")
		(net 261)
	)
	(arc
		(start 158.595929 157.818362)
		(mid 158.669152 157.995139)
		(end 158.595929 158.171916)
		(width 0.148)
		(layer "In4.Cu")
		(net 261)
	)
	(arc
		(start 159.169798 156.270913)
		(mid 158.993021 156.19769)
		(end 158.816244 156.270913)
		(width 0.148)
		(layer "In4.Cu")
		(net 261)
	)
	(arc
		(start 161.291116 154.149595)
		(mid 161.114339 154.076372)
		(end 160.937562 154.149595)
		(width 0.148)
		(layer "In4.Cu")
		(net 261)
	)
	(arc
		(start 163.125501 152.802)
		(mid 162.948724 152.875223)
		(end 162.771947 152.802)
		(width 0.148)
		(layer "In4.Cu")
		(net 261)
	)
	(arc
		(start 158.109138 156.978019)
		(mid 158.035915 157.154795)
		(end 158.109138 157.331571)
		(width 0.148)
		(layer "In4.Cu")
		(net 261)
	)
	(arc
		(start 154.220056 161.220655)
		(mid 154.043279 161.147432)
		(end 153.866502 161.220655)
		(width 0.148)
		(layer "In4.Cu")
		(net 261)
	)
	(arc
		(start 157.755586 157.685125)
		(mid 157.578809 157.611902)
		(end 157.402032 157.685125)
		(width 0.148)
		(layer "In4.Cu")
		(net 261)
	)
	(arc
		(start 156.474611 159.93968)
		(mid 156.547834 160.116457)
		(end 156.474611 160.293234)
		(width 0.148)
		(layer "In4.Cu")
		(net 261)
	)
	(arc
		(start 158.595929 158.171916)
		(mid 158.419152 158.24514)
		(end 158.242377 158.171916)
		(width 0.148)
		(layer "In4.Cu")
		(net 261)
	)
	(arc
		(start 160.010141 156.757704)
		(mid 159.833364 156.830928)
		(end 159.656589 156.757704)
		(width 0.148)
		(layer "In4.Cu")
		(net 261)
	)
	(arc
		(start 153.933122 162.347936)
		(mid 153.756346 162.274712)
		(end 153.579569 162.347935)
		(width 0.148)
		(layer "In4.Cu")
		(net 261)
	)
	(arc
		(start 156.474611 160.293234)
		(mid 156.297834 160.366458)
		(end 156.121059 160.293234)
		(width 0.148)
		(layer "In4.Cu")
		(net 261)
	)
	(arc
		(start 160.717247 156.050598)
		(mid 160.54047 156.123822)
		(end 160.363695 156.050598)
		(width 0.148)
		(layer "In4.Cu")
		(net 261)
	)
	(arc
		(start 162.705329 152.735382)
		(mid 162.528553 152.662158)
		(end 162.351776 152.735381)
		(width 0.148)
		(layer "In4.Cu")
		(net 261)
	)
	(arc
		(start 153.866502 161.220655)
		(mid 153.793279 161.397431)
		(end 153.866502 161.574207)
		(width 0.148)
		(layer "In4.Cu")
		(net 261)
	)
	(arc
		(start 157.888823 158.879022)
		(mid 157.712046 158.952246)
		(end 157.535271 158.879022)
		(width 0.148)
		(layer "In4.Cu")
		(net 261)
	)
	(arc
		(start 158.462692 156.978019)
		(mid 158.285915 156.904796)
		(end 158.109138 156.978019)
		(width 0.148)
		(layer "In4.Cu")
		(net 261)
	)
	(arc
		(start 154.353293 162.414552)
		(mid 154.176516 162.487776)
		(end 153.999741 162.414552)
		(width 0.148)
		(layer "In4.Cu")
		(net 261)
	)
	(arc
		(start 154.573608 160.513549)
		(mid 154.500385 160.690325)
		(end 154.573608 160.867101)
		(width 0.148)
		(layer "In4.Cu")
		(net 261)
	)
	(arc
		(start 160.58401 154.856701)
		(mid 160.407233 154.783478)
		(end 160.230456 154.856701)
		(width 0.148)
		(layer "In4.Cu")
		(net 261)
	)
	(arc
		(start 160.937562 154.149595)
		(mid 160.864339 154.326371)
		(end 160.937562 154.503147)
		(width 0.148)
		(layer "In4.Cu")
		(net 261)
	)
	(arc
		(start 155.280714 159.806443)
		(mid 155.207491 159.983219)
		(end 155.280714 160.159995)
		(width 0.148)
		(layer "In4.Cu")
		(net 261)
	)
	(arc
		(start 161.644668 153.442489)
		(mid 161.571445 153.619265)
		(end 161.644668 153.796041)
		(width 0.148)
		(layer "In4.Cu")
		(net 261)
	)
	(arc
		(start 157.181717 159.586128)
		(mid 157.00494 159.659352)
		(end 156.828165 159.586128)
		(width 0.148)
		(layer "In4.Cu")
		(net 261)
	)
	(arc
		(start 155.767505 160.646786)
		(mid 155.840728 160.823563)
		(end 155.767505 161.00034)
		(width 0.148)
		(layer "In4.Cu")
		(net 261)
	)
	(arc
		(start 159.52335 155.563807)
		(mid 159.450127 155.740583)
		(end 159.52335 155.917359)
		(width 0.148)
		(layer "In4.Cu")
		(net 261)
	)
	(arc
		(start 157.181717 159.232574)
		(mid 157.25494 159.409351)
		(end 157.181717 159.586128)
		(width 0.148)
		(layer "In4.Cu")
		(net 261)
	)
	(arc
		(start 156.341374 159.099337)
		(mid 156.164597 159.026114)
		(end 155.98782 159.099337)
		(width 0.148)
		(layer "In4.Cu")
		(net 261)
	)
	(arc
		(start 162.351775 152.735382)
		(mid 162.278552 152.912158)
		(end 162.351775 153.088934)
		(width 0.148)
		(layer "In4.Cu")
		(net 261)
	)
	(arc
		(start 155.767505 161.00034)
		(mid 155.590728 161.073564)
		(end 155.413953 161.00034)
		(width 0.148)
		(layer "In4.Cu")
		(net 261)
	)
	(arc
		(start 154.353293 162.060998)
		(mid 154.426516 162.237775)
		(end 154.353293 162.414552)
		(width 0.148)
		(layer "In4.Cu")
		(net 261)
	)
	(arc
		(start 160.010141 156.40415)
		(mid 160.083364 156.580927)
		(end 160.010141 156.757704)
		(width 0.148)
		(layer "In4.Cu")
		(net 261)
	)
	(arc
		(start 160.717247 155.697044)
		(mid 160.79047 155.873821)
		(end 160.717247 156.050598)
		(width 0.148)
		(layer "In4.Cu")
		(net 261)
	)
	(arc
		(start 156.694926 158.392231)
		(mid 156.621703 158.569007)
		(end 156.694926 158.745783)
		(width 0.148)
		(layer "In4.Cu")
		(net 261)
	)
	(arc
		(start 157.04848 158.392231)
		(mid 156.871703 158.319008)
		(end 156.694926 158.392231)
		(width 0.148)
		(layer "In4.Cu")
		(net 261)
	)
	(arc
		(start 157.402032 157.685125)
		(mid 157.328809 157.861901)
		(end 157.402032 158.038677)
		(width 0.148)
		(layer "In4.Cu")
		(net 261)
	)
	(arc
		(start 162.838565 153.575726)
		(mid 162.911788 153.752503)
		(end 162.838565 153.92928)
		(width 0.148)
		(layer "In4.Cu")
		(net 261)
	)
	(arc
		(start 155.98782 159.099337)
		(mid 155.914597 159.276113)
		(end 155.98782 159.452889)
		(width 0.148)
		(layer "In4.Cu")
		(net 261)
	)
	(arc
		(start 158.816244 156.270913)
		(mid 158.743021 156.447689)
		(end 158.816244 156.624465)
		(width 0.148)
		(layer "In4.Cu")
		(net 261)
	)
	(arc
		(start 159.876904 155.563807)
		(mid 159.700127 155.490584)
		(end 159.52335 155.563807)
		(width 0.148)
		(layer "In4.Cu")
		(net 261)
	)
	(arc
		(start 155.060399 161.353892)
		(mid 155.133622 161.530669)
		(end 155.060399 161.707446)
		(width 0.148)
		(layer "In4.Cu")
		(net 261)
	)
	(segment
		(start 150.375501 165.302)
		(end 150.875001 164.8025)
		(width 0.256)
		(layer "F.Cu")
		(net 262)
	)
	(segment
		(start 164.150001 138.8025)
		(end 164.150002 139.877499)
		(width 0.201)
		(layer "F.Cu")
		(net 262)
	)
	(via
		(at 164.150002 139.877499)
		(size 0.45)
		(drill 0.1)
		(layers "F.Cu" "B.Cu")
		(net 262)
	)
	(via
		(at 150.875001 164.8025)
		(size 0.45)
		(drill 0.1)
		(layers "F.Cu" "B.Cu")
		(net 262)
	)
	(segment
		(start 159.930959 153.996542)
		(end 159.724309 153.789892)
		(width 0.148)
		(layer "In4.Cu")
		(net 262)
	)
	(segment
		(start 152.375501 161.552)
		(end 152.375501 162.061)
		(width 0.148)
		(layer "In4.Cu")
		(net 262)
	)
	(segment
		(start 155.128119 158.386081)
		(end 155.54142 158.799381)
		(width 0.148)
		(layer "In4.Cu")
		(net 262)
	)
	(segment
		(start 154.097335 159.830168)
		(end 152.375501 161.552)
		(width 0.148)
		(layer "In4.Cu")
		(net 262)
	)
	(segment
		(start 160.491163 154.203192)
		(end 160.491162 154.203193)
		(width 0.148)
		(layer "In4.Cu")
		(net 262)
	)
	(segment
		(start 156.542331 156.971869)
		(end 156.955632 157.385169)
		(width 0.148)
		(layer "In4.Cu")
		(net 262)
	)
	(segment
		(start 156.248527 158.445828)
		(end 156.248526 158.445829)
		(width 0.148)
		(layer "In4.Cu")
		(net 262)
	)
	(segment
		(start 158.723396 155.617406)
		(end 158.516747 155.410757)
		(width 0.148)
		(layer "In4.Cu")
		(net 262)
	)
	(segment
		(start 162.375501 151.552)
		(end 161.875501 152.052)
		(width 0.148)
		(layer "In4.Cu")
		(net 262)
	)
	(segment
		(start 160.638065 153.289439)
		(end 160.638065 153.289436)
		(width 0.148)
		(layer "In4.Cu")
		(net 262)
	)
	(segment
		(start 160.844716 153.496087)
		(end 160.844714 153.496088)
		(width 0.148)
		(layer "In4.Cu")
		(net 262)
	)
	(segment
		(start 155.541421 159.152934)
		(end 155.54142 159.152935)
		(width 0.148)
		(layer "In4.Cu")
		(net 262)
	)
	(segment
		(start 154.48076 159.860042)
		(end 154.450887 159.830169)
		(width 0.148)
		(layer "In4.Cu")
		(net 262)
	)
	(segment
		(start 159.370756 153.789891)
		(end 159.370755 153.789892)
		(width 0.148)
		(layer "In4.Cu")
		(net 262)
	)
	(segment
		(start 158.516747 155.410754)
		(end 158.310097 155.204104)
		(width 0.148)
		(layer "In4.Cu")
		(net 262)
	)
	(segment
		(start 155.894972 158.44583)
		(end 155.688323 158.239181)
		(width 0.148)
		(layer "In4.Cu")
		(net 262)
	)
	(segment
		(start 158.516747 155.410757)
		(end 158.516747 155.410754)
		(width 0.148)
		(layer "In4.Cu")
		(net 262)
	)
	(segment
		(start 156.395429 157.532072)
		(end 156.188779 157.325422)
		(width 0.148)
		(layer "In4.Cu")
		(net 262)
	)
	(segment
		(start 160.784968 152.375679)
		(end 160.784967 152.37568)
		(width 0.148)
		(layer "In4.Cu")
		(net 262)
	)
	(segment
		(start 161.905374 152.788981)
		(end 161.905374 152.788982)
		(width 0.148)
		(layer "In4.Cu")
		(net 262)
	)
	(segment
		(start 159.784057 154.910298)
		(end 159.784056 154.910299)
		(width 0.148)
		(layer "In4.Cu")
		(net 262)
	)
	(segment
		(start 163.875001 145.8525)
		(end 163.400501 146.327)
		(width 0.148)
		(layer "In4.Cu")
		(net 262)
	)
	(segment
		(start 159.223853 154.703648)
		(end 159.017203 154.496998)
		(width 0.148)
		(layer "In4.Cu")
		(net 262)
	)
	(segment
		(start 161.198269 153.496086)
		(end 161.198268 153.496087)
		(width 0.148)
		(layer "In4.Cu")
		(net 262)
	)
	(segment
		(start 157.249437 156.264763)
		(end 157.662738 156.678063)
		(width 0.148)
		(layer "In4.Cu")
		(net 262)
	)
	(segment
		(start 157.662739 157.031616)
		(end 157.662738 157.031617)
		(width 0.148)
		(layer "In4.Cu")
		(net 262)
	)
	(segment
		(start 156.60208 157.738723)
		(end 156.602078 157.738724)
		(width 0.148)
		(layer "In4.Cu")
		(net 262)
	)
	(segment
		(start 155.187868 159.152935)
		(end 155.187866 159.152936)
		(width 0.148)
		(layer "In4.Cu")
		(net 262)
	)
	(segment
		(start 156.602078 157.738724)
		(end 156.395429 157.532075)
		(width 0.148)
		(layer "In4.Cu")
		(net 262)
	)
	(segment
		(start 155.128119 158.38608)
		(end 155.128119 158.386081)
		(width 0.148)
		(layer "In4.Cu")
		(net 262)
	)
	(segment
		(start 157.956544 155.204103)
		(end 157.956543 155.204104)
		(width 0.148)
		(layer "In4.Cu")
		(net 262)
	)
	(segment
		(start 157.809641 156.11786)
		(end 157.602991 155.91121)
		(width 0.148)
		(layer "In4.Cu")
		(net 262)
	)
	(segment
		(start 154.421013 159.093187)
		(end 154.834314 159.506487)
		(width 0.148)
		(layer "In4.Cu")
		(net 262)
	)
	(segment
		(start 160.13761 154.203193)
		(end 160.137608 154.203194)
		(width 0.148)
		(layer "In4.Cu")
		(net 262)
	)
	(segment
		(start 161.551822 152.788982)
		(end 161.551822 152.788981)
		(width 0.148)
		(layer "In4.Cu")
		(net 262)
	)
	(segment
		(start 154.097334 159.83017)
		(end 154.097335 159.830168)
		(width 0.148)
		(layer "In4.Cu")
		(net 262)
	)
	(segment
		(start 157.309186 157.031617)
		(end 157.309184 157.031618)
		(width 0.148)
		(layer "In4.Cu")
		(net 262)
	)
	(segment
		(start 160.077861 153.436339)
		(end 160.491162 153.849639)
		(width 0.148)
		(layer "In4.Cu")
		(net 262)
	)
	(segment
		(start 162.375501 148.802)
		(end 162.375501 151.552)
		(width 0.148)
		(layer "In4.Cu")
		(net 262)
	)
	(segment
		(start 163.400501 146.327)
		(end 163.400501 147.777)
		(width 0.148)
		(layer "In4.Cu")
		(net 262)
	)
	(segment
		(start 155.835225 157.678974)
		(end 155.835225 157.678975)
		(width 0.148)
		(layer "In4.Cu")
		(net 262)
	)
	(segment
		(start 157.956543 155.557656)
		(end 157.956543 155.557657)
		(width 0.148)
		(layer "In4.Cu")
		(net 262)
	)
	(segment
		(start 155.835225 157.678975)
		(end 156.248526 158.092275)
		(width 0.148)
		(layer "In4.Cu")
		(net 262)
	)
	(segment
		(start 154.981217 158.946284)
		(end 154.774567 158.739634)
		(width 0.148)
		(layer "In4.Cu")
		(net 262)
	)
	(segment
		(start 152.160501 162.276)
		(end 151.760501 162.276)
		(width 0.148)
		(layer "In4.Cu")
		(net 262)
	)
	(segment
		(start 159.430504 154.910299)
		(end 159.430502 154.9103)
		(width 0.148)
		(layer "In4.Cu")
		(net 262)
	)
	(segment
		(start 154.981217 158.946287)
		(end 154.981217 158.946284)
		(width 0.148)
		(layer "In4.Cu")
		(net 262)
	)
	(segment
		(start 151.760501 162.276)
		(end 151.400501 162.636)
		(width 0.148)
		(layer "In4.Cu")
		(net 262)
	)
	(segment
		(start 152.375501 162.061)
		(end 152.160501 162.276)
		(width 0.148)
		(layer "In4.Cu")
		(net 262)
	)
	(segment
		(start 160.077862 153.082785)
		(end 160.077861 153.082786)
		(width 0.148)
		(layer "In4.Cu")
		(net 262)
	)
	(segment
		(start 159.930959 153.996545)
		(end 159.930959 153.996542)
		(width 0.148)
		(layer "In4.Cu")
		(net 262)
	)
	(segment
		(start 163.400501 147.777)
		(end 162.375501 148.802)
		(width 0.148)
		(layer "In4.Cu")
		(net 262)
	)
	(segment
		(start 156.395429 157.532075)
		(end 156.395429 157.532072)
		(width 0.148)
		(layer "In4.Cu")
		(net 262)
	)
	(segment
		(start 157.956543 155.557657)
		(end 158.369844 155.970957)
		(width 0.148)
		(layer "In4.Cu")
		(net 262)
	)
	(segment
		(start 155.688323 158.239178)
		(end 155.481673 158.032528)
		(width 0.148)
		(layer "In4.Cu")
		(net 262)
	)
	(segment
		(start 161.551822 152.788981)
		(end 161.138521 152.37568)
		(width 0.148)
		(layer "In4.Cu")
		(net 262)
	)
	(segment
		(start 154.834315 159.86004)
		(end 154.834314 159.860041)
		(width 0.148)
		(layer "In4.Cu")
		(net 262)
	)
	(segment
		(start 154.421013 159.093186)
		(end 154.421013 159.093187)
		(width 0.148)
		(layer "In4.Cu")
		(net 262)
	)
	(segment
		(start 158.01629 156.324512)
		(end 157.809641 156.117863)
		(width 0.148)
		(layer "In4.Cu")
		(net 262)
	)
	(segment
		(start 160.077861 153.436338)
		(end 160.077861 153.436339)
		(width 0.148)
		(layer "In4.Cu")
		(net 262)
	)
	(segment
		(start 150.875001 164.5015)
		(end 150.875001 164.8025)
		(width 0.148)
		(layer "In4.Cu")
		(net 262)
	)
	(segment
		(start 159.076951 155.617404)
		(end 159.07695 155.617405)
		(width 0.148)
		(layer "In4.Cu")
		(net 262)
	)
	(segment
		(start 158.723398 155.617405)
		(end 158.723396 155.617406)
		(width 0.148)
		(layer "In4.Cu")
		(net 262)
	)
	(segment
		(start 155.894974 158.445829)
		(end 155.894972 158.44583)
		(width 0.148)
		(layer "In4.Cu")
		(net 262)
	)
	(segment
		(start 159.223853 154.703651)
		(end 159.223853 154.703648)
		(width 0.148)
		(layer "In4.Cu")
		(net 262)
	)
	(segment
		(start 156.542332 156.618315)
		(end 156.542331 156.618316)
		(width 0.148)
		(layer "In4.Cu")
		(net 262)
	)
	(segment
		(start 160.784967 152.729233)
		(end 161.198268 153.142533)
		(width 0.148)
		(layer "In4.Cu")
		(net 262)
	)
	(segment
		(start 163.875001 140.1525)
		(end 163.875001 145.8525)
		(width 0.148)
		(layer "In4.Cu")
		(net 262)
	)
	(segment
		(start 155.835226 157.325421)
		(end 155.835225 157.325422)
		(width 0.148)
		(layer "In4.Cu")
		(net 262)
	)
	(segment
		(start 160.137608 154.203194)
		(end 159.930959 153.996545)
		(width 0.148)
		(layer "In4.Cu")
		(net 262)
	)
	(segment
		(start 154.480762 159.860041)
		(end 154.48076 159.860042)
		(width 0.148)
		(layer "In4.Cu")
		(net 262)
	)
	(segment
		(start 157.102535 156.824966)
		(end 156.895885 156.618316)
		(width 0.148)
		(layer "In4.Cu")
		(net 262)
	)
	(segment
		(start 157.309184 157.031618)
		(end 157.102535 156.824969)
		(width 0.148)
		(layer "In4.Cu")
		(net 262)
	)
	(segment
		(start 158.66365 154.496997)
		(end 158.663649 154.496998)
		(width 0.148)
		(layer "In4.Cu")
		(net 262)
	)
	(segment
		(start 157.249437 156.264762)
		(end 157.249437 156.264763)
		(width 0.148)
		(layer "In4.Cu")
		(net 262)
	)
	(segment
		(start 155.187866 159.152936)
		(end 154.981217 158.946287)
		(width 0.148)
		(layer "In4.Cu")
		(net 262)
	)
	(segment
		(start 156.542331 156.971868)
		(end 156.542331 156.971869)
		(width 0.148)
		(layer "In4.Cu")
		(net 262)
	)
	(segment
		(start 157.249438 155.911209)
		(end 157.249437 155.91121)
		(width 0.148)
		(layer "In4.Cu")
		(net 262)
	)
	(segment
		(start 151.400501 163.976)
		(end 150.875001 164.5015)
		(width 0.148)
		(layer "In4.Cu")
		(net 262)
	)
	(segment
		(start 156.955633 157.738722)
		(end 156.955632 157.738723)
		(width 0.148)
		(layer "In4.Cu")
		(net 262)
	)
	(segment
		(start 158.663649 154.850551)
		(end 159.07695 155.263851)
		(width 0.148)
		(layer "In4.Cu")
		(net 262)
	)
	(segment
		(start 161.875501 152.405554)
		(end 161.905375 152.435428)
		(width 0.148)
		(layer "In4.Cu")
		(net 262)
	)
	(segment
		(start 160.784967 152.729232)
		(end 160.784967 152.729233)
		(width 0.148)
		(layer "In4.Cu")
		(net 262)
	)
	(segment
		(start 154.421014 158.739633)
		(end 154.421013 158.739634)
		(width 0.148)
		(layer "In4.Cu")
		(net 262)
	)
	(segment
		(start 155.12812 158.032527)
		(end 155.128119 158.032528)
		(width 0.148)
		(layer "In4.Cu")
		(net 262)
	)
	(segment
		(start 159.370755 154.143445)
		(end 159.784056 154.556745)
		(width 0.148)
		(layer "In4.Cu")
		(net 262)
	)
	(segment
		(start 160.844714 153.496088)
		(end 160.638065 153.289439)
		(width 0.148)
		(layer "In4.Cu")
		(net 262)
	)
	(segment
		(start 159.370755 154.143444)
		(end 159.370755 154.143445)
		(width 0.148)
		(layer "In4.Cu")
		(net 262)
	)
	(segment
		(start 159.430502 154.9103)
		(end 159.223853 154.703651)
		(width 0.148)
		(layer "In4.Cu")
		(net 262)
	)
	(segment
		(start 158.016292 156.324511)
		(end 158.01629 156.324512)
		(width 0.148)
		(layer "In4.Cu")
		(net 262)
	)
	(segment
		(start 157.102535 156.824969)
		(end 157.102535 156.824966)
		(width 0.148)
		(layer "In4.Cu")
		(net 262)
	)
	(segment
		(start 151.400501 162.636)
		(end 151.400501 163.976)
		(width 0.148)
		(layer "In4.Cu")
		(net 262)
	)
	(segment
		(start 157.809641 156.117863)
		(end 157.809641 156.11786)
		(width 0.148)
		(layer "In4.Cu")
		(net 262)
	)
	(segment
		(start 164.150002 139.877499)
		(end 163.875001 140.1525)
		(width 0.148)
		(layer "In4.Cu")
		(net 262)
	)
	(segment
		(start 158.663649 154.85055)
		(end 158.663649 154.850551)
		(width 0.148)
		(layer "In4.Cu")
		(net 262)
	)
	(segment
		(start 160.638065 153.289436)
		(end 160.431415 153.082786)
		(width 0.148)
		(layer "In4.Cu")
		(net 262)
	)
	(segment
		(start 158.369845 156.32451)
		(end 158.369844 156.324511)
		(width 0.148)
		(layer "In4.Cu")
		(net 262)
	)
	(segment
		(start 155.688323 158.239181)
		(end 155.688323 158.239178)
		(width 0.148)
		(layer "In4.Cu")
		(net 262)
	)
	(arc
		(start 157.662738 156.678063)
		(mid 157.735962 156.854839)
		(end 157.662739 157.031616)
		(width 0.148)
		(layer "In4.Cu")
		(net 262)
	)
	(arc
		(start 159.724309 153.789892)
		(mid 159.547533 153.716668)
		(end 159.370756 153.789891)
		(width 0.148)
		(layer "In4.Cu")
		(net 262)
	)
	(arc
		(start 159.370755 153.789892)
		(mid 159.297532 153.966668)
		(end 159.370755 154.143444)
		(width 0.148)
		(layer "In4.Cu")
		(net 262)
	)
	(arc
		(start 154.834314 159.860041)
		(mid 154.657537 159.933265)
		(end 154.480762 159.860041)
		(width 0.148)
		(layer "In4.Cu")
		(net 262)
	)
	(arc
		(start 158.310097 155.204104)
		(mid 158.133321 155.13088)
		(end 157.956544 155.204103)
		(width 0.148)
		(layer "In4.Cu")
		(net 262)
	)
	(arc
		(start 156.542331 156.618316)
		(mid 156.469108 156.795092)
		(end 156.542331 156.971868)
		(width 0.148)
		(layer "In4.Cu")
		(net 262)
	)
	(arc
		(start 155.54142 158.799381)
		(mid 155.614644 158.976157)
		(end 155.541421 159.152934)
		(width 0.148)
		(layer "In4.Cu")
		(net 262)
	)
	(arc
		(start 156.248526 158.445829)
		(mid 156.071749 158.519053)
		(end 155.894974 158.445829)
		(width 0.148)
		(layer "In4.Cu")
		(net 262)
	)
	(arc
		(start 159.784056 154.910299)
		(mid 159.607279 154.983523)
		(end 159.430504 154.910299)
		(width 0.148)
		(layer "In4.Cu")
		(net 262)
	)
	(arc
		(start 154.450887 159.830169)
		(mid 154.27411 159.756946)
		(end 154.097334 159.83017)
		(width 0.148)
		(layer "In4.Cu")
		(net 262)
	)
	(arc
		(start 155.835225 157.325422)
		(mid 155.762002 157.502198)
		(end 155.835225 157.678974)
		(width 0.148)
		(layer "In4.Cu")
		(net 262)
	)
	(arc
		(start 161.875501 152.052)
		(mid 161.802278 152.228777)
		(end 161.875501 152.405554)
		(width 0.148)
		(layer "In4.Cu")
		(net 262)
	)
	(arc
		(start 156.248526 158.092275)
		(mid 156.32175 158.269051)
		(end 156.248527 158.445828)
		(width 0.148)
		(layer "In4.Cu")
		(net 262)
	)
	(arc
		(start 161.905374 152.788982)
		(mid 161.728599 152.862204)
		(end 161.551822 152.788982)
		(width 0.148)
		(layer "In4.Cu")
		(net 262)
	)
	(arc
		(start 156.895885 156.618316)
		(mid 156.719109 156.545092)
		(end 156.542332 156.618315)
		(width 0.148)
		(layer "In4.Cu")
		(net 262)
	)
	(arc
		(start 158.369844 155.970957)
		(mid 158.443068 156.147733)
		(end 158.369845 156.32451)
		(width 0.148)
		(layer "In4.Cu")
		(net 262)
	)
	(arc
		(start 157.956543 155.204104)
		(mid 157.88332 155.38088)
		(end 157.956543 155.557656)
		(width 0.148)
		(layer "In4.Cu")
		(net 262)
	)
	(arc
		(start 160.491162 154.203193)
		(mid 160.314385 154.276417)
		(end 160.13761 154.203193)
		(width 0.148)
		(layer "In4.Cu")
		(net 262)
	)
	(arc
		(start 154.421013 158.739634)
		(mid 154.34779 158.91641)
		(end 154.421013 159.093186)
		(width 0.148)
		(layer "In4.Cu")
		(net 262)
	)
	(arc
		(start 160.784967 152.37568)
		(mid 160.711744 152.552456)
		(end 160.784967 152.729232)
		(width 0.148)
		(layer "In4.Cu")
		(net 262)
	)
	(arc
		(start 156.955632 157.385169)
		(mid 157.028856 157.561945)
		(end 156.955633 157.738722)
		(width 0.148)
		(layer "In4.Cu")
		(net 262)
	)
	(arc
		(start 158.369844 156.324511)
		(mid 158.193067 156.397735)
		(end 158.016292 156.324511)
		(width 0.148)
		(layer "In4.Cu")
		(net 262)
	)
	(arc
		(start 156.188779 157.325422)
		(mid 156.012003 157.252198)
		(end 155.835226 157.325421)
		(width 0.148)
		(layer "In4.Cu")
		(net 262)
	)
	(arc
		(start 156.955632 157.738723)
		(mid 156.778855 157.811947)
		(end 156.60208 157.738723)
		(width 0.148)
		(layer "In4.Cu")
		(net 262)
	)
	(arc
		(start 160.431415 153.082786)
		(mid 160.254639 153.009562)
		(end 160.077862 153.082785)
		(width 0.148)
		(layer "In4.Cu")
		(net 262)
	)
	(arc
		(start 157.602991 155.91121)
		(mid 157.426215 155.837986)
		(end 157.249438 155.911209)
		(width 0.148)
		(layer "In4.Cu")
		(net 262)
	)
	(arc
		(start 161.138521 152.37568)
		(mid 160.961745 152.302456)
		(end 160.784968 152.375679)
		(width 0.148)
		(layer "In4.Cu")
		(net 262)
	)
	(arc
		(start 161.198268 153.142533)
		(mid 161.271492 153.319309)
		(end 161.198269 153.496086)
		(width 0.148)
		(layer "In4.Cu")
		(net 262)
	)
	(arc
		(start 158.663649 154.496998)
		(mid 158.590426 154.673774)
		(end 158.663649 154.85055)
		(width 0.148)
		(layer "In4.Cu")
		(net 262)
	)
	(arc
		(start 160.077861 153.082786)
		(mid 160.004638 153.259562)
		(end 160.077861 153.436338)
		(width 0.148)
		(layer "In4.Cu")
		(net 262)
	)
	(arc
		(start 159.07695 155.263851)
		(mid 159.150174 155.440627)
		(end 159.076951 155.617404)
		(width 0.148)
		(layer "In4.Cu")
		(net 262)
	)
	(arc
		(start 157.249437 155.91121)
		(mid 157.176214 156.087986)
		(end 157.249437 156.264762)
		(width 0.148)
		(layer "In4.Cu")
		(net 262)
	)
	(arc
		(start 154.774567 158.739634)
		(mid 154.597791 158.66641)
		(end 154.421014 158.739633)
		(width 0.148)
		(layer "In4.Cu")
		(net 262)
	)
	(arc
		(start 159.07695 155.617405)
		(mid 158.900173 155.690629)
		(end 158.723398 155.617405)
		(width 0.148)
		(layer "In4.Cu")
		(net 262)
	)
	(arc
		(start 161.198268 153.496087)
		(mid 161.021491 153.569311)
		(end 160.844716 153.496087)
		(width 0.148)
		(layer "In4.Cu")
		(net 262)
	)
	(arc
		(start 155.481673 158.032528)
		(mid 155.304897 157.959304)
		(end 155.12812 158.032527)
		(width 0.148)
		(layer "In4.Cu")
		(net 262)
	)
	(arc
		(start 154.834314 159.506487)
		(mid 154.907538 159.683263)
		(end 154.834315 159.86004)
		(width 0.148)
		(layer "In4.Cu")
		(net 262)
	)
	(arc
		(start 160.491162 153.849639)
		(mid 160.564386 154.026415)
		(end 160.491163 154.203192)
		(width 0.148)
		(layer "In4.Cu")
		(net 262)
	)
	(arc
		(start 155.54142 159.152935)
		(mid 155.364643 159.226159)
		(end 155.187868 159.152935)
		(width 0.148)
		(layer "In4.Cu")
		(net 262)
	)
	(arc
		(start 157.662738 157.031617)
		(mid 157.485961 157.104841)
		(end 157.309186 157.031617)
		(width 0.148)
		(layer "In4.Cu")
		(net 262)
	)
	(arc
		(start 155.128119 158.032528)
		(mid 155.054896 158.209304)
		(end 155.128119 158.38608)
		(width 0.148)
		(layer "In4.Cu")
		(net 262)
	)
	(arc
		(start 159.784056 154.556745)
		(mid 159.85728 154.733521)
		(end 159.784057 154.910298)
		(width 0.148)
		(layer "In4.Cu")
		(net 262)
	)
	(arc
		(start 159.017203 154.496998)
		(mid 158.840427 154.423774)
		(end 158.66365 154.496997)
		(width 0.148)
		(layer "In4.Cu")
		(net 262)
	)
	(arc
		(start 161.905375 152.435428)
		(mid 161.978598 152.612205)
		(end 161.905374 152.788981)
		(width 0.148)
		(layer "In4.Cu")
		(net 262)
	)
	(segment
		(start 91 182.2)
		(end 91.45 182.2)
		(width 0.15)
		(layer "F.Cu")
		(net 263)
	)
	(segment
		(start 91.45 182.2)
		(end 91.706 181.944)
		(width 0.15)
		(layer "F.Cu")
		(net 263)
	)
	(segment
		(start 91 182.2)
		(end 91 182.85)
		(width 0.15)
		(layer "F.Cu")
		(net 263)
	)
	(segment
		(start 92.401 181.944)
		(end 91.706 181.944)
		(width 0.15)
		(layer "F.Cu")
		(net 263)
	)
	(segment
		(start 199.1765 156.8025)
		(end 198.1755 156.8025)
		(width 0.256)
		(layer "F.Cu")
		(net 263)
	)
	(via
		(at 91 182.85)
		(size 0.45)
		(drill 0.1)
		(layers "F.Cu" "B.Cu")
		(net 263)
	)
	(via
		(at 198.1755 156.8025)
		(size 0.45)
		(drill 0.1)
		(layers "F.Cu" "B.Cu")
		(net 263)
	)
	(segment
		(start 91 182.85)
		(end 89.5 182.85)
		(width 0.15)
		(layer "B.Cu")
		(net 263)
	)
	(segment
		(start 203.25 160.85)
		(end 203.25 192.15)
		(width 0.1)
		(layer "In4.Cu")
		(net 263)
	)
	(segment
		(start 195.3 200.1)
		(end 180.2 200.1)
		(width 0.1)
		(layer "In4.Cu")
		(net 263)
	)
	(segment
		(start 180.2 200.1)
		(end 177.775 197.675)
		(width 0.1)
		(layer "In4.Cu")
		(net 263)
	)
	(segment
		(start 92.15 187.35)
		(end 91 186.2)
		(width 0.1)
		(layer "In4.Cu")
		(net 263)
	)
	(segment
		(start 198.1755 156.8025)
		(end 199.2025 156.8025)
		(width 0.1)
		(layer "In4.Cu")
		(net 263)
	)
	(segment
		(start 157.75 197.05)
		(end 152.45 197.05)
		(width 0.1)
		(layer "In4.Cu")
		(net 263)
	)
	(segment
		(start 176.3 191.6)
		(end 174.5 189.8)
		(width 0.1)
		(layer "In4.Cu")
		(net 263)
	)
	(segment
		(start 199.2025 156.8025)
		(end 203.25 160.85)
		(width 0.1)
		(layer "In4.Cu")
		(net 263)
	)
	(segment
		(start 203.25 192.15)
		(end 195.3 200.1)
		(width 0.1)
		(layer "In4.Cu")
		(net 263)
	)
	(segment
		(start 176.3 194.3)
		(end 176.3 191.6)
		(width 0.1)
		(layer "In4.Cu")
		(net 263)
	)
	(segment
		(start 152.45 197.05)
		(end 151.4 196)
		(width 0.1)
		(layer "In4.Cu")
		(net 263)
	)
	(segment
		(start 106.85 196)
		(end 98.2 187.35)
		(width 0.1)
		(layer "In4.Cu")
		(net 263)
	)
	(segment
		(start 177.775 197.675)
		(end 177.775 195.775)
		(width 0.1)
		(layer "In4.Cu")
		(net 263)
	)
	(segment
		(start 165 189.8)
		(end 157.75 197.05)
		(width 0.1)
		(layer "In4.Cu")
		(net 263)
	)
	(segment
		(start 174.5 189.8)
		(end 165 189.8)
		(width 0.1)
		(layer "In4.Cu")
		(net 263)
	)
	(segment
		(start 98.2 187.35)
		(end 92.15 187.35)
		(width 0.1)
		(layer "In4.Cu")
		(net 263)
	)
	(segment
		(start 151.4 196)
		(end 106.85 196)
		(width 0.1)
		(layer "In4.Cu")
		(net 263)
	)
	(segment
		(start 177.775 195.775)
		(end 176.3 194.3)
		(width 0.1)
		(layer "In4.Cu")
		(net 263)
	)
	(segment
		(start 91 186.2)
		(end 91 182.85)
		(width 0.1)
		(layer "In4.Cu")
		(net 263)
	)
	(segment
		(start 151.375501 168.302)
		(end 151.875001 167.8025)
		(width 0.256)
		(layer "F.Cu")
		(net 264)
	)
	(segment
		(start 164.900001 146.2025)
		(end 164.900001 147.2775)
		(width 0.201)
		(layer "F.Cu")
		(net 264)
	)
	(via
		(at 164.900001 147.2775)
		(size 0.45)
		(drill 0.1)
		(layers "F.Cu" "B.Cu")
		(net 264)
	)
	(via
		(at 151.875001 167.8025)
		(size 0.45)
		(drill 0.1)
		(layers "F.Cu" "B.Cu")
		(net 264)
	)
	(segment
		(start 160.02228 161.951818)
		(end 160.02228 161.951817)
		(width 0.148)
		(layer "In4.Cu")
		(net 264)
	)
	(segment
		(start 162.075555 159.05535)
		(end 162.497151 159.476946)
		(width 0.148)
		(layer "In4.Cu")
		(net 264)
	)
	(segment
		(start 164.196873 156.934032)
		(end 164.618469 157.355628)
		(width 0.148)
		(layer "In4.Cu")
		(net 264)
	)
	(segment
		(start 156.418707 164.712197)
		(end 156.418707 164.712198)
		(width 0.148)
		(layer "In4.Cu")
		(net 264)
	)
	(segment
		(start 162.782661 157.994692)
		(end 162.782661 157.994691)
		(width 0.148)
		(layer "In4.Cu")
		(net 264)
	)
	(segment
		(start 155.711601 165.419304)
		(end 156.133197 165.8409)
		(width 0.148)
		(layer "In4.Cu")
		(net 264)
	)
	(segment
		(start 160.661343 160.469561)
		(end 160.661343 160.469562)
		(width 0.148)
		(layer "In4.Cu")
		(net 264)
	)
	(segment
		(start 161.790044 160.537605)
		(end 161.790044 160.537606)
		(width 0.148)
		(layer "In4.Cu")
		(net 264)
	)
	(segment
		(start 157.547408 164.780241)
		(end 157.547408 164.780242)
		(width 0.148)
		(layer "In4.Cu")
		(net 264)
	)
	(segment
		(start 162.075555 158.701798)
		(end 162.075555 158.701797)
		(width 0.148)
		(layer "In4.Cu")
		(net 264)
	)
	(segment
		(start 163.489767 157.287586)
		(end 163.489767 157.287585)
		(width 0.148)
		(layer "In4.Cu")
		(net 264)
	)
	(segment
		(start 160.729386 161.244712)
		(end 160.729386 161.244711)
		(width 0.148)
		(layer "In4.Cu")
		(net 264)
	)
	(segment
		(start 155.711601 165.065752)
		(end 155.711601 165.065751)
		(width 0.148)
		(layer "In4.Cu")
		(net 264)
	)
	(segment
		(start 163.911362 158.416287)
		(end 163.911362 158.416288)
		(width 0.148)
		(layer "In4.Cu")
		(net 264)
	)
	(segment
		(start 161.436492 160.537606)
		(end 161.436492 160.537605)
		(width 0.148)
		(layer "In4.Cu")
		(net 264)
	)
	(segment
		(start 160.661343 160.469562)
		(end 161.082939 160.891158)
		(width 0.148)
		(layer "In4.Cu")
		(net 264)
	)
	(segment
		(start 157.900962 164.073135)
		(end 157.479366 163.651539)
		(width 0.148)
		(layer "In4.Cu")
		(net 264)
	)
	(segment
		(start 156.133196 166.194453)
		(end 156.133196 166.194454)
		(width 0.148)
		(layer "In4.Cu")
		(net 264)
	)
	(segment
		(start 162.850704 159.123394)
		(end 162.850704 159.123393)
		(width 0.148)
		(layer "In4.Cu")
		(net 264)
	)
	(segment
		(start 157.193856 164.780241)
		(end 156.77226 164.358645)
		(width 0.148)
		(layer "In4.Cu")
		(net 264)
	)
	(segment
		(start 160.661343 160.11601)
		(end 160.661343 160.116009)
		(width 0.148)
		(layer "In4.Cu")
		(net 264)
	)
	(segment
		(start 158.540025 162.590879)
		(end 158.540025 162.59088)
		(width 0.148)
		(layer "In4.Cu")
		(net 264)
	)
	(segment
		(start 155.779644 166.194454)
		(end 155.779644 166.194453)
		(width 0.148)
		(layer "In4.Cu")
		(net 264)
	)
	(segment
		(start 155.779644 166.194453)
		(end 155.745624 166.160433)
		(width 0.148)
		(layer "In4.Cu")
		(net 264)
	)
	(segment
		(start 157.832919 162.944434)
		(end 157.832919 162.944433)
		(width 0.148)
		(layer "In4.Cu")
		(net 264)
	)
	(segment
		(start 159.668726 162.658923)
		(end 159.668726 162.658924)
		(width 0.148)
		(layer "In4.Cu")
		(net 264)
	)
	(segment
		(start 165.625501 155.927)
		(end 164.938001 156.6145)
		(width 0.148)
		(layer "In4.Cu")
		(net 264)
	)
	(segment
		(start 159.954237 161.176667)
		(end 159.954237 161.176668)
		(width 0.148)
		(layer "In4.Cu")
		(net 264)
	)
	(segment
		(start 158.608068 163.36603)
		(end 158.608068 163.366029)
		(width 0.148)
		(layer "In4.Cu")
		(net 264)
	)
	(segment
		(start 158.540025 162.59088)
		(end 158.961621 163.012476)
		(width 0.148)
		(layer "In4.Cu")
		(net 264)
	)
	(segment
		(start 161.368449 159.408904)
		(end 161.368449 159.408903)
		(width 0.148)
		(layer "In4.Cu")
		(net 264)
	)
	(segment
		(start 161.436492 160.537605)
		(end 161.014896 160.116009)
		(width 0.148)
		(layer "In4.Cu")
		(net 264)
	)
	(segment
		(start 161.368449 159.762456)
		(end 161.790045 160.184052)
		(width 0.148)
		(layer "In4.Cu")
		(net 264)
	)
	(segment
		(start 156.418707 164.358646)
		(end 156.418707 164.358645)
		(width 0.148)
		(layer "In4.Cu")
		(net 264)
	)
	(segment
		(start 158.96162 163.366029)
		(end 158.96162 163.36603)
		(width 0.148)
		(layer "In4.Cu")
		(net 264)
	)
	(segment
		(start 159.247131 161.530222)
		(end 159.247131 161.530221)
		(width 0.148)
		(layer "In4.Cu")
		(net 264)
	)
	(segment
		(start 158.540025 162.237328)
		(end 158.540025 162.237327)
		(width 0.148)
		(layer "In4.Cu")
		(net 264)
	)
	(segment
		(start 156.418707 164.712198)
		(end 156.840303 165.133794)
		(width 0.148)
		(layer "In4.Cu")
		(net 264)
	)
	(segment
		(start 163.55781 158.416287)
		(end 163.136214 157.994691)
		(width 0.148)
		(layer "In4.Cu")
		(net 264)
	)
	(segment
		(start 161.368449 159.762455)
		(end 161.368449 159.762456)
		(width 0.148)
		(layer "In4.Cu")
		(net 264)
	)
	(segment
		(start 162.075555 159.055349)
		(end 162.075555 159.05535)
		(width 0.148)
		(layer "In4.Cu")
		(net 264)
	)
	(segment
		(start 162.782661 158.348244)
		(end 163.204257 158.76984)
		(width 0.148)
		(layer "In4.Cu")
		(net 264)
	)
	(segment
		(start 164.264916 157.709182)
		(end 164.264916 157.709181)
		(width 0.148)
		(layer "In4.Cu")
		(net 264)
	)
	(segment
		(start 157.900962 164.073136)
		(end 157.900962 164.073135)
		(width 0.148)
		(layer "In4.Cu")
		(net 264)
	)
	(segment
		(start 155.711601 165.419303)
		(end 155.711601 165.419304)
		(width 0.148)
		(layer "In4.Cu")
		(net 264)
	)
	(segment
		(start 164.900001 147.2775)
		(end 164.900001 148.9755)
		(width 0.148)
		(layer "In4.Cu")
		(net 264)
	)
	(segment
		(start 156.840302 165.487347)
		(end 156.840302 165.487348)
		(width 0.148)
		(layer "In4.Cu")
		(net 264)
	)
	(segment
		(start 159.247131 161.883774)
		(end 159.668727 162.30537)
		(width 0.148)
		(layer "In4.Cu")
		(net 264)
	)
	(segment
		(start 156.48675 165.487348)
		(end 156.48675 165.487347)
		(width 0.148)
		(layer "In4.Cu")
		(net 264)
	)
	(segment
		(start 157.832919 163.297985)
		(end 157.832919 163.297986)
		(width 0.148)
		(layer "In4.Cu")
		(net 264)
	)
	(segment
		(start 163.489767 157.641137)
		(end 163.489767 157.641138)
		(width 0.148)
		(layer "In4.Cu")
		(net 264)
	)
	(segment
		(start 162.143598 159.8305)
		(end 162.143598 159.830499)
		(width 0.148)
		(layer "In4.Cu")
		(net 264)
	)
	(segment
		(start 157.125813 164.005092)
		(end 157.547409 164.426688)
		(width 0.148)
		(layer "In4.Cu")
		(net 264)
	)
	(segment
		(start 160.375832 161.951817)
		(end 160.375832 161.951818)
		(width 0.148)
		(layer "In4.Cu")
		(net 264)
	)
	(segment
		(start 158.254514 164.073135)
		(end 158.254514 164.073136)
		(width 0.148)
		(layer "In4.Cu")
		(net 264)
	)
	(segment
		(start 162.850704 159.123393)
		(end 162.429108 158.701797)
		(width 0.148)
		(layer "In4.Cu")
		(net 264)
	)
	(segment
		(start 157.125813 164.005091)
		(end 157.125813 164.005092)
		(width 0.148)
		(layer "In4.Cu")
		(net 264)
	)
	(segment
		(start 157.125813 163.65154)
		(end 157.125813 163.651539)
		(width 0.148)
		(layer "In4.Cu")
		(net 264)
	)
	(segment
		(start 162.143598 159.830499)
		(end 161.722002 159.408903)
		(width 0.148)
		(layer "In4.Cu")
		(net 264)
	)
	(segment
		(start 152.625501 167.052)
		(end 151.875001 167.8025)
		(width 0.148)
		(layer "In4.Cu")
		(net 264)
	)
	(segment
		(start 161.082938 161.244711)
		(end 161.082938 161.244712)
		(width 0.148)
		(layer "In4.Cu")
		(net 264)
	)
	(segment
		(start 160.729386 161.244711)
		(end 160.30779 160.823115)
		(width 0.148)
		(layer "In4.Cu")
		(net 264)
	)
	(segment
		(start 155.39207 166.160434)
		(end 154.500501 167.052)
		(width 0.148)
		(layer "In4.Cu")
		(net 264)
	)
	(segment
		(start 159.954237 161.176668)
		(end 160.375833 161.598264)
		(width 0.148)
		(layer "In4.Cu")
		(net 264)
	)
	(segment
		(start 159.247131 161.883773)
		(end 159.247131 161.883774)
		(width 0.148)
		(layer "In4.Cu")
		(net 264)
	)
	(segment
		(start 164.196872 156.580479)
		(end 164.196873 156.580479)
		(width 0.148)
		(layer "In4.Cu")
		(net 264)
	)
	(segment
		(start 162.782661 158.348243)
		(end 162.782661 158.348244)
		(width 0.148)
		(layer "In4.Cu")
		(net 264)
	)
	(segment
		(start 164.264916 157.709181)
		(end 163.84332 157.287585)
		(width 0.148)
		(layer "In4.Cu")
		(net 264)
	)
	(segment
		(start 164.900001 148.9755)
		(end 165.625501 149.701)
		(width 0.148)
		(layer "In4.Cu")
		(net 264)
	)
	(segment
		(start 159.315174 162.658924)
		(end 159.315174 162.658923)
		(width 0.148)
		(layer "In4.Cu")
		(net 264)
	)
	(segment
		(start 154.500501 167.052)
		(end 152.625501 167.052)
		(width 0.148)
		(layer "In4.Cu")
		(net 264)
	)
	(segment
		(start 155.39207 166.160433)
		(end 155.39207 166.160434)
		(width 0.148)
		(layer "In4.Cu")
		(net 264)
	)
	(segment
		(start 158.608068 163.366029)
		(end 158.186472 162.944433)
		(width 0.148)
		(layer "In4.Cu")
		(net 264)
	)
	(segment
		(start 159.954237 160.823116)
		(end 159.954237 160.823115)
		(width 0.148)
		(layer "In4.Cu")
		(net 264)
	)
	(segment
		(start 162.49715 159.830499)
		(end 162.49715 159.8305)
		(width 0.148)
		(layer "In4.Cu")
		(net 264)
	)
	(segment
		(start 165.625501 149.701)
		(end 165.625501 155.927)
		(width 0.148)
		(layer "In4.Cu")
		(net 264)
	)
	(segment
		(start 157.193856 164.780242)
		(end 157.193856 164.780241)
		(width 0.148)
		(layer "In4.Cu")
		(net 264)
	)
	(segment
		(start 163.55781 158.416288)
		(end 163.55781 158.416287)
		(width 0.148)
		(layer "In4.Cu")
		(net 264)
	)
	(segment
		(start 159.315174 162.658923)
		(end 158.893578 162.237327)
		(width 0.148)
		(layer "In4.Cu")
		(net 264)
	)
	(segment
		(start 164.618468 157.709181)
		(end 164.618468 157.709182)
		(width 0.148)
		(layer "In4.Cu")
		(net 264)
	)
	(segment
		(start 163.204256 159.123393)
		(end 163.204256 159.123394)
		(width 0.148)
		(layer "In4.Cu")
		(net 264)
	)
	(segment
		(start 164.584447 156.6145)
		(end 164.550426 156.580479)
		(width 0.148)
		(layer "In4.Cu")
		(net 264)
	)
	(segment
		(start 164.196873 156.934031)
		(end 164.196873 156.934032)
		(width 0.148)
		(layer "In4.Cu")
		(net 264)
	)
	(segment
		(start 160.02228 161.951817)
		(end 159.600684 161.530221)
		(width 0.148)
		(layer "In4.Cu")
		(net 264)
	)
	(segment
		(start 163.489767 157.641138)
		(end 163.911363 158.062734)
		(width 0.148)
		(layer "In4.Cu")
		(net 264)
	)
	(segment
		(start 157.832919 163.297986)
		(end 158.254515 163.719582)
		(width 0.148)
		(layer "In4.Cu")
		(net 264)
	)
	(segment
		(start 156.48675 165.487347)
		(end 156.065154 165.065751)
		(width 0.148)
		(layer "In4.Cu")
		(net 264)
	)
	(arc
		(start 156.133196 166.194454)
		(mid 155.956421 166.267676)
		(end 155.779644 166.194454)
		(width 0.148)
		(layer "In4.Cu")
		(net 264)
	)
	(arc
		(start 157.479366 163.651539)
		(mid 157.302589 163.578316)
		(end 157.125813 163.65154)
		(width 0.148)
		(layer "In4.Cu")
		(net 264)
	)
	(arc
		(start 159.600684 161.530221)
		(mid 159.423907 161.456998)
		(end 159.247131 161.530222)
		(width 0.148)
		(layer "In4.Cu")
		(net 264)
	)
	(arc
		(start 162.429108 158.701797)
		(mid 162.252331 158.628574)
		(end 162.075555 158.701798)
		(width 0.148)
		(layer "In4.Cu")
		(net 264)
	)
	(arc
		(start 155.745624 166.160433)
		(mid 155.568847 166.08721)
		(end 155.39207 166.160433)
		(width 0.148)
		(layer "In4.Cu")
		(net 264)
	)
	(arc
		(start 163.489767 157.287585)
		(mid 163.416544 157.464361)
		(end 163.489767 157.641137)
		(width 0.148)
		(layer "In4.Cu")
		(net 264)
	)
	(arc
		(start 164.938001 156.6145)
		(mid 164.761224 156.687723)
		(end 164.584447 156.6145)
		(width 0.148)
		(layer "In4.Cu")
		(net 264)
	)
	(arc
		(start 158.961621 163.012476)
		(mid 159.034844 163.189253)
		(end 158.96162 163.366029)
		(width 0.148)
		(layer "In4.Cu")
		(net 264)
	)
	(arc
		(start 161.790044 160.537606)
		(mid 161.613269 160.610828)
		(end 161.436492 160.537606)
		(width 0.148)
		(layer "In4.Cu")
		(net 264)
	)
	(arc
		(start 158.540025 162.237327)
		(mid 158.466802 162.414103)
		(end 158.540025 162.590879)
		(width 0.148)
		(layer "In4.Cu")
		(net 264)
	)
	(arc
		(start 163.84332 157.287585)
		(mid 163.666543 157.214362)
		(end 163.489767 157.287586)
		(width 0.148)
		(layer "In4.Cu")
		(net 264)
	)
	(arc
		(start 157.547408 164.780242)
		(mid 157.370633 164.853464)
		(end 157.193856 164.780242)
		(width 0.148)
		(layer "In4.Cu")
		(net 264)
	)
	(arc
		(start 163.911363 158.062734)
		(mid 163.984586 158.239511)
		(end 163.911362 158.416287)
		(width 0.148)
		(layer "In4.Cu")
		(net 264)
	)
	(arc
		(start 159.954237 160.823115)
		(mid 159.881014 160.999891)
		(end 159.954237 161.176667)
		(width 0.148)
		(layer "In4.Cu")
		(net 264)
	)
	(arc
		(start 156.840303 165.133794)
		(mid 156.913526 165.310571)
		(end 156.840302 165.487347)
		(width 0.148)
		(layer "In4.Cu")
		(net 264)
	)
	(arc
		(start 156.840302 165.487348)
		(mid 156.663527 165.56057)
		(end 156.48675 165.487348)
		(width 0.148)
		(layer "In4.Cu")
		(net 264)
	)
	(arc
		(start 162.782661 157.994691)
		(mid 162.709438 158.171467)
		(end 162.782661 158.348243)
		(width 0.148)
		(layer "In4.Cu")
		(net 264)
	)
	(arc
		(start 156.065154 165.065751)
		(mid 155.888377 164.992528)
		(end 155.711601 165.065752)
		(width 0.148)
		(layer "In4.Cu")
		(net 264)
	)
	(arc
		(start 163.136214 157.994691)
		(mid 162.959437 157.921468)
		(end 162.782661 157.994692)
		(width 0.148)
		(layer "In4.Cu")
		(net 264)
	)
	(arc
		(start 162.49715 159.8305)
		(mid 162.320375 159.903722)
		(end 162.143598 159.8305)
		(width 0.148)
		(layer "In4.Cu")
		(net 264)
	)
	(arc
		(start 164.618469 157.355628)
		(mid 164.691692 157.532405)
		(end 164.618468 157.709181)
		(width 0.148)
		(layer "In4.Cu")
		(net 264)
	)
	(arc
		(start 162.497151 159.476946)
		(mid 162.570374 159.653723)
		(end 162.49715 159.830499)
		(width 0.148)
		(layer "In4.Cu")
		(net 264)
	)
	(arc
		(start 158.254515 163.719582)
		(mid 158.327738 163.896359)
		(end 158.254514 164.073135)
		(width 0.148)
		(layer "In4.Cu")
		(net 264)
	)
	(arc
		(start 160.30779 160.823115)
		(mid 160.131013 160.749892)
		(end 159.954237 160.823116)
		(width 0.148)
		(layer "In4.Cu")
		(net 264)
	)
	(arc
		(start 160.661343 160.116009)
		(mid 160.58812 160.292785)
		(end 160.661343 160.469561)
		(width 0.148)
		(layer "In4.Cu")
		(net 264)
	)
	(arc
		(start 164.550426 156.580479)
		(mid 164.373649 156.507256)
		(end 164.196872 156.580479)
		(width 0.148)
		(layer "In4.Cu")
		(net 264)
	)
	(arc
		(start 158.186472 162.944433)
		(mid 158.009695 162.87121)
		(end 157.832919 162.944434)
		(width 0.148)
		(layer "In4.Cu")
		(net 264)
	)
	(arc
		(start 157.125813 163.651539)
		(mid 157.05259 163.828315)
		(end 157.125813 164.005091)
		(width 0.148)
		(layer "In4.Cu")
		(net 264)
	)
	(arc
		(start 161.082939 160.891158)
		(mid 161.156162 161.067935)
		(end 161.082938 161.244711)
		(width 0.148)
		(layer "In4.Cu")
		(net 264)
	)
	(arc
		(start 156.418707 164.358645)
		(mid 156.345484 164.535421)
		(end 156.418707 164.712197)
		(width 0.148)
		(layer "In4.Cu")
		(net 264)
	)
	(arc
		(start 158.254514 164.073136)
		(mid 158.077739 164.146358)
		(end 157.900962 164.073136)
		(width 0.148)
		(layer "In4.Cu")
		(net 264)
	)
	(arc
		(start 159.668727 162.30537)
		(mid 159.74195 162.482147)
		(end 159.668726 162.658923)
		(width 0.148)
		(layer "In4.Cu")
		(net 264)
	)
	(arc
		(start 163.204256 159.123394)
		(mid 163.027481 159.196616)
		(end 162.850704 159.123394)
		(width 0.148)
		(layer "In4.Cu")
		(net 264)
	)
	(arc
		(start 158.893578 162.237327)
		(mid 158.716801 162.164104)
		(end 158.540025 162.237328)
		(width 0.148)
		(layer "In4.Cu")
		(net 264)
	)
	(arc
		(start 161.082938 161.244712)
		(mid 160.906163 161.317934)
		(end 160.729386 161.244712)
		(width 0.148)
		(layer "In4.Cu")
		(net 264)
	)
	(arc
		(start 161.790045 160.184052)
		(mid 161.863268 160.360829)
		(end 161.790044 160.537605)
		(width 0.148)
		(layer "In4.Cu")
		(net 264)
	)
	(arc
		(start 159.247131 161.530221)
		(mid 159.173908 161.706997)
		(end 159.247131 161.883773)
		(width 0.148)
		(layer "In4.Cu")
		(net 264)
	)
	(arc
		(start 163.911362 158.416288)
		(mid 163.734587 158.48951)
		(end 163.55781 158.416288)
		(width 0.148)
		(layer "In4.Cu")
		(net 264)
	)
	(arc
		(start 164.196873 156.580479)
		(mid 164.12365 156.757255)
		(end 164.196873 156.934031)
		(width 0.148)
		(layer "In4.Cu")
		(net 264)
	)
	(arc
		(start 155.711601 165.065751)
		(mid 155.638378 165.242527)
		(end 155.711601 165.419303)
		(width 0.148)
		(layer "In4.Cu")
		(net 264)
	)
	(arc
		(start 163.204257 158.76984)
		(mid 163.27748 158.946617)
		(end 163.204256 159.123393)
		(width 0.148)
		(layer "In4.Cu")
		(net 264)
	)
	(arc
		(start 158.96162 163.36603)
		(mid 158.784845 163.439252)
		(end 158.608068 163.36603)
		(width 0.148)
		(layer "In4.Cu")
		(net 264)
	)
	(arc
		(start 161.722002 159.408903)
		(mid 161.545225 159.33568)
		(end 161.368449 159.408904)
		(width 0.148)
		(layer "In4.Cu")
		(net 264)
	)
	(arc
		(start 160.375832 161.951818)
		(mid 160.199057 162.02504)
		(end 160.02228 161.951818)
		(width 0.148)
		(layer "In4.Cu")
		(net 264)
	)
	(arc
		(start 157.832919 162.944433)
		(mid 157.759696 163.121209)
		(end 157.832919 163.297985)
		(width 0.148)
		(layer "In4.Cu")
		(net 264)
	)
	(arc
		(start 156.77226 164.358645)
		(mid 156.595483 164.285422)
		(end 156.418707 164.358646)
		(width 0.148)
		(layer "In4.Cu")
		(net 264)
	)
	(arc
		(start 164.618468 157.709182)
		(mid 164.441693 157.782404)
		(end 164.264916 157.709182)
		(width 0.148)
		(layer "In4.Cu")
		(net 264)
	)
	(arc
		(start 161.014896 160.116009)
		(mid 160.838119 160.042786)
		(end 160.661343 160.11601)
		(width 0.148)
		(layer "In4.Cu")
		(net 264)
	)
	(arc
		(start 161.368449 159.408903)
		(mid 161.295226 159.585679)
		(end 161.368449 159.762455)
		(width 0.148)
		(layer "In4.Cu")
		(net 264)
	)
	(arc
		(start 160.375833 161.598264)
		(mid 160.449056 161.775041)
		(end 160.375832 161.951817)
		(width 0.148)
		(layer "In4.Cu")
		(net 264)
	)
	(arc
		(start 157.547409 164.426688)
		(mid 157.620632 164.603465)
		(end 157.547408 164.780241)
		(width 0.148)
		(layer "In4.Cu")
		(net 264)
	)
	(arc
		(start 162.075555 158.701797)
		(mid 162.002332 158.878573)
		(end 162.075555 159.055349)
		(width 0.148)
		(layer "In4.Cu")
		(net 264)
	)
	(arc
		(start 159.668726 162.658924)
		(mid 159.491951 162.732146)
		(end 159.315174 162.658924)
		(width 0.148)
		(layer "In4.Cu")
		(net 264)
	)
	(arc
		(start 156.133197 165.8409)
		(mid 156.20642 166.017677)
		(end 156.133196 166.194453)
		(width 0.148)
		(layer "In4.Cu")
		(net 264)
	)
	(segment
		(start 165.17 139.892427)
		(end 165.125001 139.937426)
		(width 0.26)
		(layer "F.Cu")
		(net 265)
	)
	(segment
		(start 165.170001 139.4225)
		(end 165.17 139.892427)
		(width 0.26)
		(layer "F.Cu")
		(net 265)
	)
	(segment
		(start 165.150001 138.8025)
		(end 165.150001 139.4025)
		(width 0.26)
		(layer "F.Cu")
		(net 265)
	)
	(segment
		(start 165.150001 139.4025)
		(end 165.170001 139.4225)
		(width 0.26)
		(layer "F.Cu")
		(net 265)
	)
	(segment
		(start 151.375501 165.302)
		(end 151.875001 164.8025)
		(width 0.256)
		(layer "F.Cu")
		(net 265)
	)
	(via
		(at 165.125001 139.937426)
		(size 0.45)
		(drill 0.1)
		(layers "F.Cu" "B.Cu")
		(net 265)
	)
	(via
		(at 151.875001 164.8025)
		(size 0.45)
		(drill 0.1)
		(layers "F.Cu" "B.Cu")
		(net 265)
	)
	(segment
		(start 157.855858 161.071644)
		(end 157.558936 160.774719)
		(width 0.13)
		(layer "In4.Cu")
		(net 265)
	)
	(segment
		(start 160.132684 159.388663)
		(end 160.132683 159.388663)
		(width 0.13)
		(layer "In4.Cu")
		(net 265)
	)
	(segment
		(start 157.091997 162.683786)
		(end 157.091997 162.683787)
		(width 0.13)
		(layer "In4.Cu")
		(net 265)
	)
	(segment
		(start 157.162831 162.358516)
		(end 157.16283 162.358516)
		(width 0.13)
		(layer "In4.Cu")
		(net 265)
	)
	(segment
		(start 155.253763 163.079893)
		(end 155.847609 163.673738)
		(width 0.13)
		(layer "In4.Cu")
		(net 265)
	)
	(segment
		(start 155.253762 163.079893)
		(end 155.253763 163.079893)
		(width 0.13)
		(layer "In4.Cu")
		(net 265)
	)
	(segment
		(start 154.772744 164.578897)
		(end 154.857596 164.663749)
		(width 0.13)
		(layer "In4.Cu")
		(net 265)
	)
	(segment
		(start 158.223616 160.11004)
		(end 158.817462 160.703885)
		(width 0.13)
		(layer "In4.Cu")
		(net 265)
	)
	(segment
		(start 151.875001 165.1005)
		(end 151.957001 165.1825)
		(width 0.13)
		(layer "In4.Cu")
		(net 265)
	)
	(segment
		(start 156.102046 163.673737)
		(end 156.102046 163.673738)
		(width 0.13)
		(layer "In4.Cu")
		(net 265)
	)
	(segment
		(start 158.548888 159.190922)
		(end 158.619721 159.12009)
		(width 0.13)
		(layer "In4.Cu")
		(net 265)
	)
	(segment
		(start 160.203518 158.130138)
		(end 160.797364 158.723983)
		(width 0.13)
		(layer "In4.Cu")
		(net 265)
	)
	(segment
		(start 158.081948 161.693835)
		(end 158.081948 161.693836)
		(width 0.13)
		(layer "In4.Cu")
		(net 265)
	)
	(segment
		(start 155.579035 162.160775)
		(end 155.649868 162.089943)
		(width 0.13)
		(layer "In4.Cu")
		(net 265)
	)
	(segment
		(start 160.825711 158.101791)
		(end 160.528789 157.804866)
		(width 0.13)
		(layer "In4.Cu")
		(net 265)
	)
	(segment
		(start 157.558937 160.180874)
		(end 157.558937 160.180873)
		(width 0.13)
		(layer "In4.Cu")
		(net 265)
	)
	(segment
		(start 158.152781 161.368565)
		(end 157.855858 161.071644)
		(width 0.13)
		(layer "In4.Cu")
		(net 265)
	)
	(segment
		(start 161.532759 157.225041)
		(end 161.532758 157.225041)
		(width 0.13)
		(layer "In4.Cu")
		(net 265)
	)
	(segment
		(start 158.845809 160.081693)
		(end 158.548887 159.784768)
		(width 0.13)
		(layer "In4.Cu")
		(net 265)
	)
	(segment
		(start 161.193469 157.140187)
		(end 161.278322 157.22504)
		(width 0.13)
		(layer "In4.Cu")
		(net 265)
	)
	(segment
		(start 160.06185 159.713934)
		(end 160.132683 159.6431)
		(width 0.13)
		(layer "In4.Cu")
		(net 265)
	)
	(segment
		(start 161.532758 157.225041)
		(end 164.280001 154.477794)
		(width 0.13)
		(layer "In4.Cu")
		(net 265)
	)
	(segment
		(start 155.112033 164.66375)
		(end 155.112033 164.663749)
		(width 0.13)
		(layer "In4.Cu")
		(net 265)
	)
	(segment
		(start 154.589084 163.150727)
		(end 154.589084 163.150726)
		(width 0.13)
		(layer "In4.Cu")
		(net 265)
	)
	(segment
		(start 154.886005 164.041497)
		(end 154.589083 163.744572)
		(width 0.13)
		(layer "In4.Cu")
		(net 265)
	)
	(segment
		(start 159.142733 160.378614)
		(end 159.142732 160.378614)
		(width 0.13)
		(layer "In4.Cu")
		(net 265)
	)
	(segment
		(start 157.091997 162.683787)
		(end 157.16283 162.612953)
		(width 0.13)
		(layer "In4.Cu")
		(net 265)
	)
	(segment
		(start 159.071899 160.703885)
		(end 159.142732 160.633051)
		(width 0.13)
		(layer "In4.Cu")
		(net 265)
	)
	(segment
		(start 164.280001 154.477794)
		(end 164.280001 149.1775)
		(width 0.13)
		(layer "In4.Cu")
		(net 265)
	)
	(segment
		(start 160.132683 159.388663)
		(end 159.83576 159.091742)
		(width 0.13)
		(layer "In4.Cu")
		(net 265)
	)
	(segment
		(start 160.52879 157.21102)
		(end 160.599623 157.140188)
		(width 0.13)
		(layer "In4.Cu")
		(net 265)
	)
	(segment
		(start 154.885942 164.041554)
		(end 154.886005 164.041497)
		(width 0.13)
		(layer "In4.Cu")
		(net 265)
	)
	(segment
		(start 161.051801 158.723983)
		(end 161.122634 158.653149)
		(width 0.13)
		(layer "In4.Cu")
		(net 265)
	)
	(segment
		(start 155.112033 164.663749)
		(end 155.182866 164.592915)
		(width 0.13)
		(layer "In4.Cu")
		(net 265)
	)
	(segment
		(start 156.865907 162.061595)
		(end 156.568985 161.76467)
		(width 0.13)
		(layer "In4.Cu")
		(net 265)
	)
	(segment
		(start 161.051801 158.723982)
		(end 161.051801 158.723983)
		(width 0.13)
		(layer "In4.Cu")
		(net 265)
	)
	(segment
		(start 159.538839 158.200971)
		(end 159.609672 158.130139)
		(width 0.13)
		(layer "In4.Cu")
		(net 265)
	)
	(segment
		(start 156.243713 162.089942)
		(end 156.243714 162.089942)
		(width 0.13)
		(layer "In4.Cu")
		(net 265)
	)
	(segment
		(start 154.589084 163.150726)
		(end 154.659917 163.079894)
		(width 0.13)
		(layer "In4.Cu")
		(net 265)
	)
	(segment
		(start 161.122635 158.398712)
		(end 161.122634 158.398712)
		(width 0.13)
		(layer "In4.Cu")
		(net 265)
	)
	(segment
		(start 165.300001 142.236078)
		(end 164.800001 142.736078)
		(width 0.1)
		(layer "In4.Cu")
		(net 265)
	)
	(segment
		(start 164.800001 145.986078)
		(end 164.300001 146.486078)
		(width 0.1)
		(layer "In4.Cu")
		(net 265)
	)
	(segment
		(start 159.538839 158.200972)
		(end 159.538839 158.200971)
		(width 0.13)
		(layer "In4.Cu")
		(net 265)
	)
	(segment
		(start 155.875956 163.051546)
		(end 155.579034 162.754621)
		(width 0.13)
		(layer "In4.Cu")
		(net 265)
	)
	(segment
		(start 151.957001 165.1825)
		(end 153.575295 165.1825)
		(width 0.13)
		(layer "In4.Cu")
		(net 265)
	)
	(segment
		(start 159.213566 159.120089)
		(end 159.213567 159.120089)
		(width 0.13)
		(layer "In4.Cu")
		(net 265)
	)
	(segment
		(start 158.548888 159.190923)
		(end 158.548888 159.190922)
		(width 0.13)
		(layer "In4.Cu")
		(net 265)
	)
	(segment
		(start 156.568986 161.170824)
		(end 156.639819 161.099992)
		(width 0.13)
		(layer "In4.Cu")
		(net 265)
	)
	(segment
		(start 158.223615 160.11004)
		(end 158.223616 160.11004)
		(width 0.13)
		(layer "In4.Cu")
		(net 265)
	)
	(segment
		(start 164.300001 146.486078)
		(end 164.300001 149.1575)
		(width 0.1)
		(layer "In4.Cu")
		(net 265)
	)
	(segment
		(start 160.203517 158.130138)
		(end 160.203518 158.130138)
		(width 0.13)
		(layer "In4.Cu")
		(net 265)
	)
	(segment
		(start 164.800001 142.736078)
		(end 164.800001 145.986078)
		(width 0.1)
		(layer "In4.Cu")
		(net 265)
	)
	(segment
		(start 165.125001 139.937426)
		(end 165.300001 140.112426)
		(width 0.1)
		(layer "In4.Cu")
		(net 265)
	)
	(segment
		(start 159.071899 160.703884)
		(end 159.071899 160.703885)
		(width 0.13)
		(layer "In4.Cu")
		(net 265)
	)
	(segment
		(start 153.575295 165.1825)
		(end 154.178898 164.578897)
		(width 0.13)
		(layer "In4.Cu")
		(net 265)
	)
	(segment
		(start 158.152782 161.368565)
		(end 158.152781 161.368565)
		(width 0.13)
		(layer "In4.Cu")
		(net 265)
	)
	(segment
		(start 151.875001 164.8025)
		(end 151.875001 165.1005)
		(width 0.13)
		(layer "In4.Cu")
		(net 265)
	)
	(segment
		(start 164.300001 149.1575)
		(end 164.280001 149.1775)
		(width 0.1)
		(layer "In4.Cu")
		(net 265)
	)
	(segment
		(start 156.243714 162.089942)
		(end 156.83756 162.683787)
		(width 0.13)
		(layer "In4.Cu")
		(net 265)
	)
	(segment
		(start 157.233664 161.099991)
		(end 157.233665 161.099991)
		(width 0.13)
		(layer "In4.Cu")
		(net 265)
	)
	(segment
		(start 161.193468 157.140187)
		(end 161.193469 157.140187)
		(width 0.13)
		(layer "In4.Cu")
		(net 265)
	)
	(segment
		(start 159.142732 160.378614)
		(end 158.845809 160.081693)
		(width 0.13)
		(layer "In4.Cu")
		(net 265)
	)
	(segment
		(start 159.213567 159.120089)
		(end 159.807413 159.713934)
		(width 0.13)
		(layer "In4.Cu")
		(net 265)
	)
	(segment
		(start 160.06185 159.713933)
		(end 160.06185 159.713934)
		(width 0.13)
		(layer "In4.Cu")
		(net 265)
	)
	(segment
		(start 165.300001 140.112426)
		(end 165.300001 142.236078)
		(width 0.1)
		(layer "In4.Cu")
		(net 265)
	)
	(segment
		(start 155.182866 164.338478)
		(end 154.885942 164.041554)
		(width 0.13)
		(layer "In4.Cu")
		(net 265)
	)
	(segment
		(start 156.102046 163.673738)
		(end 156.172879 163.602904)
		(width 0.13)
		(layer "In4.Cu")
		(net 265)
	)
	(segment
		(start 157.16283 162.358516)
		(end 156.865907 162.061595)
		(width 0.13)
		(layer "In4.Cu")
		(net 265)
	)
	(segment
		(start 156.568986 161.170825)
		(end 156.568986 161.170824)
		(width 0.13)
		(layer "In4.Cu")
		(net 265)
	)
	(segment
		(start 157.558937 160.180873)
		(end 157.62977 160.110041)
		(width 0.13)
		(layer "In4.Cu")
		(net 265)
	)
	(segment
		(start 159.83576 159.091742)
		(end 159.538838 158.794817)
		(width 0.13)
		(layer "In4.Cu")
		(net 265)
	)
	(segment
		(start 161.122634 158.398712)
		(end 160.825711 158.101791)
		(width 0.13)
		(layer "In4.Cu")
		(net 265)
	)
	(segment
		(start 158.081948 161.693836)
		(end 158.152781 161.623002)
		(width 0.13)
		(layer "In4.Cu")
		(net 265)
	)
	(segment
		(start 155.579035 162.160776)
		(end 155.579035 162.160775)
		(width 0.13)
		(layer "In4.Cu")
		(net 265)
	)
	(segment
		(start 160.52879 157.211021)
		(end 160.52879 157.21102)
		(width 0.13)
		(layer "In4.Cu")
		(net 265)
	)
	(segment
		(start 155.182867 164.338478)
		(end 155.182866 164.338478)
		(width 0.13)
		(layer "In4.Cu")
		(net 265)
	)
	(segment
		(start 157.233665 161.099991)
		(end 157.827511 161.693836)
		(width 0.13)
		(layer "In4.Cu")
		(net 265)
	)
	(segment
		(start 156.172879 163.348467)
		(end 155.875956 163.051546)
		(width 0.13)
		(layer "In4.Cu")
		(net 265)
	)
	(segment
		(start 156.17288 163.348467)
		(end 156.172879 163.348467)
		(width 0.13)
		(layer "In4.Cu")
		(net 265)
	)
	(arc
		(start 155.182866 164.592915)
		(mid 155.235562 164.465697)
		(end 155.182867 164.338478)
		(width 0.13)
		(layer "In4.Cu")
		(net 265)
	)
	(arc
		(start 157.558936 160.774719)
		(mid 157.435947 160.477796)
		(end 157.558937 160.180874)
		(width 0.13)
		(layer "In4.Cu")
		(net 265)
	)
	(arc
		(start 157.16283 162.612953)
		(mid 157.215526 162.485735)
		(end 157.162831 162.358516)
		(width 0.13)
		(layer "In4.Cu")
		(net 265)
	)
	(arc
		(start 158.619721 159.12009)
		(mid 158.916643 158.9971)
		(end 159.213566 159.120089)
		(width 0.13)
		(layer "In4.Cu")
		(net 265)
	)
	(arc
		(start 160.599623 157.140188)
		(mid 160.896545 157.017198)
		(end 161.193468 157.140187)
		(width 0.13)
		(layer "In4.Cu")
		(net 265)
	)
	(arc
		(start 160.132683 159.6431)
		(mid 160.185379 159.515882)
		(end 160.132684 159.388663)
		(width 0.13)
		(layer "In4.Cu")
		(net 265)
	)
	(arc
		(start 154.857596 164.663749)
		(mid 154.984814 164.716445)
		(end 155.112033 164.66375)
		(width 0.13)
		(layer "In4.Cu")
		(net 265)
	)
	(arc
		(start 156.83756 162.683787)
		(mid 156.964779 162.736482)
		(end 157.091997 162.683786)
		(width 0.13)
		(layer "In4.Cu")
		(net 265)
	)
	(arc
		(start 160.528789 157.804866)
		(mid 160.4058 157.507943)
		(end 160.52879 157.211021)
		(width 0.13)
		(layer "In4.Cu")
		(net 265)
	)
	(arc
		(start 155.579034 162.754621)
		(mid 155.456045 162.457698)
		(end 155.579035 162.160776)
		(width 0.13)
		(layer "In4.Cu")
		(net 265)
	)
	(arc
		(start 157.62977 160.110041)
		(mid 157.926692 159.987051)
		(end 158.223615 160.11004)
		(width 0.13)
		(layer "In4.Cu")
		(net 265)
	)
	(arc
		(start 154.178898 164.578897)
		(mid 154.475821 164.455907)
		(end 154.772744 164.578897)
		(width 0.13)
		(layer "In4.Cu")
		(net 265)
	)
	(arc
		(start 157.827511 161.693836)
		(mid 157.95473 161.746531)
		(end 158.081948 161.693835)
		(width 0.13)
		(layer "In4.Cu")
		(net 265)
	)
	(arc
		(start 161.122634 158.653149)
		(mid 161.17533 158.525931)
		(end 161.122635 158.398712)
		(width 0.13)
		(layer "In4.Cu")
		(net 265)
	)
	(arc
		(start 155.847609 163.673738)
		(mid 155.974828 163.726433)
		(end 156.102046 163.673737)
		(width 0.13)
		(layer "In4.Cu")
		(net 265)
	)
	(arc
		(start 156.639819 161.099992)
		(mid 156.936741 160.977002)
		(end 157.233664 161.099991)
		(width 0.13)
		(layer "In4.Cu")
		(net 265)
	)
	(arc
		(start 160.797364 158.723983)
		(mid 160.924583 158.776678)
		(end 161.051801 158.723982)
		(width 0.13)
		(layer "In4.Cu")
		(net 265)
	)
	(arc
		(start 155.649868 162.089943)
		(mid 155.94679 161.966953)
		(end 156.243713 162.089942)
		(width 0.13)
		(layer "In4.Cu")
		(net 265)
	)
	(arc
		(start 158.548887 159.784768)
		(mid 158.425898 159.487845)
		(end 158.548888 159.190923)
		(width 0.13)
		(layer "In4.Cu")
		(net 265)
	)
	(arc
		(start 159.807413 159.713934)
		(mid 159.934632 159.766629)
		(end 160.06185 159.713933)
		(width 0.13)
		(layer "In4.Cu")
		(net 265)
	)
	(arc
		(start 154.589083 163.744572)
		(mid 154.466094 163.447649)
		(end 154.589084 163.150727)
		(width 0.13)
		(layer "In4.Cu")
		(net 265)
	)
	(arc
		(start 161.278322 157.22504)
		(mid 161.40554 157.277736)
		(end 161.532759 157.225041)
		(width 0.13)
		(layer "In4.Cu")
		(net 265)
	)
	(arc
		(start 156.568985 161.76467)
		(mid 156.445996 161.467747)
		(end 156.568986 161.170825)
		(width 0.13)
		(layer "In4.Cu")
		(net 265)
	)
	(arc
		(start 158.152781 161.623002)
		(mid 158.205477 161.495784)
		(end 158.152782 161.368565)
		(width 0.13)
		(layer "In4.Cu")
		(net 265)
	)
	(arc
		(start 158.817462 160.703885)
		(mid 158.944681 160.75658)
		(end 159.071899 160.703884)
		(width 0.13)
		(layer "In4.Cu")
		(net 265)
	)
	(arc
		(start 156.172879 163.602904)
		(mid 156.225575 163.475686)
		(end 156.17288 163.348467)
		(width 0.13)
		(layer "In4.Cu")
		(net 265)
	)
	(arc
		(start 159.142732 160.633051)
		(mid 159.195428 160.505833)
		(end 159.142733 160.378614)
		(width 0.13)
		(layer "In4.Cu")
		(net 265)
	)
	(arc
		(start 154.659917 163.079894)
		(mid 154.956839 162.956904)
		(end 155.253762 163.079893)
		(width 0.13)
		(layer "In4.Cu")
		(net 265)
	)
	(arc
		(start 159.609672 158.130139)
		(mid 159.906594 158.007149)
		(end 160.203517 158.130138)
		(width 0.13)
		(layer "In4.Cu")
		(net 265)
	)
	(arc
		(start 159.538838 158.794817)
		(mid 159.415849 158.497894)
		(end 159.538839 158.200972)
		(width 0.13)
		(layer "In4.Cu")
		(net 265)
	)
	(segment
		(start 165.650001 138.8025)
		(end 165.650001 139.4025)
		(width 0.26)
		(layer "F.Cu")
		(net 266)
	)
	(segment
		(start 151.375501 166.302)
		(end 151.875001 165.8025)
		(width 0.256)
		(layer "F.Cu")
		(net 266)
	)
	(segment
		(start 165.630001 139.4225)
		(end 165.630002 139.892427)
		(width 0.26)
		(layer "F.Cu")
		(net 266)
	)
	(segment
		(start 165.650001 139.4025)
		(end 165.630001 139.4225)
		(width 0.26)
		(layer "F.Cu")
		(net 266)
	)
	(segment
		(start 165.630002 139.892427)
		(end 165.675001 139.937426)
		(width 0.26)
		(layer "F.Cu")
		(net 266)
	)
	(via
		(at 151.875001 165.8025)
		(size 0.45)
		(drill 0.1)
		(layers "F.Cu" "B.Cu")
		(net 266)
	)
	(via
		(at 165.675001 139.937426)
		(size 0.45)
		(drill 0.1)
		(layers "F.Cu" "B.Cu")
		(net 266)
	)
	(segment
		(start 160.033814 158.299842)
		(end 160.62766 158.893687)
		(width 0.13)
		(layer "In4.Cu")
		(net 266)
	)
	(segment
		(start 160.995414 157.932084)
		(end 160.995418 157.932084)
		(width 0.13)
		(layer "In4.Cu")
		(net 266)
	)
	(segment
		(start 155.055646 163.871851)
		(end 155.055712 163.87179)
		(width 0.13)
		(layer "In4.Cu")
		(net 266)
	)
	(segment
		(start 153.674707 165.4225)
		(end 154.348603 164.748602)
		(width 0.13)
		(layer "In4.Cu")
		(net 266)
	)
	(segment
		(start 156.07401 162.259646)
		(end 156.667856 162.853491)
		(width 0.13)
		(layer "In4.Cu")
		(net 266)
	)
	(segment
		(start 155.055712 163.87179)
		(end 154.758787 163.574868)
		(width 0.13)
		(layer "In4.Cu")
		(net 266)
	)
	(segment
		(start 165.000001 146.068922)
		(end 164.500001 146.568922)
		(width 0.1)
		(layer "In4.Cu")
		(net 266)
	)
	(segment
		(start 159.043862 159.289793)
		(end 159.043863 159.289793)
		(width 0.13)
		(layer "In4.Cu")
		(net 266)
	)
	(segment
		(start 164.520001 154.577206)
		(end 164.520001 149.1775)
		(width 0.13)
		(layer "In4.Cu")
		(net 266)
	)
	(segment
		(start 157.728641 160.350578)
		(end 157.728641 160.350577)
		(width 0.13)
		(layer "In4.Cu")
		(net 266)
	)
	(segment
		(start 155.748739 162.330479)
		(end 155.819572 162.259647)
		(width 0.13)
		(layer "In4.Cu")
		(net 266)
	)
	(segment
		(start 157.332535 162.188812)
		(end 157.332534 162.188812)
		(width 0.13)
		(layer "In4.Cu")
		(net 266)
	)
	(segment
		(start 158.322486 161.198861)
		(end 158.322485 161.198861)
		(width 0.13)
		(layer "In4.Cu")
		(net 266)
	)
	(segment
		(start 158.053912 160.279744)
		(end 158.647758 160.873589)
		(width 0.13)
		(layer "In4.Cu")
		(net 266)
	)
	(segment
		(start 156.074009 162.259646)
		(end 156.07401 162.259646)
		(width 0.13)
		(layer "In4.Cu")
		(net 266)
	)
	(segment
		(start 159.043863 159.289793)
		(end 159.637709 159.883638)
		(width 0.13)
		(layer "In4.Cu")
		(net 266)
	)
	(segment
		(start 155.35257 164.168775)
		(end 155.055646 163.871851)
		(width 0.13)
		(layer "In4.Cu")
		(net 266)
	)
	(segment
		(start 159.708543 158.370676)
		(end 159.708543 158.370675)
		(width 0.13)
		(layer "In4.Cu")
		(net 266)
	)
	(segment
		(start 154.758788 163.32043)
		(end 154.829621 163.249598)
		(width 0.13)
		(layer "In4.Cu")
		(net 266)
	)
	(segment
		(start 160.995418 157.932084)
		(end 160.698493 157.635162)
		(width 0.13)
		(layer "In4.Cu")
		(net 266)
	)
	(segment
		(start 156.342583 163.178763)
		(end 156.045659 162.881839)
		(width 0.13)
		(layer "In4.Cu")
		(net 266)
	)
	(segment
		(start 151.875001 165.5015)
		(end 151.954001 165.4225)
		(width 0.13)
		(layer "In4.Cu")
		(net 266)
	)
	(segment
		(start 157.03561 161.891888)
		(end 157.035614 161.891888)
		(width 0.13)
		(layer "In4.Cu")
		(net 266)
	)
	(segment
		(start 157.261701 162.85349)
		(end 157.261701 162.853491)
		(width 0.13)
		(layer "In4.Cu")
		(net 266)
	)
	(segment
		(start 154.603039 164.748602)
		(end 154.687891 164.833454)
		(width 0.13)
		(layer "In4.Cu")
		(net 266)
	)
	(segment
		(start 156.045663 162.881839)
		(end 155.748738 162.584917)
		(width 0.13)
		(layer "In4.Cu")
		(net 266)
	)
	(segment
		(start 156.73869 161.340528)
		(end 156.809523 161.269696)
		(width 0.13)
		(layer "In4.Cu")
		(net 266)
	)
	(segment
		(start 155.084058 163.249597)
		(end 155.084059 163.249597)
		(width 0.13)
		(layer "In4.Cu")
		(net 266)
	)
	(segment
		(start 155.281736 164.833455)
		(end 155.281737 164.833454)
		(width 0.13)
		(layer "In4.Cu")
		(net 266)
	)
	(segment
		(start 156.27175 163.843442)
		(end 156.342583 163.772608)
		(width 0.13)
		(layer "In4.Cu")
		(net 266)
	)
	(segment
		(start 155.281737 164.833454)
		(end 155.35257 164.76262)
		(width 0.13)
		(layer "In4.Cu")
		(net 266)
	)
	(segment
		(start 151.875001 165.8025)
		(end 151.875001 165.5015)
		(width 0.13)
		(layer "In4.Cu")
		(net 266)
	)
	(segment
		(start 159.015512 159.911986)
		(end 159.015516 159.911986)
		(width 0.13)
		(layer "In4.Cu")
		(net 266)
	)
	(segment
		(start 164.500001 149.1575)
		(end 164.520001 149.1775)
		(width 0.1)
		(layer "In4.Cu")
		(net 266)
	)
	(segment
		(start 160.302388 159.218959)
		(end 160.302387 159.218959)
		(width 0.13)
		(layer "In4.Cu")
		(net 266)
	)
	(segment
		(start 157.06396 161.269695)
		(end 157.063961 161.269695)
		(width 0.13)
		(layer "In4.Cu")
		(net 266)
	)
	(segment
		(start 160.302387 159.218959)
		(end 160.005463 158.922035)
		(width 0.13)
		(layer "In4.Cu")
		(net 266)
	)
	(segment
		(start 160.231554 159.883637)
		(end 160.231554 159.883638)
		(width 0.13)
		(layer "In4.Cu")
		(net 266)
	)
	(segment
		(start 158.718592 159.360626)
		(end 158.789425 159.289794)
		(width 0.13)
		(layer "In4.Cu")
		(net 266)
	)
	(segment
		(start 158.025565 160.901937)
		(end 157.72864 160.605015)
		(width 0.13)
		(layer "In4.Cu")
		(net 266)
	)
	(segment
		(start 165.500001 140.112426)
		(end 165.500001 142.318922)
		(width 0.1)
		(layer "In4.Cu")
		(net 266)
	)
	(segment
		(start 157.261701 162.853491)
		(end 157.332534 162.782657)
		(width 0.13)
		(layer "In4.Cu")
		(net 266)
	)
	(segment
		(start 156.045659 162.881839)
		(end 156.045663 162.881839)
		(width 0.13)
		(layer "In4.Cu")
		(net 266)
	)
	(segment
		(start 158.251652 161.86354)
		(end 158.322485 161.792706)
		(width 0.13)
		(layer "In4.Cu")
		(net 266)
	)
	(segment
		(start 165.500001 142.318922)
		(end 165.000001 142.818922)
		(width 0.1)
		(layer "In4.Cu")
		(net 266)
	)
	(segment
		(start 160.005467 158.922035)
		(end 159.708542 158.625113)
		(width 0.13)
		(layer "In4.Cu")
		(net 266)
	)
	(segment
		(start 161.702463 157.394745)
		(end 161.702464 157.394744)
		(width 0.13)
		(layer "In4.Cu")
		(net 266)
	)
	(segment
		(start 161.023764 157.309891)
		(end 161.023765 157.309891)
		(width 0.13)
		(layer "In4.Cu")
		(net 266)
	)
	(segment
		(start 155.748739 162.33048)
		(end 155.748739 162.330479)
		(width 0.13)
		(layer "In4.Cu")
		(net 266)
	)
	(segment
		(start 158.251652 161.863539)
		(end 158.251652 161.86354)
		(width 0.13)
		(layer "In4.Cu")
		(net 266)
	)
	(segment
		(start 158.025561 160.901937)
		(end 158.025565 160.901937)
		(width 0.13)
		(layer "In4.Cu")
		(net 266)
	)
	(segment
		(start 157.035614 161.891888)
		(end 156.738689 161.594966)
		(width 0.13)
		(layer "In4.Cu")
		(net 266)
	)
	(segment
		(start 160.033813 158.299842)
		(end 160.033814 158.299842)
		(width 0.13)
		(layer "In4.Cu")
		(net 266)
	)
	(segment
		(start 156.73869 161.340529)
		(end 156.73869 161.340528)
		(width 0.13)
		(layer "In4.Cu")
		(net 266)
	)
	(segment
		(start 161.221505 158.893687)
		(end 161.292338 158.822853)
		(width 0.13)
		(layer "In4.Cu")
		(net 266)
	)
	(segment
		(start 161.023765 157.309891)
		(end 161.108618 157.394744)
		(width 0.13)
		(layer "In4.Cu")
		(net 266)
	)
	(segment
		(start 154.758788 163.320431)
		(end 154.758788 163.32043)
		(width 0.13)
		(layer "In4.Cu")
		(net 266)
	)
	(segment
		(start 157.332534 162.188812)
		(end 157.03561 161.891888)
		(width 0.13)
		(layer "In4.Cu")
		(net 266)
	)
	(segment
		(start 160.231554 159.883638)
		(end 160.302387 159.812804)
		(width 0.13)
		(layer "In4.Cu")
		(net 266)
	)
	(segment
		(start 161.702464 157.394744)
		(end 164.520001 154.577206)
		(width 0.13)
		(layer "In4.Cu")
		(net 266)
	)
	(segment
		(start 161.221505 158.893686)
		(end 161.221505 158.893687)
		(width 0.13)
		(layer "In4.Cu")
		(net 266)
	)
	(segment
		(start 158.718592 159.360627)
		(end 158.718592 159.360626)
		(width 0.13)
		(layer "In4.Cu")
		(net 266)
	)
	(segment
		(start 164.500001 146.568922)
		(end 164.500001 149.1575)
		(width 0.1)
		(layer "In4.Cu")
		(net 266)
	)
	(segment
		(start 155.352571 164.168775)
		(end 155.35257 164.168775)
		(width 0.13)
		(layer "In4.Cu")
		(net 266)
	)
	(segment
		(start 159.312436 160.20891)
		(end 159.015512 159.911986)
		(width 0.13)
		(layer "In4.Cu")
		(net 266)
	)
	(segment
		(start 161.292338 158.229008)
		(end 160.995414 157.932084)
		(width 0.13)
		(layer "In4.Cu")
		(net 266)
	)
	(segment
		(start 158.053911 160.279744)
		(end 158.053912 160.279744)
		(width 0.13)
		(layer "In4.Cu")
		(net 266)
	)
	(segment
		(start 155.084059 163.249597)
		(end 155.677905 163.843442)
		(width 0.13)
		(layer "In4.Cu")
		(net 266)
	)
	(segment
		(start 159.241603 160.873589)
		(end 159.312436 160.802755)
		(width 0.13)
		(layer "In4.Cu")
		(net 266)
	)
	(segment
		(start 157.728641 160.350577)
		(end 157.799474 160.279745)
		(width 0.13)
		(layer "In4.Cu")
		(net 266)
	)
	(segment
		(start 160.698494 157.380724)
		(end 160.769327 157.309892)
		(width 0.13)
		(layer "In4.Cu")
		(net 266)
	)
	(segment
		(start 165.000001 142.818922)
		(end 165.000001 146.068922)
		(width 0.1)
		(layer "In4.Cu")
		(net 266)
	)
	(segment
		(start 151.954001 165.4225)
		(end 153.674707 165.4225)
		(width 0.13)
		(layer "In4.Cu")
		(net 266)
	)
	(segment
		(start 165.675001 139.937426)
		(end 165.500001 140.112426)
		(width 0.1)
		(layer "In4.Cu")
		(net 266)
	)
	(segment
		(start 160.698494 157.380725)
		(end 160.698494 157.380724)
		(width 0.13)
		(layer "In4.Cu")
		(net 266)
	)
	(segment
		(start 156.27175 163.843441)
		(end 156.27175 163.843442)
		(width 0.13)
		(layer "In4.Cu")
		(net 266)
	)
	(segment
		(start 156.342584 163.178763)
		(end 156.342583 163.178763)
		(width 0.13)
		(layer "In4.Cu")
		(net 266)
	)
	(segment
		(start 159.241603 160.873588)
		(end 159.241603 160.873589)
		(width 0.13)
		(layer "In4.Cu")
		(net 266)
	)
	(segment
		(start 159.312437 160.20891)
		(end 159.312436 160.20891)
		(width 0.13)
		(layer "In4.Cu")
		(net 266)
	)
	(segment
		(start 161.292339 158.229008)
		(end 161.292338 158.229008)
		(width 0.13)
		(layer "In4.Cu")
		(net 266)
	)
	(segment
		(start 159.015516 159.911986)
		(end 158.718591 159.615064)
		(width 0.13)
		(layer "In4.Cu")
		(net 266)
	)
	(segment
		(start 157.063961 161.269695)
		(end 157.657807 161.86354)
		(width 0.13)
		(layer "In4.Cu")
		(net 266)
	)
	(segment
		(start 159.708543 158.370675)
		(end 159.779376 158.299843)
		(width 0.13)
		(layer "In4.Cu")
		(net 266)
	)
	(segment
		(start 160.005463 158.922035)
		(end 160.005467 158.922035)
		(width 0.13)
		(layer "In4.Cu")
		(net 266)
	)
	(segment
		(start 158.322485 161.198861)
		(end 158.025561 160.901937)
		(width 0.13)
		(layer "In4.Cu")
		(net 266)
	)
	(arc
		(start 154.758787 163.574868)
		(mid 154.706092 163.447649)
		(end 154.758788 163.320431)
		(width 0.13)
		(layer "In4.Cu")
		(net 266)
	)
	(arc
		(start 161.292338 158.822853)
		(mid 161.415328 158.525931)
		(end 161.292339 158.229008)
		(width 0.13)
		(layer "In4.Cu")
		(net 266)
	)
	(arc
		(start 157.332534 162.782657)
		(mid 157.455524 162.485735)
		(end 157.332535 162.188812)
		(width 0.13)
		(layer "In4.Cu")
		(net 266)
	)
	(arc
		(start 156.342583 163.772608)
		(mid 156.465573 163.475686)
		(end 156.342584 163.178763)
		(width 0.13)
		(layer "In4.Cu")
		(net 266)
	)
	(arc
		(start 159.779376 158.299843)
		(mid 159.906594 158.247147)
		(end 160.033813 158.299842)
		(width 0.13)
		(layer "In4.Cu")
		(net 266)
	)
	(arc
		(start 155.819572 162.259647)
		(mid 155.94679 162.206951)
		(end 156.074009 162.259646)
		(width 0.13)
		(layer "In4.Cu")
		(net 266)
	)
	(arc
		(start 160.62766 158.893687)
		(mid 160.924583 159.016676)
		(end 161.221505 158.893686)
		(width 0.13)
		(layer "In4.Cu")
		(net 266)
	)
	(arc
		(start 160.769327 157.309892)
		(mid 160.896545 157.257196)
		(end 161.023764 157.309891)
		(width 0.13)
		(layer "In4.Cu")
		(net 266)
	)
	(arc
		(start 154.687891 164.833454)
		(mid 154.984813 164.956444)
		(end 155.281736 164.833455)
		(width 0.13)
		(layer "In4.Cu")
		(net 266)
	)
	(arc
		(start 159.708542 158.625113)
		(mid 159.655847 158.497894)
		(end 159.708543 158.370676)
		(width 0.13)
		(layer "In4.Cu")
		(net 266)
	)
	(arc
		(start 155.35257 164.76262)
		(mid 155.47556 164.465698)
		(end 155.352571 164.168775)
		(width 0.13)
		(layer "In4.Cu")
		(net 266)
	)
	(arc
		(start 159.312436 160.802755)
		(mid 159.435426 160.505833)
		(end 159.312437 160.20891)
		(width 0.13)
		(layer "In4.Cu")
		(net 266)
	)
	(arc
		(start 156.809523 161.269696)
		(mid 156.936741 161.217)
		(end 157.06396 161.269695)
		(width 0.13)
		(layer "In4.Cu")
		(net 266)
	)
	(arc
		(start 156.738689 161.594966)
		(mid 156.685994 161.467747)
		(end 156.73869 161.340529)
		(width 0.13)
		(layer "In4.Cu")
		(net 266)
	)
	(arc
		(start 158.322485 161.792706)
		(mid 158.445475 161.495784)
		(end 158.322486 161.198861)
		(width 0.13)
		(layer "In4.Cu")
		(net 266)
	)
	(arc
		(start 157.799474 160.279745)
		(mid 157.926692 160.227049)
		(end 158.053911 160.279744)
		(width 0.13)
		(layer "In4.Cu")
		(net 266)
	)
	(arc
		(start 157.657807 161.86354)
		(mid 157.95473 161.986529)
		(end 158.251652 161.863539)
		(width 0.13)
		(layer "In4.Cu")
		(net 266)
	)
	(arc
		(start 155.677905 163.843442)
		(mid 155.974828 163.966431)
		(end 156.27175 163.843441)
		(width 0.13)
		(layer "In4.Cu")
		(net 266)
	)
	(arc
		(start 160.302387 159.812804)
		(mid 160.425377 159.515882)
		(end 160.302388 159.218959)
		(width 0.13)
		(layer "In4.Cu")
		(net 266)
	)
	(arc
		(start 154.348603 164.748602)
		(mid 154.475821 164.695907)
		(end 154.603039 164.748602)
		(width 0.13)
		(layer "In4.Cu")
		(net 266)
	)
	(arc
		(start 160.698493 157.635162)
		(mid 160.645798 157.507943)
		(end 160.698494 157.380725)
		(width 0.13)
		(layer "In4.Cu")
		(net 266)
	)
	(arc
		(start 156.667856 162.853491)
		(mid 156.964779 162.97648)
		(end 157.261701 162.85349)
		(width 0.13)
		(layer "In4.Cu")
		(net 266)
	)
	(arc
		(start 154.829621 163.249598)
		(mid 154.956839 163.196902)
		(end 155.084058 163.249597)
		(width 0.13)
		(layer "In4.Cu")
		(net 266)
	)
	(arc
		(start 161.108618 157.394744)
		(mid 161.40554 157.517734)
		(end 161.702463 157.394745)
		(width 0.13)
		(layer "In4.Cu")
		(net 266)
	)
	(arc
		(start 157.72864 160.605015)
		(mid 157.675945 160.477796)
		(end 157.728641 160.350578)
		(width 0.13)
		(layer "In4.Cu")
		(net 266)
	)
	(arc
		(start 155.748738 162.584917)
		(mid 155.696043 162.457698)
		(end 155.748739 162.33048)
		(width 0.13)
		(layer "In4.Cu")
		(net 266)
	)
	(arc
		(start 158.718591 159.615064)
		(mid 158.665896 159.487845)
		(end 158.718592 159.360627)
		(width 0.13)
		(layer "In4.Cu")
		(net 266)
	)
	(arc
		(start 158.647758 160.873589)
		(mid 158.944681 160.996578)
		(end 159.241603 160.873588)
		(width 0.13)
		(layer "In4.Cu")
		(net 266)
	)
	(arc
		(start 158.789425 159.289794)
		(mid 158.916643 159.237098)
		(end 159.043862 159.289793)
		(width 0.13)
		(layer "In4.Cu")
		(net 266)
	)
	(arc
		(start 159.637709 159.883638)
		(mid 159.934632 160.006627)
		(end 160.231554 159.883637)
		(width 0.13)
		(layer "In4.Cu")
		(net 266)
	)
	(segment
		(start 99.8 135.585)
		(end 100.885 135.585)
		(width 0.256)
		(layer "F.Cu")
		(net 267)
	)
	(segment
		(start 99.895 132.994)
		(end 99.908 132.981)
		(width 0.256)
		(layer "F.Cu")
		(net 267)
	)
	(segment
		(start 100.262501 139.428)
		(end 100.262501 138.214)
		(width 0.256)
		(layer "F.Cu")
		(net 267)
	)
	(segment
		(start 100.9 137.576501)
		(end 100.280501 138.196)
		(width 0.256)
		(layer "F.Cu")
		(net 267)
	)
	(segment
		(start 99.895 133.995)
		(end 99.895 132.994)
		(width 0.256)
		(layer "F.Cu")
		(net 267)
	)
	(segment
		(start 99.895 133.995)
		(end 100.9 135)
		(width 0.256)
		(layer "F.Cu")
		(net 267)
	)
	(segment
		(start 100.885 135.585)
		(end 100.9 135.6)
		(width 0.256)
		(layer "F.Cu")
		(net 267)
	)
	(segment
		(start 100.9 135.6)
		(end 100.9 137.576501)
		(width 0.256)
		(layer "F.Cu")
		(net 267)
	)
	(segment
		(start 100.262501 138.214)
		(end 100.280501 138.196)
		(width 0.256)
		(layer "F.Cu")
		(net 267)
	)
	(segment
		(start 98.78 135.585)
		(end 99.8 135.585)
		(width 0.256)
		(layer "F.Cu")
		(net 267)
	)
	(segment
		(start 100.9 135)
		(end 100.9 135.6)
		(width 0.256)
		(layer "F.Cu")
		(net 267)
	)
	(via
		(at 100.280501 138.196)
		(size 0.45)
		(drill 0.1)
		(layers "F.Cu" "B.Cu")
		(net 267)
	)
	(segment
		(start 99.754501 138.236)
		(end 100.240501 138.236)
		(width 0.256)
		(layer "B.Cu")
		(net 267)
	)
	(segment
		(start 100.240501 138.236)
		(end 100.280501 138.196)
		(width 0.256)
		(layer "B.Cu")
		(net 267)
	)
	(segment
		(start 151.375501 169.302)
		(end 151.875001 168.8025)
		(width 0.256)
		(layer "F.Cu")
		(net 268)
	)
	(segment
		(start 165.900001 146.2025)
		(end 165.900001 147.2775)
		(width 0.201)
		(layer "F.Cu")
		(net 268)
	)
	(via
		(at 165.900001 147.2775)
		(size 0.45)
		(drill 0.1)
		(layers "F.Cu" "B.Cu")
		(net 268)
	)
	(via
		(at 151.875001 168.8025)
		(size 0.45)
		(drill 0.1)
		(layers "F.Cu" "B.Cu")
		(net 268)
	)
	(segment
		(start 161.81393 163.286364)
		(end 161.602535 163.074969)
		(width 0.148)
		(layer "In4.Cu")
		(net 268)
	)
	(segment
		(start 160.895429 163.782072)
		(end 160.684033 163.570676)
		(width 0.148)
		(layer "In4.Cu")
		(net 268)
	)
	(segment
		(start 160.39972 164.700575)
		(end 160.399718 164.700576)
		(width 0.148)
		(layer "In4.Cu")
		(net 268)
	)
	(segment
		(start 162.451797 161.802911)
		(end 162.87459 162.225703)
		(width 0.148)
		(layer "In4.Cu")
		(net 268)
	)
	(segment
		(start 162.521038 162.579257)
		(end 162.521036 162.579258)
		(width 0.148)
		(layer "In4.Cu")
		(net 268)
	)
	(segment
		(start 158.2784 166.821894)
		(end 158.243781 166.787275)
		(width 0.148)
		(layer "In4.Cu")
		(net 268)
	)
	(segment
		(start 161.602535 163.074966)
		(end 161.391139 162.86357)
		(width 0.148)
		(layer "In4.Cu")
		(net 268)
	)
	(segment
		(start 159.623374 164.277781)
		(end 159.623373 164.277782)
		(width 0.148)
		(layer "In4.Cu")
		(net 268)
	)
	(segment
		(start 165.138065 159.539439)
		(end 165.138065 159.539436)
		(width 0.148)
		(layer "In4.Cu")
		(net 268)
	)
	(segment
		(start 159.339061 166.114786)
		(end 159.33906 166.114787)
		(width 0.148)
		(layer "In4.Cu")
		(net 268)
	)
	(segment
		(start 161.602535 163.074969)
		(end 161.602535 163.074966)
		(width 0.148)
		(layer "In4.Cu")
		(net 268)
	)
	(segment
		(start 165.349462 159.750833)
		(end 165.34946 159.750834)
		(width 0.148)
		(layer "In4.Cu")
		(net 268)
	)
	(segment
		(start 158.209161 166.045547)
		(end 158.631954 166.468339)
		(width 0.148)
		(layer "In4.Cu")
		(net 268)
	)
	(segment
		(start 157.890228 166.787276)
		(end 157.890229 166.787274)
		(width 0.148)
		(layer "In4.Cu")
		(net 268)
	)
	(segment
		(start 160.188323 164.489181)
		(end 160.188323 164.489178)
		(width 0.148)
		(layer "In4.Cu")
		(net 268)
	)
	(segment
		(start 164.430959 160.246545)
		(end 164.430959 160.246542)
		(width 0.148)
		(layer "In4.Cu")
		(net 268)
	)
	(segment
		(start 158.985506 166.114788)
		(end 158.774111 165.903393)
		(width 0.148)
		(layer "In4.Cu")
		(net 268)
	)
	(segment
		(start 160.046167 165.40768)
		(end 160.046166 165.407681)
		(width 0.148)
		(layer "In4.Cu")
		(net 268)
	)
	(segment
		(start 162.167485 163.286362)
		(end 162.167484 163.286363)
		(width 0.148)
		(layer "In4.Cu")
		(net 268)
	)
	(segment
		(start 158.916268 164.984887)
		(end 158.916267 164.984888)
		(width 0.148)
		(layer "In4.Cu")
		(net 268)
	)
	(segment
		(start 165.138065 159.539436)
		(end 164.926669 159.32804)
		(width 0.148)
		(layer "In4.Cu")
		(net 268)
	)
	(segment
		(start 163.016747 161.660757)
		(end 163.016747 161.660754)
		(width 0.148)
		(layer "In4.Cu")
		(net 268)
	)
	(segment
		(start 158.209161 166.045546)
		(end 158.209161 166.045547)
		(width 0.148)
		(layer "In4.Cu")
		(net 268)
	)
	(segment
		(start 160.330479 163.924228)
		(end 160.330479 163.924229)
		(width 0.148)
		(layer "In4.Cu")
		(net 268)
	)
	(segment
		(start 163.866009 160.388698)
		(end 163.866009 160.388699)
		(width 0.148)
		(layer "In4.Cu")
		(net 268)
	)
	(segment
		(start 160.399718 164.700576)
		(end 160.188323 164.489181)
		(width 0.148)
		(layer "In4.Cu")
		(net 268)
	)
	(segment
		(start 159.623373 164.631335)
		(end 160.046166 165.054127)
		(width 0.148)
		(layer "In4.Cu")
		(net 268)
	)
	(segment
		(start 162.874591 162.579256)
		(end 162.87459 162.579257)
		(width 0.148)
		(layer "In4.Cu")
		(net 268)
	)
	(segment
		(start 162.309641 162.367863)
		(end 162.309641 162.36786)
		(width 0.148)
		(layer "In4.Cu")
		(net 268)
	)
	(segment
		(start 159.692614 165.407681)
		(end 159.692612 165.407682)
		(width 0.148)
		(layer "In4.Cu")
		(net 268)
	)
	(segment
		(start 164.430959 160.246542)
		(end 164.219563 160.035146)
		(width 0.148)
		(layer "In4.Cu")
		(net 268)
	)
	(segment
		(start 163.016747 161.660754)
		(end 162.805351 161.449358)
		(width 0.148)
		(layer "In4.Cu")
		(net 268)
	)
	(segment
		(start 163.158903 161.095805)
		(end 163.581696 161.518597)
		(width 0.148)
		(layer "In4.Cu")
		(net 268)
	)
	(segment
		(start 162.309641 162.36786)
		(end 162.098245 162.156464)
		(width 0.148)
		(layer "In4.Cu")
		(net 268)
	)
	(segment
		(start 165.280222 158.620933)
		(end 165.280221 158.620934)
		(width 0.148)
		(layer "In4.Cu")
		(net 268)
	)
	(segment
		(start 160.33048 163.570675)
		(end 160.330479 163.570676)
		(width 0.148)
		(layer "In4.Cu")
		(net 268)
	)
	(segment
		(start 160.753273 164.700574)
		(end 160.753272 164.700575)
		(width 0.148)
		(layer "In4.Cu")
		(net 268)
	)
	(segment
		(start 166.056568 159.043728)
		(end 166.056568 159.043727)
		(width 0.148)
		(layer "In4.Cu")
		(net 268)
	)
	(segment
		(start 158.916267 165.338441)
		(end 159.33906 165.761233)
		(width 0.148)
		(layer "In4.Cu")
		(net 268)
	)
	(segment
		(start 158.916267 165.33844)
		(end 158.916267 165.338441)
		(width 0.148)
		(layer "In4.Cu")
		(net 268)
	)
	(segment
		(start 153.227001 168.8025)
		(end 151.875001 168.8025)
		(width 0.148)
		(layer "In4.Cu")
		(net 268)
	)
	(segment
		(start 161.744691 162.510016)
		(end 161.744691 162.510017)
		(width 0.148)
		(layer "In4.Cu")
		(net 268)
	)
	(segment
		(start 161.106824 163.99347)
		(end 160.895429 163.782075)
		(width 0.148)
		(layer "In4.Cu")
		(net 268)
	)
	(segment
		(start 165.703015 159.750832)
		(end 165.703014 159.750833)
		(width 0.148)
		(layer "In4.Cu")
		(net 268)
	)
	(segment
		(start 163.228144 161.872151)
		(end 163.228142 161.872152)
		(width 0.148)
		(layer "In4.Cu")
		(net 268)
	)
	(segment
		(start 164.995909 160.457938)
		(end 164.995908 160.457939)
		(width 0.148)
		(layer "In4.Cu")
		(net 268)
	)
	(segment
		(start 165.900001 148.1755)
		(end 168.125501 150.401)
		(width 0.148)
		(layer "In4.Cu")
		(net 268)
	)
	(segment
		(start 160.330479 163.924229)
		(end 160.753272 164.347021)
		(width 0.148)
		(layer "In4.Cu")
		(net 268)
	)
	(segment
		(start 168.125501 150.401)
		(end 168.125501 156.552)
		(width 0.148)
		(layer "In4.Cu")
		(net 268)
	)
	(segment
		(start 165.280221 158.974486)
		(end 165.280221 158.974487)
		(width 0.148)
		(layer "In4.Cu")
		(net 268)
	)
	(segment
		(start 163.723853 160.953648)
		(end 163.512457 160.742252)
		(width 0.148)
		(layer "In4.Cu")
		(net 268)
	)
	(segment
		(start 159.692612 165.407682)
		(end 159.481217 165.196287)
		(width 0.148)
		(layer "In4.Cu")
		(net 268)
	)
	(segment
		(start 164.642354 160.45794)
		(end 164.430959 160.246545)
		(width 0.148)
		(layer "In4.Cu")
		(net 268)
	)
	(segment
		(start 164.288803 161.165044)
		(end 164.288802 161.165045)
		(width 0.148)
		(layer "In4.Cu")
		(net 268)
	)
	(segment
		(start 163.581697 161.87215)
		(end 163.581696 161.872151)
		(width 0.148)
		(layer "In4.Cu")
		(net 268)
	)
	(segment
		(start 158.631955 166.821892)
		(end 158.631954 166.821893)
		(width 0.148)
		(layer "In4.Cu")
		(net 268)
	)
	(segment
		(start 153.700501 169.276)
		(end 153.227001 168.8025)
		(width 0.148)
		(layer "In4.Cu")
		(net 268)
	)
	(segment
		(start 155.401501 169.276)
		(end 153.700501 169.276)
		(width 0.148)
		(layer "In4.Cu")
		(net 268)
	)
	(segment
		(start 158.774111 165.90339)
		(end 158.562715 165.691994)
		(width 0.148)
		(layer "In4.Cu")
		(net 268)
	)
	(segment
		(start 163.935248 161.165046)
		(end 163.723853 160.953651)
		(width 0.148)
		(layer "In4.Cu")
		(net 268)
	)
	(segment
		(start 159.481217 165.196287)
		(end 159.481217 165.196284)
		(width 0.148)
		(layer "In4.Cu")
		(net 268)
	)
	(segment
		(start 161.106826 163.993469)
		(end 161.106824 163.99347)
		(width 0.148)
		(layer "In4.Cu")
		(net 268)
	)
	(segment
		(start 160.188323 164.489178)
		(end 159.976927 164.277782)
		(width 0.148)
		(layer "In4.Cu")
		(net 268)
	)
	(segment
		(start 158.985508 166.114787)
		(end 158.985506 166.114788)
		(width 0.148)
		(layer "In4.Cu")
		(net 268)
	)
	(segment
		(start 164.573115 159.681593)
		(end 164.995908 160.104385)
		(width 0.148)
		(layer "In4.Cu")
		(net 268)
	)
	(segment
		(start 158.774111 165.903393)
		(end 158.774111 165.90339)
		(width 0.148)
		(layer "In4.Cu")
		(net 268)
	)
	(segment
		(start 166.41012 159.043727)
		(end 166.41012 159.043728)
		(width 0.148)
		(layer "In4.Cu")
		(net 268)
	)
	(segment
		(start 160.895429 163.782075)
		(end 160.895429 163.782072)
		(width 0.148)
		(layer "In4.Cu")
		(net 268)
	)
	(segment
		(start 162.521036 162.579258)
		(end 162.309641 162.367863)
		(width 0.148)
		(layer "In4.Cu")
		(net 268)
	)
	(segment
		(start 164.573115 159.681592)
		(end 164.573115 159.681593)
		(width 0.148)
		(layer "In4.Cu")
		(net 268)
	)
	(segment
		(start 163.866009 160.388699)
		(end 164.288802 160.811491)
		(width 0.148)
		(layer "In4.Cu")
		(net 268)
	)
	(segment
		(start 163.158903 161.095804)
		(end 163.158903 161.095805)
		(width 0.148)
		(layer "In4.Cu")
		(net 268)
	)
	(segment
		(start 158.278402 166.821893)
		(end 158.2784 166.821894)
		(width 0.148)
		(layer "In4.Cu")
		(net 268)
	)
	(segment
		(start 162.451798 161.449357)
		(end 162.451797 161.449358)
		(width 0.148)
		(layer "In4.Cu")
		(net 268)
	)
	(segment
		(start 161.744692 162.156463)
		(end 161.744691 162.156464)
		(width 0.148)
		(layer "In4.Cu")
		(net 268)
	)
	(segment
		(start 163.93525 161.165045)
		(end 163.935248 161.165046)
		(width 0.148)
		(layer "In4.Cu")
		(net 268)
	)
	(segment
		(start 157.890229 166.787274)
		(end 155.401501 169.276)
		(width 0.148)
		(layer "In4.Cu")
		(net 268)
	)
	(segment
		(start 161.037585 163.217122)
		(end 161.037585 163.217123)
		(width 0.148)
		(layer "In4.Cu")
		(net 268)
	)
	(segment
		(start 161.744691 162.510017)
		(end 162.167484 162.932809)
		(width 0.148)
		(layer "In4.Cu")
		(net 268)
	)
	(segment
		(start 161.813932 163.286363)
		(end 161.81393 163.286364)
		(width 0.148)
		(layer "In4.Cu")
		(net 268)
	)
	(segment
		(start 166.375501 158.655554)
		(end 166.410121 158.690174)
		(width 0.148)
		(layer "In4.Cu")
		(net 268)
	)
	(segment
		(start 165.900001 147.2775)
		(end 165.900001 148.1755)
		(width 0.148)
		(layer "In4.Cu")
		(net 268)
	)
	(segment
		(start 158.209162 165.691993)
		(end 158.209161 165.691994)
		(width 0.148)
		(layer "In4.Cu")
		(net 268)
	)
	(segment
		(start 161.037585 163.217123)
		(end 161.460378 163.639915)
		(width 0.148)
		(layer "In4.Cu")
		(net 268)
	)
	(segment
		(start 168.125501 156.552)
		(end 166.375501 158.302)
		(width 0.148)
		(layer "In4.Cu")
		(net 268)
	)
	(segment
		(start 161.460379 163.993468)
		(end 161.460378 163.993469)
		(width 0.148)
		(layer "In4.Cu")
		(net 268)
	)
	(segment
		(start 164.573116 159.328039)
		(end 164.573115 159.32804)
		(width 0.148)
		(layer "In4.Cu")
		(net 268)
	)
	(segment
		(start 162.451797 161.80291)
		(end 162.451797 161.802911)
		(width 0.148)
		(layer "In4.Cu")
		(net 268)
	)
	(segment
		(start 161.037586 162.863569)
		(end 161.037585 162.86357)
		(width 0.148)
		(layer "In4.Cu")
		(net 268)
	)
	(segment
		(start 163.86601 160.035145)
		(end 163.866009 160.035146)
		(width 0.148)
		(layer "In4.Cu")
		(net 268)
	)
	(segment
		(start 163.723853 160.953651)
		(end 163.723853 160.953648)
		(width 0.148)
		(layer "In4.Cu")
		(net 268)
	)
	(segment
		(start 159.481217 165.196284)
		(end 159.269821 164.984888)
		(width 0.148)
		(layer "In4.Cu")
		(net 268)
	)
	(segment
		(start 159.623373 164.631334)
		(end 159.623373 164.631335)
		(width 0.148)
		(layer "In4.Cu")
		(net 268)
	)
	(segment
		(start 166.056568 159.043727)
		(end 165.633775 158.620934)
		(width 0.148)
		(layer "In4.Cu")
		(net 268)
	)
	(segment
		(start 165.280221 158.974487)
		(end 165.703014 159.397279)
		(width 0.148)
		(layer "In4.Cu")
		(net 268)
	)
	(segment
		(start 163.228142 161.872152)
		(end 163.016747 161.660757)
		(width 0.148)
		(layer "In4.Cu")
		(net 268)
	)
	(segment
		(start 163.158904 160.742251)
		(end 163.158903 160.742252)
		(width 0.148)
		(layer "In4.Cu")
		(net 268)
	)
	(segment
		(start 165.34946 159.750834)
		(end 165.138065 159.539439)
		(width 0.148)
		(layer "In4.Cu")
		(net 268)
	)
	(segment
		(start 164.642356 160.457939)
		(end 164.642354 160.45794)
		(width 0.148)
		(layer "In4.Cu")
		(net 268)
	)
	(arc
		(start 162.167484 162.932809)
		(mid 162.240708 163.109585)
		(end 162.167485 163.286362)
		(width 0.148)
		(layer "In4.Cu")
		(net 268)
	)
	(arc
		(start 163.581696 161.518597)
		(mid 163.65492 161.695373)
		(end 163.581697 161.87215)
		(width 0.148)
		(layer "In4.Cu")
		(net 268)
	)
	(arc
		(start 162.451797 161.449358)
		(mid 162.378574 161.626134)
		(end 162.451797 161.80291)
		(width 0.148)
		(layer "In4.Cu")
		(net 268)
	)
	(arc
		(start 161.037585 162.86357)
		(mid 160.964362 163.040346)
		(end 161.037585 163.217122)
		(width 0.148)
		(layer "In4.Cu")
		(net 268)
	)
	(arc
		(start 160.684033 163.570676)
		(mid 160.507257 163.497452)
		(end 160.33048 163.570675)
		(width 0.148)
		(layer "In4.Cu")
		(net 268)
	)
	(arc
		(start 159.33906 166.114787)
		(mid 159.162283 166.188011)
		(end 158.985508 166.114787)
		(width 0.148)
		(layer "In4.Cu")
		(net 268)
	)
	(arc
		(start 164.926669 159.32804)
		(mid 164.749893 159.254816)
		(end 164.573116 159.328039)
		(width 0.148)
		(layer "In4.Cu")
		(net 268)
	)
	(arc
		(start 162.805351 161.449358)
		(mid 162.628575 161.376134)
		(end 162.451798 161.449357)
		(width 0.148)
		(layer "In4.Cu")
		(net 268)
	)
	(arc
		(start 165.703014 159.397279)
		(mid 165.776238 159.574055)
		(end 165.703015 159.750832)
		(width 0.148)
		(layer "In4.Cu")
		(net 268)
	)
	(arc
		(start 158.631954 166.821893)
		(mid 158.455177 166.895117)
		(end 158.278402 166.821893)
		(width 0.148)
		(layer "In4.Cu")
		(net 268)
	)
	(arc
		(start 165.280221 158.620934)
		(mid 165.206998 158.79771)
		(end 165.280221 158.974486)
		(width 0.148)
		(layer "In4.Cu")
		(net 268)
	)
	(arc
		(start 164.995908 160.457939)
		(mid 164.819131 160.531163)
		(end 164.642356 160.457939)
		(width 0.148)
		(layer "In4.Cu")
		(net 268)
	)
	(arc
		(start 160.330479 163.570676)
		(mid 160.257256 163.747452)
		(end 160.330479 163.924228)
		(width 0.148)
		(layer "In4.Cu")
		(net 268)
	)
	(arc
		(start 159.623373 164.277782)
		(mid 159.55015 164.454558)
		(end 159.623373 164.631334)
		(width 0.148)
		(layer "In4.Cu")
		(net 268)
	)
	(arc
		(start 162.098245 162.156464)
		(mid 161.921469 162.08324)
		(end 161.744692 162.156463)
		(width 0.148)
		(layer "In4.Cu")
		(net 268)
	)
	(arc
		(start 162.167484 163.286363)
		(mid 161.990707 163.359587)
		(end 161.813932 163.286363)
		(width 0.148)
		(layer "In4.Cu")
		(net 268)
	)
	(arc
		(start 160.753272 164.700575)
		(mid 160.576495 164.773799)
		(end 160.39972 164.700575)
		(width 0.148)
		(layer "In4.Cu")
		(net 268)
	)
	(arc
		(start 158.243781 166.787275)
		(mid 158.067004 166.714052)
		(end 157.890228 166.787276)
		(width 0.148)
		(layer "In4.Cu")
		(net 268)
	)
	(arc
		(start 166.375501 158.302)
		(mid 166.302278 158.478777)
		(end 166.375501 158.655554)
		(width 0.148)
		(layer "In4.Cu")
		(net 268)
	)
	(arc
		(start 158.916267 164.984888)
		(mid 158.843044 165.161664)
		(end 158.916267 165.33844)
		(width 0.148)
		(layer "In4.Cu")
		(net 268)
	)
	(arc
		(start 161.391139 162.86357)
		(mid 161.214363 162.790346)
		(end 161.037586 162.863569)
		(width 0.148)
		(layer "In4.Cu")
		(net 268)
	)
	(arc
		(start 162.87459 162.579257)
		(mid 162.697813 162.652481)
		(end 162.521038 162.579257)
		(width 0.148)
		(layer "In4.Cu")
		(net 268)
	)
	(arc
		(start 161.744691 162.156464)
		(mid 161.671468 162.33324)
		(end 161.744691 162.510016)
		(width 0.148)
		(layer "In4.Cu")
		(net 268)
	)
	(arc
		(start 159.976927 164.277782)
		(mid 159.800151 164.204558)
		(end 159.623374 164.277781)
		(width 0.148)
		(layer "In4.Cu")
		(net 268)
	)
	(arc
		(start 163.581696 161.872151)
		(mid 163.404919 161.945375)
		(end 163.228144 161.872151)
		(width 0.148)
		(layer "In4.Cu")
		(net 268)
	)
	(arc
		(start 164.995908 160.104385)
		(mid 165.069132 160.281161)
		(end 164.995909 160.457938)
		(width 0.148)
		(layer "In4.Cu")
		(net 268)
	)
	(arc
		(start 163.158903 160.742252)
		(mid 163.08568 160.919028)
		(end 163.158903 161.095804)
		(width 0.148)
		(layer "In4.Cu")
		(net 268)
	)
	(arc
		(start 165.703014 159.750833)
		(mid 165.526237 159.824057)
		(end 165.349462 159.750833)
		(width 0.148)
		(layer "In4.Cu")
		(net 268)
	)
	(arc
		(start 163.512457 160.742252)
		(mid 163.335681 160.669028)
		(end 163.158904 160.742251)
		(width 0.148)
		(layer "In4.Cu")
		(net 268)
	)
	(arc
		(start 159.269821 164.984888)
		(mid 159.093045 164.911664)
		(end 158.916268 164.984887)
		(width 0.148)
		(layer "In4.Cu")
		(net 268)
	)
	(arc
		(start 158.209161 165.691994)
		(mid 158.135938 165.86877)
		(end 158.209161 166.045546)
		(width 0.148)
		(layer "In4.Cu")
		(net 268)
	)
	(arc
		(start 164.288802 161.165045)
		(mid 164.112025 161.238269)
		(end 163.93525 161.165045)
		(width 0.148)
		(layer "In4.Cu")
		(net 268)
	)
	(arc
		(start 160.753272 164.347021)
		(mid 160.826496 164.523797)
		(end 160.753273 164.700574)
		(width 0.148)
		(layer "In4.Cu")
		(net 268)
	)
	(arc
		(start 161.460378 163.639915)
		(mid 161.533602 163.816691)
		(end 161.460379 163.993468)
		(width 0.148)
		(layer "In4.Cu")
		(net 268)
	)
	(arc
		(start 165.633775 158.620934)
		(mid 165.456999 158.54771)
		(end 165.280222 158.620933)
		(width 0.148)
		(layer "In4.Cu")
		(net 268)
	)
	(arc
		(start 158.562715 165.691994)
		(mid 158.385939 165.61877)
		(end 158.209162 165.691993)
		(width 0.148)
		(layer "In4.Cu")
		(net 268)
	)
	(arc
		(start 164.288802 160.811491)
		(mid 164.362026 160.988267)
		(end 164.288803 161.165044)
		(width 0.148)
		(layer "In4.Cu")
		(net 268)
	)
	(arc
		(start 159.33906 165.761233)
		(mid 159.412284 165.938009)
		(end 159.339061 166.114786)
		(width 0.148)
		(layer "In4.Cu")
		(net 268)
	)
	(arc
		(start 162.87459 162.225703)
		(mid 162.947814 162.402479)
		(end 162.874591 162.579256)
		(width 0.148)
		(layer "In4.Cu")
		(net 268)
	)
	(arc
		(start 158.631954 166.468339)
		(mid 158.705178 166.645115)
		(end 158.631955 166.821892)
		(width 0.148)
		(layer "In4.Cu")
		(net 268)
	)
	(arc
		(start 164.573115 159.32804)
		(mid 164.499892 159.504816)
		(end 164.573115 159.681592)
		(width 0.148)
		(layer "In4.Cu")
		(net 268)
	)
	(arc
		(start 163.866009 160.035146)
		(mid 163.792786 160.211922)
		(end 163.866009 160.388698)
		(width 0.148)
		(layer "In4.Cu")
		(net 268)
	)
	(arc
		(start 164.219563 160.035146)
		(mid 164.042787 159.961922)
		(end 163.86601 160.035145)
		(width 0.148)
		(layer "In4.Cu")
		(net 268)
	)
	(arc
		(start 166.410121 158.690174)
		(mid 166.483344 158.866951)
		(end 166.41012 159.043727)
		(width 0.148)
		(layer "In4.Cu")
		(net 268)
	)
	(arc
		(start 161.460378 163.993469)
		(mid 161.283601 164.066693)
		(end 161.106826 163.993469)
		(width 0.148)
		(layer "In4.Cu")
		(net 268)
	)
	(arc
		(start 160.046166 165.407681)
		(mid 159.869389 165.480905)
		(end 159.692614 165.407681)
		(width 0.148)
		(layer "In4.Cu")
		(net 268)
	)
	(arc
		(start 166.41012 159.043728)
		(mid 166.233345 159.11695)
		(end 166.056568 159.043728)
		(width 0.148)
		(layer "In4.Cu")
		(net 268)
	)
	(arc
		(start 160.046166 165.054127)
		(mid 160.11939 165.230903)
		(end 160.046167 165.40768)
		(width 0.148)
		(layer "In4.Cu")
		(net 268)
	)
	(segment
		(start 166.650001 138.8025)
		(end 166.650001 139.8775)
		(width 0.201)
		(layer "F.Cu")
		(net 269)
	)
	(segment
		(start 150.375501 168.302)
		(end 150.875001 167.802499)
		(width 0.256)
		(layer "F.Cu")
		(net 269)
	)
	(via
		(at 150.875001 167.802499)
		(size 0.45)
		(drill 0.1)
		(layers "F.Cu" "B.Cu")
		(net 269)
	)
	(via
		(at 166.650001 139.8775)
		(size 0.45)
		(drill 0.1)
		(layers "F.Cu" "B.Cu")
		(net 269)
	)
	(segment
		(start 165.974501 143.603)
		(end 165.974501 145.603)
		(width 0.148)
		(layer "In4.Cu")
		(net 269)
	)
	(segment
		(start 166.875501 156.302)
		(end 154.901501 168.276)
		(width 0.148)
		(layer "In4.Cu")
		(net 269)
	)
	(segment
		(start 166.355121 154.052)
		(end 167.395881 154.052)
		(width 0.148)
		(layer "In4.Cu")
		(net 269)
	)
	(segment
		(start 154.901501 168.276)
		(end 151.348502 168.276)
		(width 0.148)
		(layer "In4.Cu")
		(net 269)
	)
	(segment
		(start 165.974501 145.603)
		(end 165.474501 146.103)
		(width 0.148)
		(layer "In4.Cu")
		(net 269)
	)
	(segment
		(start 166.355121 152.052)
		(end 167.395881 152.052)
		(width 0.148)
		(layer "In4.Cu")
		(net 269)
	)
	(segment
		(start 165.474501 148.65)
		(end 166.875501 150.051)
		(width 0.148)
		(layer "In4.Cu")
		(net 269)
	)
	(segment
		(start 166.355121 154.552)
		(end 167.395881 154.552)
		(width 0.148)
		(layer "In4.Cu")
		(net 269)
	)
	(segment
		(start 166.650001 139.8775)
		(end 166.650001 142.9275)
		(width 0.148)
		(layer "In4.Cu")
		(net 269)
	)
	(segment
		(start 166.875501 150.051)
		(end 166.875501 150.302)
		(width 0.148)
		(layer "In4.Cu")
		(net 269)
	)
	(segment
		(start 166.625501 150.552)
		(end 166.355121 150.552)
		(width 0.148)
		(layer "In4.Cu")
		(net 269)
	)
	(segment
		(start 151.348502 168.276)
		(end 150.875001 167.802499)
		(width 0.148)
		(layer "In4.Cu")
		(net 269)
	)
	(segment
		(start 166.355121 152.552)
		(end 167.395881 152.552)
		(width 0.148)
		(layer "In4.Cu")
		(net 269)
	)
	(segment
		(start 166.355121 155.052)
		(end 167.395881 155.052)
		(width 0.148)
		(layer "In4.Cu")
		(net 269)
	)
	(segment
		(start 167.395881 155.552)
		(end 167.125501 155.552)
		(width 0.148)
		(layer "In4.Cu")
		(net 269)
	)
	(segment
		(start 166.355121 153.052)
		(end 167.395881 153.052)
		(width 0.148)
		(layer "In4.Cu")
		(net 269)
	)
	(segment
		(start 166.875501 155.802)
		(end 166.875501 156.302)
		(width 0.148)
		(layer "In4.Cu")
		(net 269)
	)
	(segment
		(start 166.355121 151.552)
		(end 167.395881 151.552)
		(width 0.148)
		(layer "In4.Cu")
		(net 269)
	)
	(segment
		(start 165.474501 146.103)
		(end 165.474501 148.65)
		(width 0.148)
		(layer "In4.Cu")
		(net 269)
	)
	(segment
		(start 166.355121 151.052)
		(end 167.395881 151.052)
		(width 0.148)
		(layer "In4.Cu")
		(net 269)
	)
	(segment
		(start 166.355121 153.552)
		(end 167.395881 153.552)
		(width 0.148)
		(layer "In4.Cu")
		(net 269)
	)
	(segment
		(start 166.650001 142.9275)
		(end 165.974501 143.603)
		(width 0.148)
		(layer "In4.Cu")
		(net 269)
	)
	(arc
		(start 166.355121 152.552)
		(mid 166.178344 152.625223)
		(end 166.105121 152.802)
		(width 0.148)
		(layer "In4.Cu")
		(net 269)
	)
	(arc
		(start 166.105121 152.802)
		(mid 166.178344 152.978777)
		(end 166.355121 153.052)
		(width 0.148)
		(layer "In4.Cu")
		(net 269)
	)
	(arc
		(start 167.395881 154.052)
		(mid 167.572658 154.125223)
		(end 167.645881 154.302)
		(width 0.148)
		(layer "In4.Cu")
		(net 269)
	)
	(arc
		(start 167.645881 153.302)
		(mid 167.572658 153.478777)
		(end 167.395881 153.552)
		(width 0.148)
		(layer "In4.Cu")
		(net 269)
	)
	(arc
		(start 167.645881 154.302)
		(mid 167.572658 154.478777)
		(end 167.395881 154.552)
		(width 0.148)
		(layer "In4.Cu")
		(net 269)
	)
	(arc
		(start 166.105121 153.802)
		(mid 166.178344 153.978777)
		(end 166.355121 154.052)
		(width 0.148)
		(layer "In4.Cu")
		(net 269)
	)
	(arc
		(start 167.395881 153.052)
		(mid 167.572658 153.125223)
		(end 167.645881 153.302)
		(width 0.148)
		(layer "In4.Cu")
		(net 269)
	)
	(arc
		(start 167.395881 151.052)
		(mid 167.572658 151.125223)
		(end 167.645881 151.302)
		(width 0.148)
		(layer "In4.Cu")
		(net 269)
	)
	(arc
		(start 166.875501 150.302)
		(mid 166.802278 150.478777)
		(end 166.625501 150.552)
		(width 0.148)
		(layer "In4.Cu")
		(net 269)
	)
	(arc
		(start 166.355121 150.552)
		(mid 166.178344 150.625223)
		(end 166.105121 150.802)
		(width 0.148)
		(layer "In4.Cu")
		(net 269)
	)
	(arc
		(start 166.105121 151.802)
		(mid 166.178344 151.978777)
		(end 166.355121 152.052)
		(width 0.148)
		(layer "In4.Cu")
		(net 269)
	)
	(arc
		(start 167.395881 152.052)
		(mid 167.572658 152.125223)
		(end 167.645881 152.302)
		(width 0.148)
		(layer "In4.Cu")
		(net 269)
	)
	(arc
		(start 167.645881 151.302)
		(mid 167.572658 151.478777)
		(end 167.395881 151.552)
		(width 0.148)
		(layer "In4.Cu")
		(net 269)
	)
	(arc
		(start 166.355121 154.552)
		(mid 166.178344 154.625223)
		(end 166.105121 154.802)
		(width 0.148)
		(layer "In4.Cu")
		(net 269)
	)
	(arc
		(start 167.645881 155.302)
		(mid 167.572658 155.478777)
		(end 167.395881 155.552)
		(width 0.148)
		(layer "In4.Cu")
		(net 269)
	)
	(arc
		(start 166.355121 153.552)
		(mid 166.178344 153.625223)
		(end 166.105121 153.802)
		(width 0.148)
		(layer "In4.Cu")
		(net 269)
	)
	(arc
		(start 167.125501 155.552)
		(mid 166.948724 155.625223)
		(end 166.875501 155.802)
		(width 0.148)
		(layer "In4.Cu")
		(net 269)
	)
	(arc
		(start 166.105121 154.802)
		(mid 166.178344 154.978777)
		(end 166.355121 155.052)
		(width 0.148)
		(layer "In4.Cu")
		(net 269)
	)
	(arc
		(start 167.395881 155.052)
		(mid 167.572658 155.125223)
		(end 167.645881 155.302)
		(width 0.148)
		(layer "In4.Cu")
		(net 269)
	)
	(arc
		(start 166.355121 151.552)
		(mid 166.178344 151.625223)
		(end 166.105121 151.802)
		(width 0.148)
		(layer "In4.Cu")
		(net 269)
	)
	(arc
		(start 166.105121 150.802)
		(mid 166.178344 150.978777)
		(end 166.355121 151.052)
		(width 0.148)
		(layer "In4.Cu")
		(net 269)
	)
	(arc
		(start 167.645881 152.302)
		(mid 167.572658 152.478777)
		(end 167.395881 152.552)
		(width 0.148)
		(layer "In4.Cu")
		(net 269)
	)
	(segment
		(start 166.900001 146.2025)
		(end 166.900001 147.2775)
		(width 0.201)
		(layer "F.Cu")
		(net 270)
	)
	(segment
		(start 151.375501 170.302)
		(end 151.875001 169.8025)
		(width 0.256)
		(layer "F.Cu")
		(net 270)
	)
	(via
		(at 151.875001 169.8025)
		(size 0.45)
		(drill 0.1)
		(layers "F.Cu" "B.Cu")
		(net 270)
	)
	(via
		(at 166.900001 147.2775)
		(size 0.45)
		(drill 0.1)
		(layers "F.Cu" "B.Cu")
		(net 270)
	)
	(segment
		(start 164.601265 164.141722)
		(end 164.601264 164.141723)
		(width 0.148)
		(layer "In4.Cu")
		(net 270)
	)
	(segment
		(start 161.895427 166.032077)
		(end 161.895427 166.032074)
		(width 0.148)
		(layer "In4.Cu")
		(net 270)
	)
	(segment
		(start 164.846438 162.265577)
		(end 164.846437 162.265578)
		(width 0.148)
		(layer "In4.Cu")
		(net 270)
	)
	(segment
		(start 161.310907 166.154661)
		(end 161.77284 166.616593)
		(width 0.148)
		(layer "In4.Cu")
		(net 270)
	)
	(segment
		(start 166.260649 161.204918)
		(end 166.260649 161.204919)
		(width 0.148)
		(layer "In4.Cu")
		(net 270)
	)
	(segment
		(start 165.553543 161.912025)
		(end 166.015476 162.373957)
		(width 0.148)
		(layer "In4.Cu")
		(net 270)
	)
	(segment
		(start 162.018013 165.447555)
		(end 162.479946 165.909487)
		(width 0.148)
		(layer "In4.Cu")
		(net 270)
	)
	(segment
		(start 156.351501 171.576)
		(end 153.700501 171.576)
		(width 0.148)
		(layer "In4.Cu")
		(net 270)
	)
	(segment
		(start 163.309639 164.617865)
		(end 163.309639 164.617862)
		(width 0.148)
		(layer "In4.Cu")
		(net 270)
	)
	(segment
		(start 162.018013 165.447554)
		(end 162.018013 165.447555)
		(width 0.148)
		(layer "In4.Cu")
		(net 270)
	)
	(segment
		(start 165.553543 161.912024)
		(end 165.553543 161.912025)
		(width 0.148)
		(layer "In4.Cu")
		(net 270)
	)
	(segment
		(start 162.602533 165.324971)
		(end 162.602533 165.324968)
		(width 0.148)
		(layer "In4.Cu")
		(net 270)
	)
	(segment
		(start 164.24771 164.141724)
		(end 164.016745 163.910759)
		(width 0.148)
		(layer "In4.Cu")
		(net 270)
	)
	(segment
		(start 170.625501 151.003)
		(end 170.625501 157.302)
		(width 0.148)
		(layer "In4.Cu")
		(net 270)
	)
	(segment
		(start 163.540604 164.84883)
		(end 163.309639 164.617865)
		(width 0.148)
		(layer "In4.Cu")
		(net 270)
	)
	(segment
		(start 167.076138 161.313297)
		(end 166.845173 161.082332)
		(width 0.148)
		(layer "In4.Cu")
		(net 270)
	)
	(segment
		(start 161.310908 165.801107)
		(end 161.310907 165.801108)
		(width 0.148)
		(layer "In4.Cu")
		(net 270)
	)
	(segment
		(start 161.772841 166.970146)
		(end 161.77284 166.970147)
		(width 0.148)
		(layer "In4.Cu")
		(net 270)
	)
	(segment
		(start 163.187053 165.555934)
		(end 163.187052 165.555935)
		(width 0.148)
		(layer "In4.Cu")
		(net 270)
	)
	(segment
		(start 170.625501 157.302)
		(end 167.375501 160.552)
		(width 0.148)
		(layer "In4.Cu")
		(net 270)
	)
	(segment
		(start 153.700501 171.576)
		(end 151.927001 169.8025)
		(width 0.148)
		(layer "In4.Cu")
		(net 270)
	)
	(segment
		(start 166.138063 161.789441)
		(end 166.138063 161.789438)
		(width 0.148)
		(layer "In4.Cu")
		(net 270)
	)
	(segment
		(start 164.247712 164.141723)
		(end 164.24771 164.141724)
		(width 0.148)
		(layer "In4.Cu")
		(net 270)
	)
	(segment
		(start 166.36903 162.020405)
		(end 166.369028 162.020406)
		(width 0.148)
		(layer "In4.Cu")
		(net 270)
	)
	(segment
		(start 167.375501 160.905554)
		(end 167.429691 160.959744)
		(width 0.148)
		(layer "In4.Cu")
		(net 270)
	)
	(segment
		(start 164.016745 163.910759)
		(end 164.016745 163.910756)
		(width 0.148)
		(layer "In4.Cu")
		(net 270)
	)
	(segment
		(start 163.894159 164.848828)
		(end 163.894158 164.848829)
		(width 0.148)
		(layer "In4.Cu")
		(net 270)
	)
	(segment
		(start 166.138063 161.789438)
		(end 165.907097 161.558472)
		(width 0.148)
		(layer "In4.Cu")
		(net 270)
	)
	(segment
		(start 164.723851 163.203653)
		(end 164.723851 163.20365)
		(width 0.148)
		(layer "In4.Cu")
		(net 270)
	)
	(segment
		(start 166.015477 162.72751)
		(end 166.015476 162.727511)
		(width 0.148)
		(layer "In4.Cu")
		(net 270)
	)
	(segment
		(start 162.725119 164.740449)
		(end 163.187052 165.202381)
		(width 0.148)
		(layer "In4.Cu")
		(net 270)
	)
	(segment
		(start 164.139332 162.972683)
		(end 164.139331 162.972684)
		(width 0.148)
		(layer "In4.Cu")
		(net 270)
	)
	(segment
		(start 162.833498 165.555936)
		(end 162.602533 165.324971)
		(width 0.148)
		(layer "In4.Cu")
		(net 270)
	)
	(segment
		(start 167.42969 161.313297)
		(end 167.42969 161.313298)
		(width 0.148)
		(layer "In4.Cu")
		(net 270)
	)
	(segment
		(start 166.900001 147.2775)
		(end 170.625501 151.003)
		(width 0.148)
		(layer "In4.Cu")
		(net 270)
	)
	(segment
		(start 165.308371 163.434616)
		(end 165.30837 163.434617)
		(width 0.148)
		(layer "In4.Cu")
		(net 270)
	)
	(segment
		(start 162.8335 165.555935)
		(end 162.833498 165.555936)
		(width 0.148)
		(layer "In4.Cu")
		(net 270)
	)
	(segment
		(start 165.430957 162.496544)
		(end 165.199991 162.265578)
		(width 0.148)
		(layer "In4.Cu")
		(net 270)
	)
	(segment
		(start 164.954816 163.434618)
		(end 164.723851 163.203653)
		(width 0.148)
		(layer "In4.Cu")
		(net 270)
	)
	(segment
		(start 165.430957 162.496547)
		(end 165.430957 162.496544)
		(width 0.148)
		(layer "In4.Cu")
		(net 270)
	)
	(segment
		(start 164.723851 163.20365)
		(end 164.492885 162.972684)
		(width 0.148)
		(layer "In4.Cu")
		(net 270)
	)
	(segment
		(start 167.076138 161.313298)
		(end 167.076138 161.313297)
		(width 0.148)
		(layer "In4.Cu")
		(net 270)
	)
	(segment
		(start 166.260649 161.204919)
		(end 166.722582 161.666851)
		(width 0.148)
		(layer "In4.Cu")
		(net 270)
	)
	(segment
		(start 162.126392 166.263042)
		(end 161.895427 166.032077)
		(width 0.148)
		(layer "In4.Cu")
		(net 270)
	)
	(segment
		(start 165.661922 162.727512)
		(end 165.430957 162.496547)
		(width 0.148)
		(layer "In4.Cu")
		(net 270)
	)
	(segment
		(start 164.846437 162.61913)
		(end 164.846437 162.619131)
		(width 0.148)
		(layer "In4.Cu")
		(net 270)
	)
	(segment
		(start 161.419286 166.970148)
		(end 161.365097 166.915959)
		(width 0.148)
		(layer "In4.Cu")
		(net 270)
	)
	(segment
		(start 161.011544 166.91596)
		(end 161.011545 166.915958)
		(width 0.148)
		(layer "In4.Cu")
		(net 270)
	)
	(segment
		(start 162.018014 165.094001)
		(end 162.018013 165.094002)
		(width 0.148)
		(layer "In4.Cu")
		(net 270)
	)
	(segment
		(start 161.011545 166.915958)
		(end 156.351501 171.576)
		(width 0.148)
		(layer "In4.Cu")
		(net 270)
	)
	(segment
		(start 161.419288 166.970147)
		(end 161.419286 166.970148)
		(width 0.148)
		(layer "In4.Cu")
		(net 270)
	)
	(segment
		(start 166.845169 161.082332)
		(end 166.614203 160.851366)
		(width 0.148)
		(layer "In4.Cu")
		(net 270)
	)
	(segment
		(start 164.846437 162.619131)
		(end 165.30837 163.081063)
		(width 0.148)
		(layer "In4.Cu")
		(net 270)
	)
	(segment
		(start 163.432225 164.033343)
		(end 163.894158 164.495275)
		(width 0.148)
		(layer "In4.Cu")
		(net 270)
	)
	(segment
		(start 163.309639 164.617862)
		(end 163.078673 164.386896)
		(width 0.148)
		(layer "In4.Cu")
		(net 270)
	)
	(segment
		(start 165.553544 161.558471)
		(end 165.553543 161.558472)
		(width 0.148)
		(layer "In4.Cu")
		(net 270)
	)
	(segment
		(start 166.722583 162.020404)
		(end 166.722582 162.020405)
		(width 0.148)
		(layer "In4.Cu")
		(net 270)
	)
	(segment
		(start 164.016745 163.910756)
		(end 163.785779 163.67979)
		(width 0.148)
		(layer "In4.Cu")
		(net 270)
	)
	(segment
		(start 166.369028 162.020406)
		(end 166.138063 161.789441)
		(width 0.148)
		(layer "In4.Cu")
		(net 270)
	)
	(segment
		(start 164.954818 163.434617)
		(end 164.954816 163.434618)
		(width 0.148)
		(layer "In4.Cu")
		(net 270)
	)
	(segment
		(start 161.310907 166.15466)
		(end 161.310907 166.154661)
		(width 0.148)
		(layer "In4.Cu")
		(net 270)
	)
	(segment
		(start 164.139331 163.326237)
		(end 164.601264 163.788169)
		(width 0.148)
		(layer "In4.Cu")
		(net 270)
	)
	(segment
		(start 162.725119 164.740448)
		(end 162.725119 164.740449)
		(width 0.148)
		(layer "In4.Cu")
		(net 270)
	)
	(segment
		(start 166.845173 161.082332)
		(end 166.845169 161.082332)
		(width 0.148)
		(layer "In4.Cu")
		(net 270)
	)
	(segment
		(start 162.602533 165.324968)
		(end 162.371567 165.094002)
		(width 0.148)
		(layer "In4.Cu")
		(net 270)
	)
	(segment
		(start 165.661924 162.727511)
		(end 165.661922 162.727512)
		(width 0.148)
		(layer "In4.Cu")
		(net 270)
	)
	(segment
		(start 163.432225 164.033342)
		(end 163.432225 164.033343)
		(width 0.148)
		(layer "In4.Cu")
		(net 270)
	)
	(segment
		(start 162.479947 166.26304)
		(end 162.479946 166.263041)
		(width 0.148)
		(layer "In4.Cu")
		(net 270)
	)
	(segment
		(start 163.432226 163.679789)
		(end 163.432225 163.67979)
		(width 0.148)
		(layer "In4.Cu")
		(net 270)
	)
	(segment
		(start 166.26065 160.851365)
		(end 166.260649 160.851366)
		(width 0.148)
		(layer "In4.Cu")
		(net 270)
	)
	(segment
		(start 161.895427 166.032074)
		(end 161.664461 165.801108)
		(width 0.148)
		(layer "In4.Cu")
		(net 270)
	)
	(segment
		(start 162.126394 166.263041)
		(end 162.126392 166.263042)
		(width 0.148)
		(layer "In4.Cu")
		(net 270)
	)
	(segment
		(start 163.540606 164.848829)
		(end 163.540604 164.84883)
		(width 0.148)
		(layer "In4.Cu")
		(net 270)
	)
	(segment
		(start 164.139331 163.326236)
		(end 164.139331 163.326237)
		(width 0.148)
		(layer "In4.Cu")
		(net 270)
	)
	(segment
		(start 151.927001 169.8025)
		(end 151.875001 169.8025)
		(width 0.148)
		(layer "In4.Cu")
		(net 270)
	)
	(segment
		(start 162.72512 164.386895)
		(end 162.725119 164.386896)
		(width 0.148)
		(layer "In4.Cu")
		(net 270)
	)
	(arc
		(start 167.375501 160.552)
		(mid 167.302278 160.728777)
		(end 167.375501 160.905554)
		(width 0.148)
		(layer "In4.Cu")
		(net 270)
	)
	(arc
		(start 162.479946 166.263041)
		(mid 162.303169 166.336265)
		(end 162.126394 166.263041)
		(width 0.148)
		(layer "In4.Cu")
		(net 270)
	)
	(arc
		(start 161.310907 165.801108)
		(mid 161.237684 165.977884)
		(end 161.310907 166.15466)
		(width 0.148)
		(layer "In4.Cu")
		(net 270)
	)
	(arc
		(start 166.722582 162.020405)
		(mid 166.545805 162.093629)
		(end 166.36903 162.020405)
		(width 0.148)
		(layer "In4.Cu")
		(net 270)
	)
	(arc
		(start 166.722582 161.666851)
		(mid 166.795806 161.843627)
		(end 166.722583 162.020404)
		(width 0.148)
		(layer "In4.Cu")
		(net 270)
	)
	(arc
		(start 165.907097 161.558472)
		(mid 165.730321 161.485248)
		(end 165.553544 161.558471)
		(width 0.148)
		(layer "In4.Cu")
		(net 270)
	)
	(arc
		(start 162.018013 165.094002)
		(mid 161.94479 165.270778)
		(end 162.018013 165.447554)
		(width 0.148)
		(layer "In4.Cu")
		(net 270)
	)
	(arc
		(start 164.846437 162.265578)
		(mid 164.773214 162.442354)
		(end 164.846437 162.61913)
		(width 0.148)
		(layer "In4.Cu")
		(net 270)
	)
	(arc
		(start 166.015476 162.727511)
		(mid 165.838699 162.800735)
		(end 165.661924 162.727511)
		(width 0.148)
		(layer "In4.Cu")
		(net 270)
	)
	(arc
		(start 164.492885 162.972684)
		(mid 164.316109 162.89946)
		(end 164.139332 162.972683)
		(width 0.148)
		(layer "In4.Cu")
		(net 270)
	)
	(arc
		(start 163.894158 164.495275)
		(mid 163.967382 164.672051)
		(end 163.894159 164.848828)
		(width 0.148)
		(layer "In4.Cu")
		(net 270)
	)
	(arc
		(start 165.30837 163.081063)
		(mid 165.381594 163.257839)
		(end 165.308371 163.434616)
		(width 0.148)
		(layer "In4.Cu")
		(net 270)
	)
	(arc
		(start 162.479946 165.909487)
		(mid 162.55317 166.086263)
		(end 162.479947 166.26304)
		(width 0.148)
		(layer "In4.Cu")
		(net 270)
	)
	(arc
		(start 167.429691 160.959744)
		(mid 167.502914 161.136521)
		(end 167.42969 161.313297)
		(width 0.148)
		(layer "In4.Cu")
		(net 270)
	)
	(arc
		(start 167.42969 161.313298)
		(mid 167.252915 161.38652)
		(end 167.076138 161.313298)
		(width 0.148)
		(layer "In4.Cu")
		(net 270)
	)
	(arc
		(start 166.015476 162.373957)
		(mid 166.0887 162.550733)
		(end 166.015477 162.72751)
		(width 0.148)
		(layer "In4.Cu")
		(net 270)
	)
	(arc
		(start 163.432225 163.67979)
		(mid 163.359002 163.856566)
		(end 163.432225 164.033342)
		(width 0.148)
		(layer "In4.Cu")
		(net 270)
	)
	(arc
		(start 162.725119 164.386896)
		(mid 162.651896 164.563672)
		(end 162.725119 164.740448)
		(width 0.148)
		(layer "In4.Cu")
		(net 270)
	)
	(arc
		(start 163.078673 164.386896)
		(mid 162.901897 164.313672)
		(end 162.72512 164.386895)
		(width 0.148)
		(layer "In4.Cu")
		(net 270)
	)
	(arc
		(start 165.30837 163.434617)
		(mid 165.131593 163.507841)
		(end 164.954818 163.434617)
		(width 0.148)
		(layer "In4.Cu")
		(net 270)
	)
	(arc
		(start 164.601264 164.141723)
		(mid 164.424487 164.214947)
		(end 164.247712 164.141723)
		(width 0.148)
		(layer "In4.Cu")
		(net 270)
	)
	(arc
		(start 165.553543 161.558472)
		(mid 165.48032 161.735248)
		(end 165.553543 161.912024)
		(width 0.148)
		(layer "In4.Cu")
		(net 270)
	)
	(arc
		(start 161.77284 166.616593)
		(mid 161.846064 166.793369)
		(end 161.772841 166.970146)
		(width 0.148)
		(layer "In4.Cu")
		(net 270)
	)
	(arc
		(start 161.664461 165.801108)
		(mid 161.487685 165.727884)
		(end 161.310908 165.801107)
		(width 0.148)
		(layer "In4.Cu")
		(net 270)
	)
	(arc
		(start 166.614203 160.851366)
		(mid 166.437427 160.778142)
		(end 166.26065 160.851365)
		(width 0.148)
		(layer "In4.Cu")
		(net 270)
	)
	(arc
		(start 164.601264 163.788169)
		(mid 164.674488 163.964945)
		(end 164.601265 164.141722)
		(width 0.148)
		(layer "In4.Cu")
		(net 270)
	)
	(arc
		(start 163.894158 164.848829)
		(mid 163.717381 164.922053)
		(end 163.540606 164.848829)
		(width 0.148)
		(layer "In4.Cu")
		(net 270)
	)
	(arc
		(start 162.371567 165.094002)
		(mid 162.194791 165.020778)
		(end 162.018014 165.094001)
		(width 0.148)
		(layer "In4.Cu")
		(net 270)
	)
	(arc
		(start 161.77284 166.970147)
		(mid 161.596063 167.043371)
		(end 161.419288 166.970147)
		(width 0.148)
		(layer "In4.Cu")
		(net 270)
	)
	(arc
		(start 163.187052 165.202381)
		(mid 163.260276 165.379157)
		(end 163.187053 165.555934)
		(width 0.148)
		(layer "In4.Cu")
		(net 270)
	)
	(arc
		(start 165.199991 162.265578)
		(mid 165.023215 162.192354)
		(end 164.846438 162.265577)
		(width 0.148)
		(layer "In4.Cu")
		(net 270)
	)
	(arc
		(start 161.365097 166.915959)
		(mid 161.18832 166.842736)
		(end 161.011544 166.91596)
		(width 0.148)
		(layer "In4.Cu")
		(net 270)
	)
	(arc
		(start 164.139331 162.972684)
		(mid 164.066108 163.14946)
		(end 164.139331 163.326236)
		(width 0.148)
		(layer "In4.Cu")
		(net 270)
	)
	(arc
		(start 166.260649 160.851366)
		(mid 166.187426 161.028142)
		(end 166.260649 161.204918)
		(width 0.148)
		(layer "In4.Cu")
		(net 270)
	)
	(arc
		(start 163.187052 165.555935)
		(mid 163.010275 165.629159)
		(end 162.8335 165.555935)
		(width 0.148)
		(layer "In4.Cu")
		(net 270)
	)
	(arc
		(start 163.785779 163.67979)
		(mid 163.609003 163.606566)
		(end 163.432226 163.679789)
		(width 0.148)
		(layer "In4.Cu")
		(net 270)
	)
	(segment
		(start 150.375501 170.302)
		(end 150.875001 169.8025)
		(width 0.256)
		(layer "F.Cu")
		(net 271)
	)
	(segment
		(start 167.650001 138.8025)
		(end 167.650001 139.8775)
		(width 0.201)
		(layer "F.Cu")
		(net 271)
	)
	(via
		(at 167.650001 139.8775)
		(size 0.45)
		(drill 0.1)
		(layers "F.Cu" "B.Cu")
		(net 271)
	)
	(via
		(at 150.875001 169.8025)
		(size 0.45)
		(drill 0.1)
		(layers "F.Cu" "B.Cu")
		(net 271)
	)
	(segment
		(start 153.500501 170.376)
		(end 152.400501 169.276)
		(width 0.148)
		(layer "In4.Cu")
		(net 271)
	)
	(segment
		(start 168.933426 154.302)
		(end 169.817576 154.302)
		(width 0.148)
		(layer "In4.Cu")
		(net 271)
	)
	(segment
		(start 166.474501 146.303)
		(end 166.474501 147.852)
		(width 0.148)
		(layer "In4.Cu")
		(net 271)
	)
	(segment
		(start 155.801501 170.376)
		(end 153.500501 170.376)
		(width 0.148)
		(layer "In4.Cu")
		(net 271)
	)
	(segment
		(start 167.650001 143.0275)
		(end 166.974502 143.702999)
		(width 0.148)
		(layer "In4.Cu")
		(net 271)
	)
	(segment
		(start 166.474501 147.852)
		(end 169.375501 150.753)
		(width 0.148)
		(layer "In4.Cu")
		(net 271)
	)
	(segment
		(start 166.974502 143.702999)
		(end 166.974502 145.802999)
		(width 0.148)
		(layer "In4.Cu")
		(net 271)
	)
	(segment
		(start 151.401501 169.276)
		(end 150.875001 169.8025)
		(width 0.148)
		(layer "In4.Cu")
		(net 271)
	)
	(segment
		(start 169.375501 150.753)
		(end 169.375501 151.052)
		(width 0.148)
		(layer "In4.Cu")
		(net 271)
	)
	(segment
		(start 168.933426 155.302)
		(end 169.817576 155.302)
		(width 0.148)
		(layer "In4.Cu")
		(net 271)
	)
	(segment
		(start 169.375501 156.802)
		(end 155.801501 170.376)
		(width 0.148)
		(layer "In4.Cu")
		(net 271)
	)
	(segment
		(start 168.933426 151.802)
		(end 169.817576 151.802)
		(width 0.148)
		(layer "In4.Cu")
		(net 271)
	)
	(segment
		(start 166.974502 145.802999)
		(end 166.474501 146.303)
		(width 0.148)
		(layer "In4.Cu")
		(net 271)
	)
	(segment
		(start 168.933426 154.802)
		(end 169.817576 154.802)
		(width 0.148)
		(layer "In4.Cu")
		(net 271)
	)
	(segment
		(start 168.933426 153.802)
		(end 169.817576 153.802)
		(width 0.148)
		(layer "In4.Cu")
		(net 271)
	)
	(segment
		(start 169.625501 151.302)
		(end 169.817576 151.302)
		(width 0.148)
		(layer "In4.Cu")
		(net 271)
	)
	(segment
		(start 152.400501 169.276)
		(end 151.401501 169.276)
		(width 0.148)
		(layer "In4.Cu")
		(net 271)
	)
	(segment
		(start 168.933426 153.302)
		(end 169.817576 153.302)
		(width 0.148)
		(layer "In4.Cu")
		(net 271)
	)
	(segment
		(start 169.375501 156.052)
		(end 169.375501 156.802)
		(width 0.148)
		(layer "In4.Cu")
		(net 271)
	)
	(segment
		(start 167.650001 139.8775)
		(end 167.650001 143.0275)
		(width 0.148)
		(layer "In4.Cu")
		(net 271)
	)
	(segment
		(start 168.933426 152.302)
		(end 169.817576 152.302)
		(width 0.148)
		(layer "In4.Cu")
		(net 271)
	)
	(segment
		(start 169.817576 155.802)
		(end 169.625501 155.802)
		(width 0.148)
		(layer "In4.Cu")
		(net 271)
	)
	(segment
		(start 168.933426 152.802)
		(end 169.817576 152.802)
		(width 0.148)
		(layer "In4.Cu")
		(net 271)
	)
	(arc
		(start 169.817576 155.302)
		(mid 169.994353 155.375223)
		(end 170.067576 155.552)
		(width 0.148)
		(layer "In4.Cu")
		(net 271)
	)
	(arc
		(start 168.683426 152.052)
		(mid 168.756649 152.228777)
		(end 168.933426 152.302)
		(width 0.148)
		(layer "In4.Cu")
		(net 271)
	)
	(arc
		(start 170.067576 154.552)
		(mid 169.994353 154.728777)
		(end 169.817576 154.802)
		(width 0.148)
		(layer "In4.Cu")
		(net 271)
	)
	(arc
		(start 168.933426 154.802)
		(mid 168.756649 154.875223)
		(end 168.683426 155.052)
		(width 0.148)
		(layer "In4.Cu")
		(net 271)
	)
	(arc
		(start 169.375501 151.052)
		(mid 169.448724 151.228777)
		(end 169.625501 151.302)
		(width 0.148)
		(layer "In4.Cu")
		(net 271)
	)
	(arc
		(start 168.933426 151.802)
		(mid 168.756649 151.875223)
		(end 168.683426 152.052)
		(width 0.148)
		(layer "In4.Cu")
		(net 271)
	)
	(arc
		(start 168.933426 153.802)
		(mid 168.756649 153.875223)
		(end 168.683426 154.052)
		(width 0.148)
		(layer "In4.Cu")
		(net 271)
	)
	(arc
		(start 170.067576 151.552)
		(mid 169.994353 151.728777)
		(end 169.817576 151.802)
		(width 0.148)
		(layer "In4.Cu")
		(net 271)
	)
	(arc
		(start 168.933426 152.802)
		(mid 168.756649 152.875223)
		(end 168.683426 153.052)
		(width 0.148)
		(layer "In4.Cu")
		(net 271)
	)
	(arc
		(start 168.683426 155.052)
		(mid 168.756649 155.228777)
		(end 168.933426 155.302)
		(width 0.148)
		(layer "In4.Cu")
		(net 271)
	)
	(arc
		(start 170.067576 153.552)
		(mid 169.994353 153.728777)
		(end 169.817576 153.802)
		(width 0.148)
		(layer "In4.Cu")
		(net 271)
	)
	(arc
		(start 168.683426 153.052)
		(mid 168.756649 153.228777)
		(end 168.933426 153.302)
		(width 0.148)
		(layer "In4.Cu")
		(net 271)
	)
	(arc
		(start 170.067576 155.552)
		(mid 169.994353 155.728777)
		(end 169.817576 155.802)
		(width 0.148)
		(layer "In4.Cu")
		(net 271)
	)
	(arc
		(start 170.067576 152.552)
		(mid 169.994353 152.728777)
		(end 169.817576 152.802)
		(width 0.148)
		(layer "In4.Cu")
		(net 271)
	)
	(arc
		(start 169.817576 154.302)
		(mid 169.994353 154.375223)
		(end 170.067576 154.552)
		(width 0.148)
		(layer "In4.Cu")
		(net 271)
	)
	(arc
		(start 168.683426 154.052)
		(mid 168.756649 154.228777)
		(end 168.933426 154.302)
		(width 0.148)
		(layer "In4.Cu")
		(net 271)
	)
	(arc
		(start 169.817576 152.302)
		(mid 169.994353 152.375223)
		(end 170.067576 152.552)
		(width 0.148)
		(layer "In4.Cu")
		(net 271)
	)
	(arc
		(start 169.817576 153.302)
		(mid 169.994353 153.375223)
		(end 170.067576 153.552)
		(width 0.148)
		(layer "In4.Cu")
		(net 271)
	)
	(arc
		(start 169.817576 151.302)
		(mid 169.994353 151.375223)
		(end 170.067576 151.552)
		(width 0.148)
		(layer "In4.Cu")
		(net 271)
	)
	(arc
		(start 169.625501 155.802)
		(mid 169.448724 155.875223)
		(end 169.375501 156.052)
		(width 0.148)
		(layer "In4.Cu")
		(net 271)
	)
	(segment
		(start 131.376501 180.301)
		(end 130.877001 180.8005)
		(width 0.256)
		(layer "F.Cu")
		(net 272)
	)
	(segment
		(start 155.649501 176.826)
		(end 155.026 176.826)
		(width 0.201)
		(layer "F.Cu")
		(net 272)
	)
	(segment
		(start 155.026 176.826)
		(end 155 176.8)
		(width 0.1)
		(layer "F.Cu")
		(net 272)
	)
	(via
		(at 155 176.8)
		(size 0.45)
		(drill 0.1)
		(layers "F.Cu" "B.Cu")
		(net 272)
	)
	(via
		(at 152.8 172.806222)
		(size 0.45)
		(drill 0.1)
		(layers "F.Cu" "B.Cu")
		(net 272)
	)
	(via
		(at 130.877001 180.8005)
		(size 0.45)
		(drill 0.1)
		(layers "F.Cu" "B.Cu")
		(net 272)
	)
	(segment
		(start 152.8 173.45)
		(end 153.25 173.9)
		(width 0.15)
		(layer "B.Cu")
		(net 272)
	)
	(segment
		(start 154.55 173.9)
		(end 155.35 174.7)
		(width 0.15)
		(layer "B.Cu")
		(net 272)
	)
	(segment
		(start 153.25 173.9)
		(end 154.55 173.9)
		(width 0.15)
		(layer "B.Cu")
		(net 272)
	)
	(segment
		(start 155.35 176.45)
		(end 155 176.8)
		(width 0.15)
		(layer "B.Cu")
		(net 272)
	)
	(segment
		(start 152.8 172.806222)
		(end 152.8 173.45)
		(width 0.15)
		(layer "B.Cu")
		(net 272)
	)
	(segment
		(start 155.35 174.7)
		(end 155.35 176.45)
		(width 0.15)
		(layer "B.Cu")
		(net 272)
	)
	(segment
		(start 130.877001 180.8005)
		(end 131.4 180.277501)
		(width 0.1)
		(layer "In9.Cu")
		(net 272)
	)
	(segment
		(start 144.65 172.3)
		(end 152.293778 172.3)
		(width 0.1)
		(layer "In9.Cu")
		(net 272)
	)
	(segment
		(start 143.4 175.3)
		(end 144.35 174.35)
		(width 0.1)
		(layer "In9.Cu")
		(net 272)
	)
	(segment
		(start 144.35 174.35)
		(end 144.35 172.6)
		(width 0.1)
		(layer "In9.Cu")
		(net 272)
	)
	(segment
		(start 152.293778 172.3)
		(end 152.8 172.806222)
		(width 0.1)
		(layer "In9.Cu")
		(net 272)
	)
	(segment
		(start 131.4 180.277501)
		(end 131.4 175.49617)
		(width 0.1)
		(layer "In9.Cu")
		(net 272)
	)
	(segment
		(start 131.59617 175.3)
		(end 143.4 175.3)
		(width 0.1)
		(layer "In9.Cu")
		(net 272)
	)
	(segment
		(start 131.4 175.49617)
		(end 131.59617 175.3)
		(width 0.1)
		(layer "In9.Cu")
		(net 272)
	)
	(segment
		(start 144.35 172.6)
		(end 144.65 172.3)
		(width 0.1)
		(layer "In9.Cu")
		(net 272)
	)
	(segment
		(start 131.376501 166.302)
		(end 130.877001 165.8025)
		(width 0.256)
		(layer "F.Cu")
		(net 273)
	)
	(via
		(at 130.877001 165.8025)
		(size 0.45)
		(drill 0.1)
		(layers "F.Cu" "B.Cu")
		(net 273)
	)
	(segment
		(start 130.877001 165.8025)
		(end 130.277001 165.2025)
		(width 0.15)
		(layer "B.Cu")
		(net 273)
	)
	(segment
		(start 124.4 145.700002)
		(end 124.4 144.85)
		(width 0.15)
		(layer "B.Cu")
		(net 273)
	)
	(segment
		(start 130.277001 164.579501)
		(end 129.9 164.2025)
		(width 0.15)
		(layer "B.Cu")
		(net 273)
	)
	(segment
		(start 129.3 163.791185)
		(end 129.3 156.1)
		(width 0.15)
		(layer "B.Cu")
		(net 273)
	)
	(segment
		(start 129.711315 164.2025)
		(end 129.3 163.791185)
		(width 0.15)
		(layer "B.Cu")
		(net 273)
	)
	(segment
		(start 109.15 141.3)
		(end 108.015 141.3)
		(width 0.15)
		(layer "B.Cu")
		(net 273)
	)
	(segment
		(start 109.65 141.8)
		(end 109.15 141.3)
		(width 0.15)
		(layer "B.Cu")
		(net 273)
	)
	(segment
		(start 109.65 142.5)
		(end 109.65 141.8)
		(width 0.15)
		(layer "B.Cu")
		(net 273)
	)
	(segment
		(start 108.015 141.3)
		(end 107.4 141.915)
		(width 0.15)
		(layer "B.Cu")
		(net 273)
	)
	(segment
		(start 129.9 164.2025)
		(end 129.711315 164.2025)
		(width 0.15)
		(layer "B.Cu")
		(net 273)
	)
	(segment
		(start 130.277001 165.2025)
		(end 130.277001 164.579501)
		(width 0.15)
		(layer "B.Cu")
		(net 273)
	)
	(segment
		(start 124.9 146.200002)
		(end 124.4 145.700002)
		(width 0.15)
		(layer "B.Cu")
		(net 273)
	)
	(segment
		(start 124.4 144.85)
		(end 123 143.45)
		(width 0.15)
		(layer "B.Cu")
		(net 273)
	)
	(segment
		(start 129.3 156.1)
		(end 124.9 151.7)
		(width 0.15)
		(layer "B.Cu")
		(net 273)
	)
	(segment
		(start 110.6 143.45)
		(end 109.65 142.5)
		(width 0.15)
		(layer "B.Cu")
		(net 273)
	)
	(segment
		(start 123 143.45)
		(end 110.6 143.45)
		(width 0.15)
		(layer "B.Cu")
		(net 273)
	)
	(segment
		(start 124.9 151.7)
		(end 124.9 146.200002)
		(width 0.15)
		(layer "B.Cu")
		(net 273)
	)
	(segment
		(start 130.376501 166.302)
		(end 129.877001 165.8025)
		(width 0.256)
		(layer "F.Cu")
		(net 274)
	)
	(via
		(at 129.877001 165.8025)
		(size 0.45)
		(drill 0.1)
		(layers "F.Cu" "B.Cu")
		(net 274)
	)
	(via
		(at 142.725 141.925)
		(size 0.45)
		(drill 0.1)
		(layers "F.Cu" "B.Cu")
		(net 274)
	)
	(segment
		(start 143.4 141.915)
		(end 142.735 141.915)
		(width 0.15)
		(layer "B.Cu")
		(net 274)
	)
	(segment
		(start 142.735 141.915)
		(end 142.725 141.925)
		(width 0.15)
		(layer "B.Cu")
		(net 274)
	)
	(segment
		(start 130.35 161.25)
		(end 130.35 165.329501)
		(width 0.1)
		(layer "In9.Cu")
		(net 274)
	)
	(segment
		(start 127.4 158.3)
		(end 130.35 161.25)
		(width 0.1)
		(layer "In9.Cu")
		(net 274)
	)
	(segment
		(start 128.275 139.075)
		(end 127.550001 139.799999)
		(width 0.1)
		(layer "In9.Cu")
		(net 274)
	)
	(segment
		(start 127.800001 142.924999)
		(end 127.800001 145.399999)
		(width 0.1)
		(layer "In9.Cu")
		(net 274)
	)
	(segment
		(start 142.725 141.886815)
		(end 142.425 141.586815)
		(width 0.1)
		(layer "In9.Cu")
		(net 274)
	)
	(segment
		(start 130.35 165.329501)
		(end 129.877001 165.8025)
		(width 0.1)
		(layer "In9.Cu")
		(net 274)
	)
	(segment
		(start 127.4 145.8)
		(end 127.4 158.3)
		(width 0.1)
		(layer "In9.Cu")
		(net 274)
	)
	(segment
		(start 127.550001 139.799999)
		(end 127.550001 142.674999)
		(width 0.1)
		(layer "In9.Cu")
		(net 274)
	)
	(segment
		(start 127.800001 145.399999)
		(end 127.4 145.8)
		(width 0.1)
		(layer "In9.Cu")
		(net 274)
	)
	(segment
		(start 142.425 139.7)
		(end 141.8 139.075)
		(width 0.1)
		(layer "In9.Cu")
		(net 274)
	)
	(segment
		(start 141.8 139.075)
		(end 128.275 139.075)
		(width 0.1)
		(layer "In9.Cu")
		(net 274)
	)
	(segment
		(start 127.550001 142.674999)
		(end 127.800001 142.924999)
		(width 0.1)
		(layer "In9.Cu")
		(net 274)
	)
	(segment
		(start 142.725 141.925)
		(end 142.725 141.886815)
		(width 0.1)
		(layer "In9.Cu")
		(net 274)
	)
	(segment
		(start 142.425 141.586815)
		(end 142.425 139.7)
		(width 0.1)
		(layer "In9.Cu")
		(net 274)
	)
	(segment
		(start 167.900002 146.2025)
		(end 167.900001 147.277499)
		(width 0.201)
		(layer "F.Cu")
		(net 275)
	)
	(segment
		(start 150.375501 171.302)
		(end 150.875001 170.8025)
		(width 0.256)
		(layer "F.Cu")
		(net 275)
	)
	(via
		(at 167.900001 147.277499)
		(size 0.45)
		(drill 0.1)
		(layers "F.Cu" "B.Cu")
		(net 275)
	)
	(via
		(at 150.875001 170.8025)
		(size 0.45)
		(drill 0.1)
		(layers "F.Cu" "B.Cu")
		(net 275)
	)
	(segment
		(start 161.52159 162.77307)
		(end 161.521589 162.77307)
		(width 0.148)
		(layer "In2.Cu")
		(net 275)
	)
	(segment
		(start 156.925381 167.369278)
		(end 157.208222 167.65212)
		(width 0.148)
		(layer "In2.Cu")
		(net 275)
	)
	(segment
		(start 166.393838 151.802)
		(end 166.375501 151.802)
		(width 0.148)
		(layer "In2.Cu")
		(net 275)
	)
	(segment
		(start 157.632491 166.379325)
		(end 157.63249 166.379327)
		(width 0.148)
		(layer "In2.Cu")
		(net 275)
	)
	(segment
		(start 158.268887 166.591456)
		(end 157.986045 166.308615)
		(width 0.148)
		(layer "In2.Cu")
		(net 275)
	)
	(segment
		(start 163.572203 161.288139)
		(end 163.572204 161.288139)
		(width 0.148)
		(layer "In2.Cu")
		(net 275)
	)
	(segment
		(start 162.228699 162.065961)
		(end 162.228698 162.065961)
		(width 0.148)
		(layer "In2.Cu")
		(net 275)
	)
	(segment
		(start 162.652964 161.358853)
		(end 162.582254 161.429562)
		(width 0.148)
		(layer "In2.Cu")
		(net 275)
	)
	(segment
		(start 156.854669 168.005674)
		(end 156.571827 167.722833)
		(width 0.148)
		(layer "In2.Cu")
		(net 275)
	)
	(segment
		(start 156.288983 167.722834)
		(end 156.218273 167.793543)
		(width 0.148)
		(layer "In2.Cu")
		(net 275)
	)
	(segment
		(start 154.874765 169.137052)
		(end 154.804055 169.207761)
		(width 0.148)
		(layer "In2.Cu")
		(net 275)
	)
	(segment
		(start 163.289362 161.005297)
		(end 163.572203 161.288139)
		(width 0.148)
		(layer "In2.Cu")
		(net 275)
	)
	(segment
		(start 167.900001 147.277499)
		(end 167.925001 147.302499)
		(width 0.148)
		(layer "In2.Cu")
		(net 275)
	)
	(segment
		(start 163.289363 160.722453)
		(end 163.289362 160.722455)
		(width 0.148)
		(layer "In2.Cu")
		(net 275)
	)
	(segment
		(start 155.794004 169.066338)
		(end 155.794005 169.066338)
		(width 0.148)
		(layer "In2.Cu")
		(net 275)
	)
	(segment
		(start 154.322001 170.2555)
		(end 151.422001 170.2555)
		(width 0.148)
		(layer "In2.Cu")
		(net 275)
	)
	(segment
		(start 155.086895 170.056289)
		(end 155.016186 170.126999)
		(width 0.148)
		(layer "In2.Cu")
		(net 275)
	)
	(segment
		(start 161.450876 163.409466)
		(end 161.450877 163.409466)
		(width 0.148)
		(layer "In2.Cu")
		(net 275)
	)
	(segment
		(start 159.329549 165.530793)
		(end 159.32955 165.530793)
		(width 0.148)
		(layer "In2.Cu")
		(net 275)
	)
	(segment
		(start 157.703201 166.308616)
		(end 157.632491 166.379325)
		(width 0.148)
		(layer "In2.Cu")
		(net 275)
	)
	(segment
		(start 165.69353 159.166812)
		(end 165.693531 159.166812)
		(width 0.148)
		(layer "In2.Cu")
		(net 275)
	)
	(segment
		(start 155.511164 168.500652)
		(end 155.511163 168.500654)
		(width 0.148)
		(layer "In2.Cu")
		(net 275)
	)
	(segment
		(start 161.875145 162.136671)
		(end 161.875144 162.136673)
		(width 0.148)
		(layer "In2.Cu")
		(net 275)
	)
	(segment
		(start 160.460927 163.550889)
		(end 160.460926 163.550891)
		(width 0.148)
		(layer "In2.Cu")
		(net 275)
	)
	(segment
		(start 163.572203 161.570982)
		(end 163.501493 161.641693)
		(width 0.148)
		(layer "In2.Cu")
		(net 275)
	)
	(segment
		(start 159.329549 165.813636)
		(end 159.258839 165.884347)
		(width 0.148)
		(layer "In2.Cu")
		(net 275)
	)
	(segment
		(start 159.753817 164.540842)
		(end 160.036658 164.823684)
		(width 0.148)
		(layer "In2.Cu")
		(net 275)
	)
	(segment
		(start 163.21865 161.641693)
		(end 162.935808 161.358852)
		(width 0.148)
		(layer "In2.Cu")
		(net 275)
	)
	(segment
		(start 158.55173 166.591456)
		(end 158.551729 166.591456)
		(width 0.148)
		(layer "In2.Cu")
		(net 275)
	)
	(segment
		(start 162.087275 163.055911)
		(end 162.087274 163.055911)
		(width 0.148)
		(layer "In2.Cu")
		(net 275)
	)
	(segment
		(start 166.125501 158.451998)
		(end 165.693529 158.883969)
		(width 0.148)
		(layer "In2.Cu")
		(net 275)
	)
	(segment
		(start 159.753818 164.257998)
		(end 159.753817 164.258)
		(width 0.148)
		(layer "In2.Cu")
		(net 275)
	)
	(segment
		(start 161.168035 163.126624)
		(end 161.450876 163.409466)
		(width 0.148)
		(layer "In2.Cu")
		(net 275)
	)
	(segment
		(start 157.844621 167.298565)
		(end 157.84462 167.298565)
		(width 0.148)
		(layer "In2.Cu")
		(net 275)
	)
	(segment
		(start 159.046709 164.965107)
		(end 159.046708 164.965109)
		(width 0.148)
		(layer "In2.Cu")
		(net 275)
	)
	(segment
		(start 161.945855 162.065962)
		(end 161.875145 162.136671)
		(width 0.148)
		(layer "In2.Cu")
		(net 275)
	)
	(segment
		(start 157.208222 167.65212)
		(end 157.208223 167.65212)
		(width 0.148)
		(layer "In2.Cu")
		(net 275)
	)
	(segment
		(start 160.107372 164.187288)
		(end 160.107371 164.187288)
		(width 0.148)
		(layer "In2.Cu")
		(net 275)
	)
	(segment
		(start 161.168036 162.84378)
		(end 161.168035 162.843782)
		(width 0.148)
		(layer "In2.Cu")
		(net 275)
	)
	(segment
		(start 163.360073 160.651744)
		(end 163.289363 160.722453)
		(width 0.148)
		(layer "In2.Cu")
		(net 275)
	)
	(segment
		(start 160.814481 163.480179)
		(end 160.81448 163.480179)
		(width 0.148)
		(layer "In2.Cu")
		(net 275)
	)
	(segment
		(start 163.501493 161.641693)
		(end 163.501492 161.641693)
		(width 0.148)
		(layer "In2.Cu")
		(net 275)
	)
	(segment
		(start 159.965948 165.177238)
		(end 159.965947 165.177238)
		(width 0.148)
		(layer "In2.Cu")
		(net 275)
	)
	(segment
		(start 156.218273 167.793543)
		(end 156.218272 167.793545)
		(width 0.148)
		(layer "In2.Cu")
		(net 275)
	)
	(segment
		(start 160.531637 163.48018)
		(end 160.460927 163.550889)
		(width 0.148)
		(layer "In2.Cu")
		(net 275)
	)
	(segment
		(start 165.339977 159.520366)
		(end 165.057135 159.237525)
		(width 0.148)
		(layer "In2.Cu")
		(net 275)
	)
	(segment
		(start 156.501113 168.642072)
		(end 156.430403 168.712783)
		(width 0.148)
		(layer "In2.Cu")
		(net 275)
	)
	(segment
		(start 160.036658 164.823684)
		(end 160.036659 164.823684)
		(width 0.148)
		(layer "In2.Cu")
		(net 275)
	)
	(segment
		(start 162.935808 161.358852)
		(end 162.935807 161.358852)
		(width 0.148)
		(layer "In2.Cu")
		(net 275)
	)
	(segment
		(start 157.986045 166.308615)
		(end 157.986044 166.308615)
		(width 0.148)
		(layer "In2.Cu")
		(net 275)
	)
	(segment
		(start 159.400263 164.894397)
		(end 159.400262 164.894397)
		(width 0.148)
		(layer "In2.Cu")
		(net 275)
	)
	(segment
		(start 160.673057 164.470129)
		(end 160.673056 164.470129)
		(width 0.148)
		(layer "In2.Cu")
		(net 275)
	)
	(segment
		(start 164.067182 159.944635)
		(end 163.996472 160.015344)
		(width 0.148)
		(layer "In2.Cu")
		(net 275)
	)
	(segment
		(start 155.086895 169.773446)
		(end 155.086896 169.773446)
		(width 0.148)
		(layer "In2.Cu")
		(net 275)
	)
	(segment
		(start 157.915331 167.227854)
		(end 157.844621 167.298565)
		(width 0.148)
		(layer "In2.Cu")
		(net 275)
	)
	(segment
		(start 162.511541 162.348802)
		(end 162.228699 162.065961)
		(width 0.148)
		(layer "In2.Cu")
		(net 275)
	)
	(segment
		(start 157.278936 167.015724)
		(end 157.278935 167.015724)
		(width 0.148)
		(layer "In2.Cu")
		(net 275)
	)
	(segment
		(start 157.915331 166.945011)
		(end 157.915332 166.945011)
		(width 0.148)
		(layer "In2.Cu")
		(net 275)
	)
	(segment
		(start 156.925382 167.086434)
		(end 156.925381 167.086436)
		(width 0.148)
		(layer "In2.Cu")
		(net 275)
	)
	(segment
		(start 164.70358 159.591079)
		(end 164.986421 159.873921)
		(width 0.148)
		(layer "In2.Cu")
		(net 275)
	)
	(segment
		(start 158.41031 165.601507)
		(end 158.3396 165.672216)
		(width 0.148)
		(layer "In2.Cu")
		(net 275)
	)
	(segment
		(start 159.046708 165.247951)
		(end 159.329549 165.530793)
		(width 0.148)
		(layer "In2.Cu")
		(net 275)
	)
	(segment
		(start 165.057135 159.237525)
		(end 165.057134 159.237525)
		(width 0.148)
		(layer "In2.Cu")
		(net 275)
	)
	(segment
		(start 155.440451 169.419892)
		(end 155.157609 169.137051)
		(width 0.148)
		(layer "In2.Cu")
		(net 275)
	)
	(segment
		(start 164.208602 160.934584)
		(end 164.208601 160.934584)
		(width 0.148)
		(layer "In2.Cu")
		(net 275)
	)
	(segment
		(start 161.450876 163.692309)
		(end 161.380166 163.76302)
		(width 0.148)
		(layer "In2.Cu")
		(net 275)
	)
	(segment
		(start 165.875501 149.802)
		(end 165.857164 149.802)
		(width 0.148)
		(layer "In2.Cu")
		(net 275)
	)
	(segment
		(start 159.117419 164.894398)
		(end 159.046709 164.965107)
		(width 0.148)
		(layer "In2.Cu")
		(net 275)
	)
	(segment
		(start 158.3396 165.672216)
		(end 158.339599 165.672218)
		(width 0.148)
		(layer "In2.Cu")
		(net 275)
	)
	(segment
		(start 166.125501 149.302)
		(end 166.125501 149.552)
		(width 0.148)
		(layer "In2.Cu")
		(net 275)
	)
	(segment
		(start 156.14756 168.712783)
		(end 155.864718 168.429942)
		(width 0.148)
		(layer "In2.Cu")
		(net 275)
	)
	(segment
		(start 155.723294 169.419892)
		(end 155.723293 169.419892)
		(width 0.148)
		(layer "In2.Cu")
		(net 275)
	)
	(segment
		(start 164.279312 160.863873)
		(end 164.208602 160.934584)
		(width 0.148)
		(layer "In2.Cu")
		(net 275)
	)
	(segment
		(start 162.865094 162.278091)
		(end 162.794384 162.348802)
		(width 0.148)
		(layer "In2.Cu")
		(net 275)
	)
	(segment
		(start 156.996092 167.015725)
		(end 156.925382 167.086434)
		(width 0.148)
		(layer "In2.Cu")
		(net 275)
	)
	(segment
		(start 162.582253 161.712406)
		(end 162.865094 161.995248)
		(width 0.148)
		(layer "In2.Cu")
		(net 275)
	)
	(segment
		(start 151.422001 170.2555)
		(end 150.875001 170.8025)
		(width 0.148)
		(layer "In2.Cu")
		(net 275)
	)
	(segment
		(start 163.996471 160.298188)
		(end 164.279312 160.58103)
		(width 0.148)
		(layer "In2.Cu")
		(net 275)
	)
	(segment
		(start 164.350026 159.944634)
		(end 164.350025 159.944634)
		(width 0.148)
		(layer "In2.Cu")
		(net 275)
	)
	(segment
		(start 155.794004 169.349181)
		(end 155.723294 169.419892)
		(width 0.148)
		(layer "In2.Cu")
		(net 275)
	)
	(segment
		(start 162.157985 162.702357)
		(end 162.157986 162.702357)
		(width 0.148)
		(layer "In2.Cu")
		(net 275)
	)
	(segment
		(start 155.864718 168.429942)
		(end 155.864717 168.429942)
		(width 0.148)
		(layer "In2.Cu")
		(net 275)
	)
	(segment
		(start 164.703581 159.308235)
		(end 164.70358 159.308237)
		(width 0.148)
		(layer "In2.Cu")
		(net 275)
	)
	(segment
		(start 161.804432 163.055911)
		(end 161.52159 162.77307)
		(width 0.148)
		(layer "In2.Cu")
		(net 275)
	)
	(segment
		(start 160.743767 164.399418)
		(end 160.673057 164.470129)
		(width 0.148)
		(layer "In2.Cu")
		(net 275)
	)
	(segment
		(start 159.258839 165.884347)
		(end 159.258838 165.884347)
		(width 0.148)
		(layer "In2.Cu")
		(net 275)
	)
	(segment
		(start 164.986421 159.873921)
		(end 164.986422 159.873921)
		(width 0.148)
		(layer "In2.Cu")
		(net 275)
	)
	(segment
		(start 163.925759 160.934584)
		(end 163.642917 160.651743)
		(width 0.148)
		(layer "In2.Cu")
		(net 275)
	)
	(segment
		(start 167.925001 147.302499)
		(end 167.925001 147.5025)
		(width 0.148)
		(layer "In2.Cu")
		(net 275)
	)
	(segment
		(start 156.430403 168.712783)
		(end 156.430402 168.712783)
		(width 0.148)
		(layer "In2.Cu")
		(net 275)
	)
	(segment
		(start 158.339599 165.95506)
		(end 158.62244 166.237902)
		(width 0.148)
		(layer "In2.Cu")
		(net 275)
	)
	(segment
		(start 160.743767 164.116575)
		(end 160.743768 164.116575)
		(width 0.148)
		(layer "In2.Cu")
		(net 275)
	)
	(segment
		(start 160.390214 164.470129)
		(end 160.107372 164.187288)
		(width 0.148)
		(layer "In2.Cu")
		(net 275)
	)
	(segment
		(start 156.571827 167.722833)
		(end 156.571826 167.722833)
		(width 0.148)
		(layer "In2.Cu")
		(net 275)
	)
	(segment
		(start 161.097323 163.76302)
		(end 160.814481 163.480179)
		(width 0.148)
		(layer "In2.Cu")
		(net 275)
	)
	(segment
		(start 165.69353 159.449655)
		(end 165.62282 159.520366)
		(width 0.148)
		(layer "In2.Cu")
		(net 275)
	)
	(segment
		(start 154.804055 169.207761)
		(end 154.804054 169.207763)
		(width 0.148)
		(layer "In2.Cu")
		(net 275)
	)
	(segment
		(start 167.925001 147.5025)
		(end 166.125501 149.302)
		(width 0.148)
		(layer "In2.Cu")
		(net 275)
	)
	(segment
		(start 158.62244 166.520745)
		(end 158.55173 166.591456)
		(width 0.148)
		(layer "In2.Cu")
		(net 275)
	)
	(segment
		(start 162.865094 161.995248)
		(end 162.865095 161.995248)
		(width 0.148)
		(layer "In2.Cu")
		(net 275)
	)
	(segment
		(start 162.157985 162.9852)
		(end 162.087275 163.055911)
		(width 0.148)
		(layer "In2.Cu")
		(net 275)
	)
	(segment
		(start 155.157609 169.137051)
		(end 155.157608 169.137051)
		(width 0.148)
		(layer "In2.Cu")
		(net 275)
	)
	(segment
		(start 155.511163 168.783496)
		(end 155.794004 169.066338)
		(width 0.148)
		(layer "In2.Cu")
		(net 275)
	)
	(segment
		(start 157.63249 166.662169)
		(end 157.915331 166.945011)
		(width 0.148)
		(layer "In2.Cu")
		(net 275)
	)
	(segment
		(start 159.683105 165.177238)
		(end 159.400263 164.894397)
		(width 0.148)
		(layer "In2.Cu")
		(net 275)
	)
	(segment
		(start 158.693154 165.601506)
		(end 158.693153 165.601506)
		(width 0.148)
		(layer "In2.Cu")
		(net 275)
	)
	(segment
		(start 162.582254 161.429562)
		(end 162.582253 161.429564)
		(width 0.148)
		(layer "In2.Cu")
		(net 275)
	)
	(segment
		(start 166.125501 152.052)
		(end 166.125501 158.451998)
		(width 0.148)
		(layer "In2.Cu")
		(net 275)
	)
	(segment
		(start 165.857164 150.802)
		(end 166.393838 150.802)
		(width 0.148)
		(layer "In2.Cu")
		(net 275)
	)
	(segment
		(start 165.875501 150.302)
		(end 166.393838 150.302)
		(width 0.148)
		(layer "In2.Cu")
		(net 275)
	)
	(segment
		(start 164.279312 160.58103)
		(end 164.279313 160.58103)
		(width 0.148)
		(layer "In2.Cu")
		(net 275)
	)
	(segment
		(start 162.794384 162.348802)
		(end 162.794383 162.348802)
		(width 0.148)
		(layer "In2.Cu")
		(net 275)
	)
	(segment
		(start 161.380166 163.76302)
		(end 161.380165 163.76302)
		(width 0.148)
		(layer "In2.Cu")
		(net 275)
	)
	(segment
		(start 163.642917 160.651743)
		(end 163.642916 160.651743)
		(width 0.148)
		(layer "In2.Cu")
		(net 275)
	)
	(segment
		(start 165.857164 150.302)
		(end 165.875501 150.302)
		(width 0.148)
		(layer "In2.Cu")
		(net 275)
	)
	(segment
		(start 164.774291 159.237526)
		(end 164.703581 159.308235)
		(width 0.148)
		(layer "In2.Cu")
		(net 275)
	)
	(segment
		(start 163.996472 160.015344)
		(end 163.996471 160.015346)
		(width 0.148)
		(layer "In2.Cu")
		(net 275)
	)
	(segment
		(start 161.238746 162.773071)
		(end 161.168036 162.84378)
		(width 0.148)
		(layer "In2.Cu")
		(net 275)
	)
	(segment
		(start 154.450501 170.127)
		(end 154.322001 170.2555)
		(width 0.148)
		(layer "In2.Cu")
		(net 275)
	)
	(segment
		(start 165.62282 159.520366)
		(end 165.622819 159.520366)
		(width 0.148)
		(layer "In2.Cu")
		(net 275)
	)
	(segment
		(start 156.218272 168.076387)
		(end 156.501113 168.359229)
		(width 0.148)
		(layer "In2.Cu")
		(net 275)
	)
	(segment
		(start 156.501113 168.359229)
		(end 156.501114 168.359229)
		(width 0.148)
		(layer "In2.Cu")
		(net 275)
	)
	(segment
		(start 157.561778 167.298565)
		(end 157.278936 167.015724)
		(width 0.148)
		(layer "In2.Cu")
		(net 275)
	)
	(segment
		(start 157.137512 168.005674)
		(end 157.137511 168.005674)
		(width 0.148)
		(layer "In2.Cu")
		(net 275)
	)
	(segment
		(start 160.460926 163.833733)
		(end 160.743767 164.116575)
		(width 0.148)
		(layer "In2.Cu")
		(net 275)
	)
	(segment
		(start 155.581874 168.429943)
		(end 155.511164 168.500652)
		(width 0.148)
		(layer "In2.Cu")
		(net 275)
	)
	(segment
		(start 164.632868 160.227475)
		(end 164.350026 159.944634)
		(width 0.148)
		(layer "In2.Cu")
		(net 275)
	)
	(segment
		(start 161.875144 162.419515)
		(end 162.157985 162.702357)
		(width 0.148)
		(layer "In2.Cu")
		(net 275)
	)
	(segment
		(start 165.857164 151.302)
		(end 166.393838 151.302)
		(width 0.148)
		(layer "In2.Cu")
		(net 275)
	)
	(segment
		(start 154.804054 169.490605)
		(end 155.086895 169.773446)
		(width 0.148)
		(layer "In2.Cu")
		(net 275)
	)
	(segment
		(start 158.975996 165.884347)
		(end 158.693154 165.601506)
		(width 0.148)
		(layer "In2.Cu")
		(net 275)
	)
	(segment
		(start 164.986421 160.156764)
		(end 164.915711 160.227475)
		(width 0.148)
		(layer "In2.Cu")
		(net 275)
	)
	(segment
		(start 159.824528 164.187289)
		(end 159.753818 164.257998)
		(width 0.148)
		(layer "In2.Cu")
		(net 275)
	)
	(segment
		(start 164.915711 160.227475)
		(end 164.91571 160.227475)
		(width 0.148)
		(layer "In2.Cu")
		(net 275)
	)
	(segment
		(start 160.036658 165.106527)
		(end 159.965948 165.177238)
		(width 0.148)
		(layer "In2.Cu")
		(net 275)
	)
	(segment
		(start 157.208222 167.934963)
		(end 157.137512 168.005674)
		(width 0.148)
		(layer "In2.Cu")
		(net 275)
	)
	(segment
		(start 158.62244 166.237902)
		(end 158.622441 166.237902)
		(width 0.148)
		(layer "In2.Cu")
		(net 275)
	)
	(arc
		(start 155.016186 170.126999)
		(mid 154.874765 170.185578)
		(end 154.733343 170.127)
		(width 0.148)
		(layer "In2.Cu")
		(net 275)
	)
	(arc
		(start 159.400262 164.894397)
		(mid 159.25884 164.835819)
		(end 159.117419 164.894398)
		(width 0.148)
		(layer "In2.Cu")
		(net 275)
	)
	(arc
		(start 157.63249 166.379327)
		(mid 157.573913 166.520747)
		(end 157.63249 166.662169)
		(width 0.148)
		(layer "In2.Cu")
		(net 275)
	)
	(arc
		(start 162.087274 163.055911)
		(mid 161.945853 163.114489)
		(end 161.804432 163.055911)
		(width 0.148)
		(layer "In2.Cu")
		(net 275)
	)
	(arc
		(start 155.723293 169.419892)
		(mid 155.581872 169.47847)
		(end 155.440451 169.419892)
		(width 0.148)
		(layer "In2.Cu")
		(net 275)
	)
	(arc
		(start 165.693529 158.883969)
		(mid 165.634951 159.025391)
		(end 165.69353 159.166812)
		(width 0.148)
		(layer "In2.Cu")
		(net 275)
	)
	(arc
		(start 162.935807 161.358852)
		(mid 162.794385 161.300274)
		(end 162.652964 161.358853)
		(width 0.148)
		(layer "In2.Cu")
		(net 275)
	)
	(arc
		(start 162.865095 161.995248)
		(mid 162.923673 162.13667)
		(end 162.865094 162.278091)
		(width 0.148)
		(layer "In2.Cu")
		(net 275)
	)
	(arc
		(start 159.965947 165.177238)
		(mid 159.824526 165.235816)
		(end 159.683105 165.177238)
		(width 0.148)
		(layer "In2.Cu")
		(net 275)
	)
	(arc
		(start 166.643838 150.552)
		(mid 166.570615 150.728777)
		(end 166.393838 150.802)
		(width 0.148)
		(layer "In2.Cu")
		(net 275)
	)
	(arc
		(start 156.925381 167.086436)
		(mid 156.866804 167.227856)
		(end 156.925381 167.369278)
		(width 0.148)
		(layer "In2.Cu")
		(net 275)
	)
	(arc
		(start 160.81448 163.480179)
		(mid 160.673058 163.421601)
		(end 160.531637 163.48018)
		(width 0.148)
		(layer "In2.Cu")
		(net 275)
	)
	(arc
		(start 163.642916 160.651743)
		(mid 163.501494 160.593165)
		(end 163.360073 160.651744)
		(width 0.148)
		(layer "In2.Cu")
		(net 275)
	)
	(arc
		(start 165.057134 159.237525)
		(mid 164.915712 159.178947)
		(end 164.774291 159.237526)
		(width 0.148)
		(layer "In2.Cu")
		(net 275)
	)
	(arc
		(start 164.208601 160.934584)
		(mid 164.06718 160.993162)
		(end 163.925759 160.934584)
		(width 0.148)
		(layer "In2.Cu")
		(net 275)
	)
	(arc
		(start 164.350025 159.944634)
		(mid 164.208603 159.886056)
		(end 164.067182 159.944635)
		(width 0.148)
		(layer "In2.Cu")
		(net 275)
	)
	(arc
		(start 166.393838 150.302)
		(mid 166.570615 150.375223)
		(end 166.643838 150.552)
		(width 0.148)
		(layer "In2.Cu")
		(net 275)
	)
	(arc
		(start 158.551729 166.591456)
		(mid 158.410308 166.650034)
		(end 158.268887 166.591456)
		(width 0.148)
		(layer "In2.Cu")
		(net 275)
	)
	(arc
		(start 164.279313 160.58103)
		(mid 164.337891 160.722452)
		(end 164.279312 160.863873)
		(width 0.148)
		(layer "In2.Cu")
		(net 275)
	)
	(arc
		(start 157.137511 168.005674)
		(mid 156.99609 168.064252)
		(end 156.854669 168.005674)
		(width 0.148)
		(layer "In2.Cu")
		(net 275)
	)
	(arc
		(start 165.607164 150.052)
		(mid 165.680387 150.228777)
		(end 165.857164 150.302)
		(width 0.148)
		(layer "In2.Cu")
		(net 275)
	)
	(arc
		(start 163.289362 160.722455)
		(mid 163.230785 160.863875)
		(end 163.289362 161.005297)
		(width 0.148)
		(layer "In2.Cu")
		(net 275)
	)
	(arc
		(start 163.572204 161.288139)
		(mid 163.630782 161.429561)
		(end 163.572203 161.570982)
		(width 0.148)
		(layer "In2.Cu")
		(net 275)
	)
	(arc
		(start 157.915332 166.945011)
		(mid 157.97391 167.086433)
		(end 157.915331 167.227854)
		(width 0.148)
		(layer "In2.Cu")
		(net 275)
	)
	(arc
		(start 156.501114 168.359229)
		(mid 156.559692 168.500651)
		(end 156.501113 168.642072)
		(width 0.148)
		(layer "In2.Cu")
		(net 275)
	)
	(arc
		(start 155.086896 169.773446)
		(mid 155.145474 169.914868)
		(end 155.086895 170.056289)
		(width 0.148)
		(layer "In2.Cu")
		(net 275)
	)
	(arc
		(start 164.70358 159.308237)
		(mid 164.645003 159.449657)
		(end 164.70358 159.591079)
		(width 0.148)
		(layer "In2.Cu")
		(net 275)
	)
	(arc
		(start 161.875144 162.136673)
		(mid 161.816567 162.278093)
		(end 161.875144 162.419515)
		(width 0.148)
		(layer "In2.Cu")
		(net 275)
	)
	(arc
		(start 166.125501 149.552)
		(mid 166.052278 149.728777)
		(end 165.875501 149.802)
		(width 0.148)
		(layer "In2.Cu")
		(net 275)
	)
	(arc
		(start 155.794005 169.066338)
		(mid 155.852583 169.20776)
		(end 155.794004 169.349181)
		(width 0.148)
		(layer "In2.Cu")
		(net 275)
	)
	(arc
		(start 165.693531 159.166812)
		(mid 165.752109 159.308234)
		(end 165.69353 159.449655)
		(width 0.148)
		(layer "In2.Cu")
		(net 275)
	)
	(arc
		(start 162.794383 162.348802)
		(mid 162.652962 162.40738)
		(end 162.511541 162.348802)
		(width 0.148)
		(layer "In2.Cu")
		(net 275)
	)
	(arc
		(start 162.582253 161.429564)
		(mid 162.523676 161.570984)
		(end 162.582253 161.712406)
		(width 0.148)
		(layer "In2.Cu")
		(net 275)
	)
	(arc
		(start 155.864717 168.429942)
		(mid 155.723295 168.371364)
		(end 155.581874 168.429943)
		(width 0.148)
		(layer "In2.Cu")
		(net 275)
	)
	(arc
		(start 160.460926 163.550891)
		(mid 160.402349 163.692311)
		(end 160.460926 163.833733)
		(width 0.148)
		(layer "In2.Cu")
		(net 275)
	)
	(arc
		(start 164.986422 159.873921)
		(mid 165.045 160.015343)
		(end 164.986421 160.156764)
		(width 0.148)
		(layer "In2.Cu")
		(net 275)
	)
	(arc
		(start 154.804054 169.207763)
		(mid 154.745477 169.349183)
		(end 154.804054 169.490605)
		(width 0.148)
		(layer "In2.Cu")
		(net 275)
	)
	(arc
		(start 154.733343 170.127)
		(mid 154.591922 170.068422)
		(end 154.450501 170.127)
		(width 0.148)
		(layer "In2.Cu")
		(net 275)
	)
	(arc
		(start 161.168035 162.843782)
		(mid 161.109458 162.985202)
		(end 161.168035 163.126624)
		(width 0.148)
		(layer "In2.Cu")
		(net 275)
	)
	(arc
		(start 156.430402 168.712783)
		(mid 156.288981 168.771361)
		(end 156.14756 168.712783)
		(width 0.148)
		(layer "In2.Cu")
		(net 275)
	)
	(arc
		(start 165.607164 151.052)
		(mid 165.680387 151.228777)
		(end 165.857164 151.302)
		(width 0.148)
		(layer "In2.Cu")
		(net 275)
	)
	(arc
		(start 160.743768 164.116575)
		(mid 160.802346 164.257997)
		(end 160.743767 164.399418)
		(width 0.148)
		(layer "In2.Cu")
		(net 275)
	)
	(arc
		(start 161.521589 162.77307)
		(mid 161.380167 162.714492)
		(end 161.238746 162.773071)
		(width 0.148)
		(layer "In2.Cu")
		(net 275)
	)
	(arc
		(start 156.218272 167.793545)
		(mid 156.159695 167.934965)
		(end 156.218272 168.076387)
		(width 0.148)
		(layer "In2.Cu")
		(net 275)
	)
	(arc
		(start 158.339599 165.672218)
		(mid 158.281022 165.813638)
		(end 158.339599 165.95506)
		(width 0.148)
		(layer "In2.Cu")
		(net 275)
	)
	(arc
		(start 162.157986 162.702357)
		(mid 162.216564 162.843779)
		(end 162.157985 162.9852)
		(width 0.148)
		(layer "In2.Cu")
		(net 275)
	)
	(arc
		(start 160.107371 164.187288)
		(mid 159.965949 164.12871)
		(end 159.824528 164.187289)
		(width 0.148)
		(layer "In2.Cu")
		(net 275)
	)
	(arc
		(start 166.643838 151.552)
		(mid 166.570615 151.728777)
		(end 166.393838 151.802)
		(width 0.148)
		(layer "In2.Cu")
		(net 275)
	)
	(arc
		(start 160.673056 164.470129)
		(mid 160.531635 164.528707)
		(end 160.390214 164.470129)
		(width 0.148)
		(layer "In2.Cu")
		(net 275)
	)
	(arc
		(start 166.375501 151.802)
		(mid 166.198724 151.875223)
		(end 166.125501 152.052)
		(width 0.148)
		(layer "In2.Cu")
		(net 275)
	)
	(arc
		(start 159.046708 164.965109)
		(mid 158.988131 165.106529)
		(end 159.046708 165.247951)
		(width 0.148)
		(layer "In2.Cu")
		(net 275)
	)
	(arc
		(start 161.450877 163.409466)
		(mid 161.509455 163.550888)
		(end 161.450876 163.692309)
		(width 0.148)
		(layer "In2.Cu")
		(net 275)
	)
	(arc
		(start 159.32955 165.530793)
		(mid 159.388128 165.672215)
		(end 159.329549 165.813636)
		(width 0.148)
		(layer "In2.Cu")
		(net 275)
	)
	(arc
		(start 163.996471 160.015346)
		(mid 163.937894 160.156766)
		(end 163.996471 160.298188)
		(width 0.148)
		(layer "In2.Cu")
		(net 275)
	)
	(arc
		(start 157.986044 166.308615)
		(mid 157.844622 166.250037)
		(end 157.703201 166.308616)
		(width 0.148)
		(layer "In2.Cu")
		(net 275)
	)
	(arc
		(start 165.622819 159.520366)
		(mid 165.481398 159.578944)
		(end 165.339977 159.520366)
		(width 0.148)
		(layer "In2.Cu")
		(net 275)
	)
	(arc
		(start 155.157608 169.137051)
		(mid 155.016186 169.078473)
		(end 154.874765 169.137052)
		(width 0.148)
		(layer "In2.Cu")
		(net 275)
	)
	(arc
		(start 156.571826 167.722833)
		(mid 156.430404 167.664255)
		(end 156.288983 167.722834)
		(width 0.148)
		(layer "In2.Cu")
		(net 275)
	)
	(arc
		(start 165.857164 150.802)
		(mid 165.680387 150.875223)
		(end 165.607164 151.052)
		(width 0.148)
		(layer "In2.Cu")
		(net 275)
	)
	(arc
		(start 159.258838 165.884347)
		(mid 159.117417 165.942925)
		(end 158.975996 165.884347)
		(width 0.148)
		(layer "In2.Cu")
		(net 275)
	)
	(arc
		(start 157.278935 167.015724)
		(mid 157.137513 166.957146)
		(end 156.996092 167.015725)
		(width 0.148)
		(layer "In2.Cu")
		(net 275)
	)
	(arc
		(start 159.753817 164.258)
		(mid 159.69524 164.39942)
		(end 159.753817 164.540842)
		(width 0.148)
		(layer "In2.Cu")
		(net 275)
	)
	(arc
		(start 166.393838 151.302)
		(mid 166.570615 151.375223)
		(end 166.643838 151.552)
		(width 0.148)
		(layer "In2.Cu")
		(net 275)
	)
	(arc
		(start 165.857164 149.802)
		(mid 165.680387 149.875223)
		(end 165.607164 150.052)
		(width 0.148)
		(layer "In2.Cu")
		(net 275)
	)
	(arc
		(start 161.380165 163.76302)
		(mid 161.238744 163.821598)
		(end 161.097323 163.76302)
		(width 0.148)
		(layer "In2.Cu")
		(net 275)
	)
	(arc
		(start 160.036659 164.823684)
		(mid 160.095237 164.965106)
		(end 160.036658 165.106527)
		(width 0.148)
		(layer "In2.Cu")
		(net 275)
	)
	(arc
		(start 163.501492 161.641693)
		(mid 163.360071 161.700271)
		(end 163.21865 161.641693)
		(width 0.148)
		(layer "In2.Cu")
		(net 275)
	)
	(arc
		(start 162.228698 162.065961)
		(mid 162.087276 162.007383)
		(end 161.945855 162.065962)
		(width 0.148)
		(layer "In2.Cu")
		(net 275)
	)
	(arc
		(start 155.511163 168.500654)
		(mid 155.452586 168.642074)
		(end 155.511163 168.783496)
		(width 0.148)
		(layer "In2.Cu")
		(net 275)
	)
	(arc
		(start 157.84462 167.298565)
		(mid 157.703199 167.357143)
		(end 157.561778 167.298565)
		(width 0.148)
		(layer "In2.Cu")
		(net 275)
	)
	(arc
		(start 157.208223 167.65212)
		(mid 157.266801 167.793542)
		(end 157.208222 167.934963)
		(width 0.148)
		(layer "In2.Cu")
		(net 275)
	)
	(arc
		(start 158.622441 166.237902)
		(mid 158.681019 166.379324)
		(end 158.62244 166.520745)
		(width 0.148)
		(layer "In2.Cu")
		(net 275)
	)
	(arc
		(start 164.91571 160.227475)
		(mid 164.774289 160.286053)
		(end 164.632868 160.227475)
		(width 0.148)
		(layer "In2.Cu")
		(net 275)
	)
	(arc
		(start 158.693153 165.601506)
		(mid 158.551731 165.542928)
		(end 158.41031 165.601507)
		(width 0.148)
		(layer "In2.Cu")
		(net 275)
	)
	(segment
		(start 168.650002 138.8025)
		(end 168.650001 139.877499)
		(width 0.201)
		(layer "F.Cu")
		(net 276)
	)
	(segment
		(start 149.3755 169.302)
		(end 149.875001 168.8025)
		(width 0.256)
		(layer "F.Cu")
		(net 276)
	)
	(via
		(at 149.875001 168.8025)
		(size 0.45)
		(drill 0.1)
		(layers "F.Cu" "B.Cu")
		(net 276)
	)
	(via
		(at 168.650001 139.877499)
		(size 0.45)
		(drill 0.1)
		(layers "F.Cu" "B.Cu")
		(net 276)
	)
	(segment
		(start 163.469854 151.802)
		(end 163.375501 151.802)
		(width 0.148)
		(layer "In2.Cu")
		(net 276)
	)
	(segment
		(start 165.375501 147.019864)
		(end 165.375501 147.702)
		(width 0.148)
		(layer "In2.Cu")
		(net 276)
	)
	(segment
		(start 150.375001 168.3025)
		(end 149.875001 168.8025)
		(width 0.148)
		(layer "In2.Cu")
		(net 276)
	)
	(segment
		(start 168.650001 139.877499)
		(end 166.875501 141.651999)
		(width 0.148)
		(layer "In2.Cu")
		(net 276)
	)
	(segment
		(start 163.125501 159.207903)
		(end 163.125501 159.252)
		(width 0.148)
		(layer "In2.Cu")
		(net 276)
	)
	(segment
		(start 163.375501 151.802)
		(end 162.781148 151.802)
		(width 0.148)
		(layer "In2.Cu")
		(net 276)
	)
	(segment
		(start 154.075001 168.3025)
		(end 150.375001 168.3025)
		(width 0.148)
		(layer "In2.Cu")
		(net 276)
	)
	(segment
		(start 163.125501 159.252)
		(end 154.075001 168.3025)
		(width 0.148)
		(layer "In2.Cu")
		(net 276)
	)
	(segment
		(start 162.781148 154.802)
		(end 163.469854 154.802)
		(width 0.148)
		(layer "In2.Cu")
		(net 276)
	)
	(segment
		(start 162.781148 158.302)
		(end 162.875501 158.302)
		(width 0.148)
		(layer "In2.Cu")
		(net 276)
	)
	(segment
		(start 162.781148 153.302)
		(end 163.469854 153.302)
		(width 0.148)
		(layer "In2.Cu")
		(net 276)
	)
	(segment
		(start 162.781148 157.802)
		(end 163.469854 157.802)
		(width 0.148)
		(layer "In2.Cu")
		(net 276)
	)
	(segment
		(start 162.781148 157.302)
		(end 163.469854 157.302)
		(width 0.148)
		(layer "In2.Cu")
		(net 276)
	)
	(segment
		(start 162.781148 156.302)
		(end 163.469854 156.302)
		(width 0.148)
		(layer "In2.Cu")
		(net 276)
	)
	(segment
		(start 162.781148 156.802)
		(end 163.469854 156.802)
		(width 0.148)
		(layer "In2.Cu")
		(net 276)
	)
	(segment
		(start 165.375501 147.702)
		(end 163.125501 149.952)
		(width 0.148)
		(layer "In2.Cu")
		(net 276)
	)
	(segment
		(start 163.375501 151.302)
		(end 163.469854 151.302)
		(width 0.148)
		(layer "In2.Cu")
		(net 276)
	)
	(segment
		(start 166.875501 145.519864)
		(end 165.375501 147.019864)
		(width 0.148)
		(layer "In2.Cu")
		(net 276)
	)
	(segment
		(start 162.781148 153.802)
		(end 163.469854 153.802)
		(width 0.148)
		(layer "In2.Cu")
		(net 276)
	)
	(segment
		(start 163.125501 149.952)
		(end 163.125501 151.052)
		(width 0.148)
		(layer "In2.Cu")
		(net 276)
	)
	(segment
		(start 162.781148 152.302)
		(end 163.469854 152.302)
		(width 0.148)
		(layer "In2.Cu")
		(net 276)
	)
	(segment
		(start 163.125501 158.552)
		(end 163.125501 159.207903)
		(width 0.148)
		(layer "In2.Cu")
		(net 276)
	)
	(segment
		(start 162.781148 154.302)
		(end 163.469854 154.302)
		(width 0.148)
		(layer "In2.Cu")
		(net 276)
	)
	(segment
		(start 162.781148 155.302)
		(end 163.469854 155.302)
		(width 0.148)
		(layer "In2.Cu")
		(net 276)
	)
	(segment
		(start 166.875501 141.651999)
		(end 166.875501 145.519864)
		(width 0.148)
		(layer "In2.Cu")
		(net 276)
	)
	(segment
		(start 162.781148 155.802)
		(end 163.469854 155.802)
		(width 0.148)
		(layer "In2.Cu")
		(net 276)
	)
	(segment
		(start 162.781148 152.802)
		(end 163.469854 152.802)
		(width 0.148)
		(layer "In2.Cu")
		(net 276)
	)
	(arc
		(start 163.469854 155.302)
		(mid 163.646631 155.375223)
		(end 163.719854 155.552)
		(width 0.148)
		(layer "In2.Cu")
		(net 276)
	)
	(arc
		(start 163.469854 156.302)
		(mid 163.646631 156.375223)
		(end 163.719854 156.552)
		(width 0.148)
		(layer "In2.Cu")
		(net 276)
	)
	(arc
		(start 162.531148 158.052)
		(mid 162.604371 158.228777)
		(end 162.781148 158.302)
		(width 0.148)
		(layer "In2.Cu")
		(net 276)
	)
	(arc
		(start 163.469854 152.302)
		(mid 163.646631 152.375223)
		(end 163.719854 152.552)
		(width 0.148)
		(layer "In2.Cu")
		(net 276)
	)
	(arc
		(start 163.719854 151.552)
		(mid 163.646631 151.728777)
		(end 163.469854 151.802)
		(width 0.148)
		(layer "In2.Cu")
		(net 276)
	)
	(arc
		(start 162.781148 153.802)
		(mid 162.604371 153.875223)
		(end 162.531148 154.052)
		(width 0.148)
		(layer "In2.Cu")
		(net 276)
	)
	(arc
		(start 162.531148 154.052)
		(mid 162.604371 154.228777)
		(end 162.781148 154.302)
		(width 0.148)
		(layer "In2.Cu")
		(net 276)
	)
	(arc
		(start 162.531148 153.052)
		(mid 162.604371 153.228777)
		(end 162.781148 153.302)
		(width 0.148)
		(layer "In2.Cu")
		(net 276)
	)
	(arc
		(start 162.875501 158.302)
		(mid 163.052278 158.375223)
		(end 163.125501 158.552)
		(width 0.148)
		(layer "In2.Cu")
		(net 276)
	)
	(arc
		(start 162.781148 152.802)
		(mid 162.604371 152.875223)
		(end 162.531148 153.052)
		(width 0.148)
		(layer "In2.Cu")
		(net 276)
	)
	(arc
		(start 162.781148 155.802)
		(mid 162.604371 155.875223)
		(end 162.531148 156.052)
		(width 0.148)
		(layer "In2.Cu")
		(net 276)
	)
	(arc
		(start 163.719854 152.552)
		(mid 163.646631 152.728777)
		(end 163.469854 152.802)
		(width 0.148)
		(layer "In2.Cu")
		(net 276)
	)
	(arc
		(start 163.469854 154.302)
		(mid 163.646631 154.375223)
		(end 163.719854 154.552)
		(width 0.148)
		(layer "In2.Cu")
		(net 276)
	)
	(arc
		(start 162.531148 157.052)
		(mid 162.604371 157.228777)
		(end 162.781148 157.302)
		(width 0.148)
		(layer "In2.Cu")
		(net 276)
	)
	(arc
		(start 162.531148 155.052)
		(mid 162.604371 155.228777)
		(end 162.781148 155.302)
		(width 0.148)
		(layer "In2.Cu")
		(net 276)
	)
	(arc
		(start 162.781148 157.802)
		(mid 162.604371 157.875223)
		(end 162.531148 158.052)
		(width 0.148)
		(layer "In2.Cu")
		(net 276)
	)
	(arc
		(start 163.469854 153.302)
		(mid 163.646631 153.375223)
		(end 163.719854 153.552)
		(width 0.148)
		(layer "In2.Cu")
		(net 276)
	)
	(arc
		(start 162.531148 152.052)
		(mid 162.604371 152.228777)
		(end 162.781148 152.302)
		(width 0.148)
		(layer "In2.Cu")
		(net 276)
	)
	(arc
		(start 162.781148 156.802)
		(mid 162.604371 156.875223)
		(end 162.531148 157.052)
		(width 0.148)
		(layer "In2.Cu")
		(net 276)
	)
	(arc
		(start 162.531148 156.052)
		(mid 162.604371 156.228777)
		(end 162.781148 156.302)
		(width 0.148)
		(layer "In2.Cu")
		(net 276)
	)
	(arc
		(start 163.469854 157.302)
		(mid 163.646631 157.375223)
		(end 163.719854 157.552)
		(width 0.148)
		(layer "In2.Cu")
		(net 276)
	)
	(arc
		(start 163.719854 154.552)
		(mid 163.646631 154.728777)
		(end 163.469854 154.802)
		(width 0.148)
		(layer "In2.Cu")
		(net 276)
	)
	(arc
		(start 163.469854 151.302)
		(mid 163.646631 151.375223)
		(end 163.719854 151.552)
		(width 0.148)
		(layer "In2.Cu")
		(net 276)
	)
	(arc
		(start 163.125501 151.052)
		(mid 163.198724 151.228777)
		(end 163.375501 151.302)
		(width 0.148)
		(layer "In2.Cu")
		(net 276)
	)
	(arc
		(start 163.719854 156.552)
		(mid 163.646631 156.728777)
		(end 163.469854 156.802)
		(width 0.148)
		(layer "In2.Cu")
		(net 276)
	)
	(arc
		(start 162.781148 154.802)
		(mid 162.604371 154.875223)
		(end 162.531148 155.052)
		(width 0.148)
		(layer "In2.Cu")
		(net 276)
	)
	(arc
		(start 163.719854 157.552)
		(mid 163.646631 157.728777)
		(end 163.469854 157.802)
		(width 0.148)
		(layer "In2.Cu")
		(net 276)
	)
	(arc
		(start 162.781148 151.802)
		(mid 162.604371 151.875223)
		(end 162.531148 152.052)
		(width 0.148)
		(layer "In2.Cu")
		(net 276)
	)
	(arc
		(start 163.719854 155.552)
		(mid 163.646631 155.728777)
		(end 163.469854 155.802)
		(width 0.148)
		(layer "In2.Cu")
		(net 276)
	)
	(arc
		(start 163.719854 153.552)
		(mid 163.646631 153.728777)
		(end 163.469854 153.802)
		(width 0.148)
		(layer "In2.Cu")
		(net 276)
	)
	(segment
		(start 148.375501 170.302)
		(end 148.875001 169.802499)
		(width 0.256)
		(layer "F.Cu")
		(net 277)
	)
	(segment
		(start 168.900001 146.2025)
		(end 168.900001 147.277498)
		(width 0.201)
		(layer "F.Cu")
		(net 277)
	)
	(via
		(at 168.900001 147.277498)
		(size 0.45)
		(drill 0.1)
		(layers "F.Cu" "B.Cu")
		(net 277)
	)
	(via
		(at 148.875001 169.802499)
		(size 0.45)
		(drill 0.1)
		(layers "F.Cu" "B.Cu")
		(net 277)
	)
	(segment
		(start 159.117848 167.223258)
		(end 159.082491 167.258614)
		(width 0.148)
		(layer "In2.Cu")
		(net 277)
	)
	(segment
		(start 163.643342 163.970554)
		(end 163.607987 164.00591)
		(width 0.148)
		(layer "In2.Cu")
		(net 277)
	)
	(segment
		(start 158.693579 168.920317)
		(end 158.658224 168.955673)
		(width 0.148)
		(layer "In2.Cu")
		(net 277)
	)
	(segment
		(start 168.900001 147.277498)
		(end 168.875501 147.301998)
		(width 0.148)
		(layer "In2.Cu")
		(net 277)
	)
	(segment
		(start 160.532066 165.80904)
		(end 160.496709 165.844396)
		(width 0.148)
		(layer "In2.Cu")
		(net 277)
	)
	(segment
		(start 162.653393 163.687713)
		(end 162.618036 163.723069)
		(width 0.148)
		(layer "In2.Cu")
		(net 277)
	)
	(segment
		(start 168.875501 148.552)
		(end 168.625501 148.802)
		(width 0.148)
		(layer "In2.Cu")
		(net 277)
	)
	(segment
		(start 163.360502 162.980604)
		(end 163.325145 163.01596)
		(width 0.148)
		(layer "In2.Cu")
		(net 277)
	)
	(segment
		(start 162.229124 165.384772)
		(end 162.193769 165.420128)
		(width 0.148)
		(layer "In2.Cu")
		(net 277)
	)
	(segment
		(start 168.625501 148.802)
		(end 168.625501 149.302)
		(width 0.148)
		(layer "In2.Cu")
		(net 277)
	)
	(segment
		(start 156.996521 169.344585)
		(end 156.961164 169.379941)
		(width 0.148)
		(layer "In2.Cu")
		(net 277)
	)
	(segment
		(start 149.675001 171.3025)
		(end 149.375001 171.0025)
		(width 0.148)
		(layer "In2.Cu")
		(net 277)
	)
	(segment
		(start 155.900501 171.077)
		(end 155.675001 171.3025)
		(width 0.148)
		(layer "In2.Cu")
		(net 277)
	)
	(segment
		(start 158.728937 167.930367)
		(end 159.047135 168.248564)
		(width 0.148)
		(layer "In2.Cu")
		(net 277)
	)
	(segment
		(start 159.082491 167.576812)
		(end 159.400688 167.89501)
		(width 0.148)
		(layer "In2.Cu")
		(net 277)
	)
	(segment
		(start 157.279361 170.334535)
		(end 157.244006 170.369891)
		(width 0.148)
		(layer "In2.Cu")
		(net 277)
	)
	(segment
		(start 161.557373 165.101931)
		(end 161.875571 165.420128)
		(width 0.148)
		(layer "In2.Cu")
		(net 277)
	)
	(segment
		(start 157.668273 168.99103)
		(end 157.98647 169.309228)
		(width 0.148)
		(layer "In2.Cu")
		(net 277)
	)
	(segment
		(start 159.824957 166.516149)
		(end 159.7896 166.551505)
		(width 0.148)
		(layer "In2.Cu")
		(net 277)
	)
	(segment
		(start 155.675001 171.3025)
		(end 149.675001 171.3025)
		(width 0.148)
		(layer "In2.Cu")
		(net 277)
	)
	(segment
		(start 162.936233 164.677663)
		(end 162.900878 164.713019)
		(width 0.148)
		(layer "In2.Cu")
		(net 277)
	)
	(segment
		(start 156.961164 169.698139)
		(end 157.279361 170.016337)
		(width 0.148)
		(layer "In2.Cu")
		(net 277)
	)
	(segment
		(start 161.522015 166.091881)
		(end 161.48666 166.127237)
		(width 0.148)
		(layer "In2.Cu")
		(net 277)
	)
	(segment
		(start 157.98647 169.627426)
		(end 157.951115 169.662782)
		(width 0.148)
		(layer "In2.Cu")
		(net 277)
	)
	(segment
		(start 168.375501 150.052)
		(end 168.992228 150.052)
		(width 0.148)
		(layer "In2.Cu")
		(net 277)
	)
	(segment
		(start 161.946284 164.394822)
		(end 161.910927 164.430178)
		(width 0.148)
		(layer "In2.Cu")
		(net 277)
	)
	(segment
		(start 163.325145 163.334158)
		(end 163.643342 163.652356)
		(width 0.148)
		(layer "In2.Cu")
		(net 277)
	)
	(segment
		(start 168.992228 150.552)
		(end 168.875501 150.552)
		(width 0.148)
		(layer "In2.Cu")
		(net 277)
	)
	(segment
		(start 162.971591 163.687713)
		(end 163.289789 164.00591)
		(width 0.148)
		(layer "In2.Cu")
		(net 277)
	)
	(segment
		(start 161.910927 164.748376)
		(end 162.229124 165.066574)
		(width 0.148)
		(layer "In2.Cu")
		(net 277)
	)
	(segment
		(start 157.70363 168.637476)
		(end 157.668273 168.672832)
		(width 0.148)
		(layer "In2.Cu")
		(net 277)
	)
	(segment
		(start 161.239175 165.101931)
		(end 161.203818 165.137287)
		(width 0.148)
		(layer "In2.Cu")
		(net 277)
	)
	(segment
		(start 160.850264 165.80904)
		(end 161.168462 166.127237)
		(width 0.148)
		(layer "In2.Cu")
		(net 277)
	)
	(segment
		(start 168.875501 147.301998)
		(end 168.875501 148.552)
		(width 0.148)
		(layer "In2.Cu")
		(net 277)
	)
	(segment
		(start 159.400688 168.213208)
		(end 159.365333 168.248564)
		(width 0.148)
		(layer "In2.Cu")
		(net 277)
	)
	(segment
		(start 160.143155 166.516149)
		(end 160.461353 166.834346)
		(width 0.148)
		(layer "In2.Cu")
		(net 277)
	)
	(segment
		(start 160.814906 166.79899)
		(end 160.779551 166.834346)
		(width 0.148)
		(layer "In2.Cu")
		(net 277)
	)
	(segment
		(start 168.625501 158.352)
		(end 163.996899 162.980605)
		(width 0.148)
		(layer "In2.Cu")
		(net 277)
	)
	(segment
		(start 156.254055 170.405248)
		(end 156.572252 170.723446)
		(width 0.148)
		(layer "In2.Cu")
		(net 277)
	)
	(segment
		(start 168.258774 150.052)
		(end 168.375501 150.052)
		(width 0.148)
		(layer "In2.Cu")
		(net 277)
	)
	(segment
		(start 168.375501 149.552)
		(end 168.258774 149.552)
		(width 0.148)
		(layer "In2.Cu")
		(net 277)
	)
	(segment
		(start 159.7896 166.869703)
		(end 160.107797 167.187901)
		(width 0.148)
		(layer "In2.Cu")
		(net 277)
	)
	(segment
		(start 168.625501 150.802)
		(end 168.625501 158.352)
		(width 0.148)
		(layer "In2.Cu")
		(net 277)
	)
	(segment
		(start 156.536897 171.077)
		(end 156.536898 171.076999)
		(width 0.148)
		(layer "In2.Cu")
		(net 277)
	)
	(segment
		(start 161.203818 165.455485)
		(end 161.522015 165.773683)
		(width 0.148)
		(layer "In2.Cu")
		(net 277)
	)
	(segment
		(start 149.375001 171.0025)
		(end 149.375001 170.302499)
		(width 0.148)
		(layer "In2.Cu")
		(net 277)
	)
	(segment
		(start 158.375382 168.283921)
		(end 158.693579 168.602119)
		(width 0.148)
		(layer "In2.Cu")
		(net 277)
	)
	(segment
		(start 149.375001 170.302499)
		(end 148.875001 169.802499)
		(width 0.148)
		(layer "In2.Cu")
		(net 277)
	)
	(segment
		(start 156.289412 170.051694)
		(end 156.254055 170.08705)
		(width 0.148)
		(layer "In2.Cu")
		(net 277)
	)
	(segment
		(start 157.314719 169.344585)
		(end 157.632917 169.662782)
		(width 0.148)
		(layer "In2.Cu")
		(net 277)
	)
	(segment
		(start 160.496709 166.162594)
		(end 160.814906 166.480792)
		(width 0.148)
		(layer "In2.Cu")
		(net 277)
	)
	(segment
		(start 159.436046 167.223258)
		(end 159.754244 167.541455)
		(width 0.148)
		(layer "In2.Cu")
		(net 277)
	)
	(segment
		(start 156.572252 171.041644)
		(end 156.536897 171.077)
		(width 0.148)
		(layer "In2.Cu")
		(net 277)
	)
	(segment
		(start 162.618036 164.041267)
		(end 162.936233 164.359465)
		(width 0.148)
		(layer "In2.Cu")
		(net 277)
	)
	(segment
		(start 162.264482 164.394822)
		(end 162.58268 164.713019)
		(width 0.148)
		(layer "In2.Cu")
		(net 277)
	)
	(segment
		(start 158.410739 167.930367)
		(end 158.375382 167.965723)
		(width 0.148)
		(layer "In2.Cu")
		(net 277)
	)
	(segment
		(start 156.60761 170.051694)
		(end 156.925808 170.369891)
		(width 0.148)
		(layer "In2.Cu")
		(net 277)
	)
	(segment
		(start 160.107797 167.506099)
		(end 160.072442 167.541455)
		(width 0.148)
		(layer "In2.Cu")
		(net 277)
	)
	(segment
		(start 158.021828 168.637476)
		(end 158.340026 168.955673)
		(width 0.148)
		(layer "In2.Cu")
		(net 277)
	)
	(arc
		(start 162.936233 164.359465)
		(mid 163.002134 164.518564)
		(end 162.936233 164.677663)
		(width 0.148)
		(layer "In2.Cu")
		(net 277)
	)
	(arc
		(start 160.107797 167.187901)
		(mid 160.173698 167.347)
		(end 160.107797 167.506099)
		(width 0.148)
		(layer "In2.Cu")
		(net 277)
	)
	(arc
		(start 168.992228 150.052)
		(mid 169.169005 150.125223)
		(end 169.242228 150.302)
		(width 0.148)
		(layer "In2.Cu")
		(net 277)
	)
	(arc
		(start 162.900878 164.713019)
		(mid 162.741779 164.77892)
		(end 162.58268 164.713019)
		(width 0.148)
		(layer "In2.Cu")
		(net 277)
	)
	(arc
		(start 169.242228 150.302)
		(mid 169.169005 150.478777)
		(end 168.992228 150.552)
		(width 0.148)
		(layer "In2.Cu")
		(net 277)
	)
	(arc
		(start 160.850264 165.80904)
		(mid 160.691165 165.743139)
		(end 160.532066 165.80904)
		(width 0.148)
		(layer "In2.Cu")
		(net 277)
	)
	(arc
		(start 162.971591 163.687713)
		(mid 162.812492 163.621812)
		(end 162.653393 163.687713)
		(width 0.148)
		(layer "In2.Cu")
		(net 277)
	)
	(arc
		(start 158.728937 167.930367)
		(mid 158.569838 167.864466)
		(end 158.410739 167.930367)
		(width 0.148)
		(layer "In2.Cu")
		(net 277)
	)
	(arc
		(start 159.400688 167.89501)
		(mid 159.466589 168.054109)
		(end 159.400688 168.213208)
		(width 0.148)
		(layer "In2.Cu")
		(net 277)
	)
	(arc
		(start 161.203818 165.137287)
		(mid 161.137917 165.296386)
		(end 161.203818 165.455485)
		(width 0.148)
		(layer "In2.Cu")
		(net 277)
	)
	(arc
		(start 160.814906 166.480792)
		(mid 160.880807 166.639891)
		(end 160.814906 166.79899)
		(width 0.148)
		(layer "In2.Cu")
		(net 277)
	)
	(arc
		(start 156.254055 170.08705)
		(mid 156.188154 170.246149)
		(end 156.254055 170.405248)
		(width 0.148)
		(layer "In2.Cu")
		(net 277)
	)
	(arc
		(start 156.218699 171.077)
		(mid 156.0596 171.011099)
		(end 155.900501 171.077)
		(width 0.148)
		(layer "In2.Cu")
		(net 277)
	)
	(arc
		(start 158.693579 168.602119)
		(mid 158.75948 168.761218)
		(end 158.693579 168.920317)
		(width 0.148)
		(layer "In2.Cu")
		(net 277)
	)
	(arc
		(start 163.6787 162.980604)
		(mid 163.519601 162.914703)
		(end 163.360502 162.980604)
		(width 0.148)
		(layer "In2.Cu")
		(net 277)
	)
	(arc
		(start 157.314719 169.344585)
		(mid 157.15562 169.278684)
		(end 156.996521 169.344585)
		(width 0.148)
		(layer "In2.Cu")
		(net 277)
	)
	(arc
		(start 160.779551 166.834346)
		(mid 160.620452 166.900247)
		(end 160.461353 166.834346)
		(width 0.148)
		(layer "In2.Cu")
		(net 277)
	)
	(arc
		(start 158.021828 168.637476)
		(mid 157.862729 168.571575)
		(end 157.70363 168.637476)
		(width 0.148)
		(layer "In2.Cu")
		(net 277)
	)
	(arc
		(start 168.258774 149.552)
		(mid 168.081997 149.625223)
		(end 168.008774 149.802)
		(width 0.148)
		(layer "In2.Cu")
		(net 277)
	)
	(arc
		(start 158.375382 167.965723)
		(mid 158.309481 168.124822)
		(end 158.375382 168.283921)
		(width 0.148)
		(layer "In2.Cu")
		(net 277)
	)
	(arc
		(start 158.658224 168.955673)
		(mid 158.499125 169.021574)
		(end 158.340026 168.955673)
		(width 0.148)
		(layer "In2.Cu")
		(net 277)
	)
	(arc
		(start 156.60761 170.051694)
		(mid 156.448511 169.985793)
		(end 156.289412 170.051694)
		(width 0.148)
		(layer "In2.Cu")
		(net 277)
	)
	(arc
		(start 157.668273 168.672832)
		(mid 157.602372 168.831931)
		(end 157.668273 168.99103)
		(width 0.148)
		(layer "In2.Cu")
		(net 277)
	)
	(arc
		(start 161.48666 166.127237)
		(mid 161.327561 166.193138)
		(end 161.168462 166.127237)
		(width 0.148)
		(layer "In2.Cu")
		(net 277)
	)
	(arc
		(start 157.951115 169.662782)
		(mid 157.792016 169.728683)
		(end 157.632917 169.662782)
		(width 0.148)
		(layer "In2.Cu")
		(net 277)
	)
	(arc
		(start 162.229124 165.066574)
		(mid 162.295025 165.225673)
		(end 162.229124 165.384772)
		(width 0.148)
		(layer "In2.Cu")
		(net 277)
	)
	(arc
		(start 160.143155 166.516149)
		(mid 159.984056 166.450248)
		(end 159.824957 166.516149)
		(width 0.148)
		(layer "In2.Cu")
		(net 277)
	)
	(arc
		(start 163.996899 162.980605)
		(mid 163.837798 163.046507)
		(end 163.6787 162.980604)
		(width 0.148)
		(layer "In2.Cu")
		(net 277)
	)
	(arc
		(start 162.618036 163.723069)
		(mid 162.552135 163.882168)
		(end 162.618036 164.041267)
		(width 0.148)
		(layer "In2.Cu")
		(net 277)
	)
	(arc
		(start 163.325145 163.01596)
		(mid 163.259244 163.175059)
		(end 163.325145 163.334158)
		(width 0.148)
		(layer "In2.Cu")
		(net 277)
	)
	(arc
		(start 159.436046 167.223258)
		(mid 159.276947 167.157357)
		(end 159.117848 167.223258)
		(width 0.148)
		(layer "In2.Cu")
		(net 277)
	)
	(arc
		(start 161.557373 165.101931)
		(mid 161.398274 165.03603)
		(end 161.239175 165.101931)
		(width 0.148)
		(layer "In2.Cu")
		(net 277)
	)
	(arc
		(start 160.496709 165.844396)
		(mid 160.430808 166.003495)
		(end 160.496709 166.162594)
		(width 0.148)
		(layer "In2.Cu")
		(net 277)
	)
	(arc
		(start 156.572252 170.723446)
		(mid 156.638153 170.882545)
		(end 156.572252 171.041644)
		(width 0.148)
		(layer "In2.Cu")
		(net 277)
	)
	(arc
		(start 157.98647 169.309228)
		(mid 158.052371 169.468327)
		(end 157.98647 169.627426)
		(width 0.148)
		(layer "In2.Cu")
		(net 277)
	)
	(arc
		(start 159.7896 166.551505)
		(mid 159.723699 166.710604)
		(end 159.7896 166.869703)
		(width 0.148)
		(layer "In2.Cu")
		(net 277)
	)
	(arc
		(start 161.522015 165.773683)
		(mid 161.587916 165.932782)
		(end 161.522015 166.091881)
		(width 0.148)
		(layer "In2.Cu")
		(net 277)
	)
	(arc
		(start 157.279361 170.016337)
		(mid 157.345262 170.175436)
		(end 157.279361 170.334535)
		(width 0.148)
		(layer "In2.Cu")
		(net 277)
	)
	(arc
		(start 157.244006 170.369891)
		(mid 157.084907 170.435792)
		(end 156.925808 170.369891)
		(width 0.148)
		(layer "In2.Cu")
		(net 277)
	)
	(arc
		(start 163.643342 163.652356)
		(mid 163.709243 163.811455)
		(end 163.643342 163.970554)
		(width 0.148)
		(layer "In2.Cu")
		(net 277)
	)
	(arc
		(start 168.875501 150.552)
		(mid 168.698724 150.625223)
		(end 168.625501 150.802)
		(width 0.148)
		(layer "In2.Cu")
		(net 277)
	)
	(arc
		(start 163.607987 164.00591)
		(mid 163.448888 164.071811)
		(end 163.289789 164.00591)
		(width 0.148)
		(layer "In2.Cu")
		(net 277)
	)
	(arc
		(start 160.072442 167.541455)
		(mid 159.913343 167.607356)
		(end 159.754244 167.541455)
		(width 0.148)
		(layer "In2.Cu")
		(net 277)
	)
	(arc
		(start 156.536898 171.076999)
		(mid 156.377799 171.142901)
		(end 156.218699 171.077)
		(width 0.148)
		(layer "In2.Cu")
		(net 277)
	)
	(arc
		(start 168.008774 149.802)
		(mid 168.081997 149.978777)
		(end 168.258774 150.052)
		(width 0.148)
		(layer "In2.Cu")
		(net 277)
	)
	(arc
		(start 159.082491 167.258614)
		(mid 159.01659 167.417713)
		(end 159.082491 167.576812)
		(width 0.148)
		(layer "In2.Cu")
		(net 277)
	)
	(arc
		(start 159.365333 168.248564)
		(mid 159.206234 168.314465)
		(end 159.047135 168.248564)
		(width 0.148)
		(layer "In2.Cu")
		(net 277)
	)
	(arc
		(start 162.264482 164.394822)
		(mid 162.105383 164.328921)
		(end 161.946284 164.394822)
		(width 0.148)
		(layer "In2.Cu")
		(net 277)
	)
	(arc
		(start 168.625501 149.302)
		(mid 168.552278 149.478777)
		(end 168.375501 149.552)
		(width 0.148)
		(layer "In2.Cu")
		(net 277)
	)
	(arc
		(start 162.193769 165.420128)
		(mid 162.03467 165.486029)
		(end 161.875571 165.420128)
		(width 0.148)
		(layer "In2.Cu")
		(net 277)
	)
	(arc
		(start 156.961164 169.379941)
		(mid 156.895263 169.53904)
		(end 156.961164 169.698139)
		(width 0.148)
		(layer "In2.Cu")
		(net 277)
	)
	(arc
		(start 161.910927 164.430178)
		(mid 161.845026 164.589277)
		(end 161.910927 164.748376)
		(width 0.148)
		(layer "In2.Cu")
		(net 277)
	)
	(segment
		(start 149.375501 170.302)
		(end 149.875001 169.8025)
		(width 0.256)
		(layer "F.Cu")
		(net 278)
	)
	(segment
		(start 169.650001 138.8025)
		(end 169.650001 139.877498)
		(width 0.201)
		(layer "F.Cu")
		(net 278)
	)
	(via
		(at 169.650001 139.877498)
		(size 0.45)
		(drill 0.1)
		(layers "F.Cu" "B.Cu")
		(net 278)
	)
	(via
		(at 149.875001 169.8025)
		(size 0.45)
		(drill 0.1)
		(layers "F.Cu" "B.Cu")
		(net 278)
	)
	(segment
		(start 164.875501 150.802)
		(end 164.326131 150.802)
		(width 0.148)
		(layer "In2.Cu")
		(net 278)
	)
	(segment
		(start 164.625501 158.852)
		(end 154.175001 169.3025)
		(width 0.148)
		(layer "In2.Cu")
		(net 278)
	)
	(segment
		(start 168.875501 145.552)
		(end 168.225501 146.202)
		(width 0.148)
		(layer "In2.Cu")
		(net 278)
	)
	(segment
		(start 164.326131 156.802)
		(end 164.924871 156.802)
		(width 0.148)
		(layer "In2.Cu")
		(net 278)
	)
	(segment
		(start 164.625501 158.052)
		(end 164.625501 158.852)
		(width 0.148)
		(layer "In2.Cu")
		(net 278)
	)
	(segment
		(start 164.326131 151.302)
		(end 164.924871 151.302)
		(width 0.148)
		(layer "In2.Cu")
		(net 278)
	)
	(segment
		(start 169.650001 139.877498)
		(end 168.875501 140.651998)
		(width 0.148)
		(layer "In2.Cu")
		(net 278)
	)
	(segment
		(start 150.375001 169.3025)
		(end 149.875001 169.8025)
		(width 0.148)
		(layer "In2.Cu")
		(net 278)
	)
	(segment
		(start 168.225501 146.202)
		(end 167.193365 146.202)
		(width 0.148)
		(layer "In2.Cu")
		(net 278)
	)
	(segment
		(start 164.625501 149.552)
		(end 164.625501 150.052)
		(width 0.148)
		(layer "In2.Cu")
		(net 278)
	)
	(segment
		(start 164.875501 150.302)
		(end 164.924871 150.302)
		(width 0.148)
		(layer "In2.Cu")
		(net 278)
	)
	(segment
		(start 167.193365 146.202)
		(end 166.375501 147.019864)
		(width 0.148)
		(layer "In2.Cu")
		(net 278)
	)
	(segment
		(start 164.924871 157.802)
		(end 164.875501 157.802)
		(width 0.148)
		(layer "In2.Cu")
		(net 278)
	)
	(segment
		(start 164.326131 154.302)
		(end 164.924871 154.302)
		(width 0.148)
		(layer "In2.Cu")
		(net 278)
	)
	(segment
		(start 164.326131 152.302)
		(end 164.924871 152.302)
		(width 0.148)
		(layer "In2.Cu")
		(net 278)
	)
	(segment
		(start 164.924871 150.802)
		(end 164.875501 150.802)
		(width 0.148)
		(layer "In2.Cu")
		(net 278)
	)
	(segment
		(start 164.326131 152.802)
		(end 164.924871 152.802)
		(width 0.148)
		(layer "In2.Cu")
		(net 278)
	)
	(segment
		(start 164.326131 153.802)
		(end 164.924871 153.802)
		(width 0.148)
		(layer "In2.Cu")
		(net 278)
	)
	(segment
		(start 164.326131 155.802)
		(end 164.924871 155.802)
		(width 0.148)
		(layer "In2.Cu")
		(net 278)
	)
	(segment
		(start 164.326131 156.302)
		(end 164.924871 156.302)
		(width 0.148)
		(layer "In2.Cu")
		(net 278)
	)
	(segment
		(start 164.326131 151.802)
		(end 164.924871 151.802)
		(width 0.148)
		(layer "In2.Cu")
		(net 278)
	)
	(segment
		(start 164.326131 155.302)
		(end 164.924871 155.302)
		(width 0.148)
		(layer "In2.Cu")
		(net 278)
	)
	(segment
		(start 164.326131 153.302)
		(end 164.924871 153.302)
		(width 0.148)
		(layer "In2.Cu")
		(net 278)
	)
	(segment
		(start 166.375501 147.802)
		(end 164.625501 149.552)
		(width 0.148)
		(layer "In2.Cu")
		(net 278)
	)
	(segment
		(start 164.326131 154.802)
		(end 164.924871 154.802)
		(width 0.148)
		(layer "In2.Cu")
		(net 278)
	)
	(segment
		(start 168.875501 140.651998)
		(end 168.875501 145.552)
		(width 0.148)
		(layer "In2.Cu")
		(net 278)
	)
	(segment
		(start 164.326131 157.302)
		(end 164.924871 157.302)
		(width 0.148)
		(layer "In2.Cu")
		(net 278)
	)
	(segment
		(start 154.175001 169.3025)
		(end 150.375001 169.3025)
		(width 0.148)
		(layer "In2.Cu")
		(net 278)
	)
	(segment
		(start 166.375501 147.019864)
		(end 166.375501 147.802)
		(width 0.148)
		(layer "In2.Cu")
		(net 278)
	)
	(arc
		(start 164.924871 152.302)
		(mid 165.101648 152.375223)
		(end 165.174871 152.552)
		(width 0.148)
		(layer "In2.Cu")
		(net 278)
	)
	(arc
		(start 164.326131 153.802)
		(mid 164.149354 153.875223)
		(end 164.076131 154.052)
		(width 0.148)
		(layer "In2.Cu")
		(net 278)
	)
	(arc
		(start 164.924871 154.302)
		(mid 165.101648 154.375223)
		(end 165.174871 154.552)
		(width 0.148)
		(layer "In2.Cu")
		(net 278)
	)
	(arc
		(start 165.174871 157.552)
		(mid 165.101648 157.728777)
		(end 164.924871 157.802)
		(width 0.148)
		(layer "In2.Cu")
		(net 278)
	)
	(arc
		(start 165.174871 151.552)
		(mid 165.101648 151.728777)
		(end 164.924871 151.802)
		(width 0.148)
		(layer "In2.Cu")
		(net 278)
	)
	(arc
		(start 164.625501 150.052)
		(mid 164.698724 150.228777)
		(end 164.875501 150.302)
		(width 0.148)
		(layer "In2.Cu")
		(net 278)
	)
	(arc
		(start 164.076131 153.052)
		(mid 164.149354 153.228777)
		(end 164.326131 153.302)
		(width 0.148)
		(layer "In2.Cu")
		(net 278)
	)
	(arc
		(start 165.174871 152.552)
		(mid 165.101648 152.728777)
		(end 164.924871 152.802)
		(width 0.148)
		(layer "In2.Cu")
		(net 278)
	)
	(arc
		(start 164.924871 151.302)
		(mid 165.101648 151.375223)
		(end 165.174871 151.552)
		(width 0.148)
		(layer "In2.Cu")
		(net 278)
	)
	(arc
		(start 164.326131 152.802)
		(mid 164.149354 152.875223)
		(end 164.076131 153.052)
		(width 0.148)
		(layer "In2.Cu")
		(net 278)
	)
	(arc
		(start 164.326131 155.802)
		(mid 164.149354 155.875223)
		(end 164.076131 156.052)
		(width 0.148)
		(layer "In2.Cu")
		(net 278)
	)
	(arc
		(start 164.076131 155.052)
		(mid 164.149354 155.228777)
		(end 164.326131 155.302)
		(width 0.148)
		(layer "In2.Cu")
		(net 278)
	)
	(arc
		(start 164.924871 153.302)
		(mid 165.101648 153.375223)
		(end 165.174871 153.552)
		(width 0.148)
		(layer "In2.Cu")
		(net 278)
	)
	(arc
		(start 165.174871 156.552)
		(mid 165.101648 156.728777)
		(end 164.924871 156.802)
		(width 0.148)
		(layer "In2.Cu")
		(net 278)
	)
	(arc
		(start 164.924871 155.302)
		(mid 165.101648 155.375223)
		(end 165.174871 155.552)
		(width 0.148)
		(layer "In2.Cu")
		(net 278)
	)
	(arc
		(start 165.174871 154.552)
		(mid 165.101648 154.728777)
		(end 164.924871 154.802)
		(width 0.148)
		(layer "In2.Cu")
		(net 278)
	)
	(arc
		(start 164.875501 157.802)
		(mid 164.698724 157.875223)
		(end 164.625501 158.052)
		(width 0.148)
		(layer "In2.Cu")
		(net 278)
	)
	(arc
		(start 165.174871 153.552)
		(mid 165.101648 153.728777)
		(end 164.924871 153.802)
		(width 0.148)
		(layer "In2.Cu")
		(net 278)
	)
	(arc
		(start 164.076131 154.052)
		(mid 164.149354 154.228777)
		(end 164.326131 154.302)
		(width 0.148)
		(layer "In2.Cu")
		(net 278)
	)
	(arc
		(start 164.076131 157.052)
		(mid 164.149354 157.228777)
		(end 164.326131 157.302)
		(width 0.148)
		(layer "In2.Cu")
		(net 278)
	)
	(arc
		(start 164.076131 151.052)
		(mid 164.149354 151.228777)
		(end 164.326131 151.302)
		(width 0.148)
		(layer "In2.Cu")
		(net 278)
	)
	(arc
		(start 164.076131 156.052)
		(mid 164.149354 156.228777)
		(end 164.326131 156.302)
		(width 0.148)
		(layer "In2.Cu")
		(net 278)
	)
	(arc
		(start 164.924871 156.302)
		(mid 165.101648 156.375223)
		(end 165.174871 156.552)
		(width 0.148)
		(layer "In2.Cu")
		(net 278)
	)
	(arc
		(start 164.326131 156.802)
		(mid 164.149354 156.875223)
		(end 164.076131 157.052)
		(width 0.148)
		(layer "In2.Cu")
		(net 278)
	)
	(arc
		(start 165.174871 155.552)
		(mid 165.101648 155.728777)
		(end 164.924871 155.802)
		(width 0.148)
		(layer "In2.Cu")
		(net 278)
	)
	(arc
		(start 164.326131 150.802)
		(mid 164.149354 150.875223)
		(end 164.076131 151.052)
		(width 0.148)
		(layer "In2.Cu")
		(net 278)
	)
	(arc
		(start 164.924871 157.302)
		(mid 165.101648 157.375223)
		(end 165.174871 157.552)
		(width 0.148)
		(layer "In2.Cu")
		(net 278)
	)
	(arc
		(start 165.174871 150.552)
		(mid 165.101648 150.728777)
		(end 164.924871 150.802)
		(width 0.148)
		(layer "In2.Cu")
		(net 278)
	)
	(arc
		(start 164.326131 151.802)
		(mid 164.149354 151.875223)
		(end 164.076131 152.052)
		(width 0.148)
		(layer "In2.Cu")
		(net 278)
	)
	(arc
		(start 164.326131 154.802)
		(mid 164.149354 154.875223)
		(end 164.076131 155.052)
		(width 0.148)
		(layer "In2.Cu")
		(net 278)
	)
	(arc
		(start 164.924871 150.302)
		(mid 165.101648 150.375223)
		(end 165.174871 150.552)
		(width 0.148)
		(layer "In2.Cu")
		(net 278)
	)
	(arc
		(start 164.076131 152.052)
		(mid 164.149354 152.228777)
		(end 164.326131 152.302)
		(width 0.148)
		(layer "In2.Cu")
		(net 278)
	)
	(segment
		(start 169.92 147.292427)
		(end 169.875001 147.337426)
		(width 0.26)
		(layer "F.Cu")
		(net 279)
	)
	(segment
		(start 147.375501 169.302)
		(end 147.875001 168.8025)
		(width 0.256)
		(layer "F.Cu")
		(net 279)
	)
	(segment
		(start 169.900001 146.8025)
		(end 169.920001 146.8225)
		(width 0.26)
		(layer "F.Cu")
		(net 279)
	)
	(segment
		(start 169.920001 146.8225)
		(end 169.92 147.292427)
		(width 0.26)
		(layer "F.Cu")
		(net 279)
	)
	(segment
		(start 169.900001 146.2025)
		(end 169.900001 146.8025)
		(width 0.26)
		(layer "F.Cu")
		(net 279)
	)
	(via
		(at 169.875001 147.337426)
		(size 0.45)
		(drill 0.1)
		(layers "F.Cu" "B.Cu")
		(net 279)
	)
	(via
		(at 147.875001 168.8025)
		(size 0.45)
		(drill 0.1)
		(layers "F.Cu" "B.Cu")
		(net 279)
	)
	(segment
		(start 169.562678 152.569999)
		(end 170.603663 152.569999)
		(width 0.13)
		(layer "In2.Cu")
		(net 279)
	)
	(segment
		(start 148.475001 172.011078)
		(end 148.666423 172.2025)
		(width 0.1)
		(layer "In2.Cu")
		(net 279)
	)
	(segment
		(start 153.250223 172.176722)
		(end 152.392336 172.176722)
		(width 0.13)
		(layer "In2.Cu")
		(net 279)
	)
	(segment
		(start 169.562678 153.509999)
		(end 170.603663 153.509999)
		(width 0.13)
		(layer "In2.Cu")
		(net 279)
	)
	(segment
		(start 169.562678 155.369999)
		(end 170.603663 155.369999)
		(width 0.13)
		(layer "In2.Cu")
		(net 279)
	)
	(segment
		(start 169.875001 147.337426)
		(end 170.030001 147.492426)
		(width 0.13)
		(layer "In2.Cu")
		(net 279)
	)
	(segment
		(start 154.475223 172.001722)
		(end 154.475223 171.970491)
		(width 0.13)
		(layer "In2.Cu")
		(net 279)
	)
	(segment
		(start 169.821921 158.385874)
		(end 156.031073 172.176722)
		(width 0.13)
		(layer "In2.Cu")
		(net 279)
	)
	(segment
		(start 169.562678 156.309999)
		(end 169.800001 156.309999)
		(width 0.13)
		(layer "In2.Cu")
		(net 279)
	)
	(segment
		(start 152.366558 172.2025)
		(end 152.392336 172.176722)
		(width 0.1)
		(layer "In2.Cu")
		(net 279)
	)
	(segment
		(start 147.573001 168.8025)
		(end 147.475001 168.9005)
		(width 0.1)
		(layer "In2.Cu")
		(net 279)
	)
	(segment
		(start 170.030001 156.539999)
		(end 170.030001 157.883525)
		(width 0.13)
		(layer "In2.Cu")
		(net 279)
	)
	(segment
		(start 147.716423 170.2025)
		(end 148.266423 170.2025)
		(width 0.1)
		(layer "In2.Cu")
		(net 279)
	)
	(segment
		(start 147.875001 168.8025)
		(end 147.573001 168.8025)
		(width 0.1)
		(layer "In2.Cu")
		(net 279)
	)
	(segment
		(start 170.817324 152.32366)
		(end 170.817324 152.356338)
		(width 0.13)
		(layer "In2.Cu")
		(net 279)
	)
	(segment
		(start 148.475001 170.411078)
		(end 148.475001 172.011078)
		(width 0.1)
		(layer "In2.Cu")
		(net 279)
	)
	(segment
		(start 148.266423 170.2025)
		(end 148.475001 170.411078)
		(width 0.1)
		(layer "In2.Cu")
		(net 279)
	)
	(segment
		(start 153.775223 172.001722)
		(end 153.775223 171.970491)
		(width 0.13)
		(layer "In2.Cu")
		(net 279)
	)
	(segment
		(start 169.562678 152.109999)
		(end 170.603663 152.109999)
		(width 0.13)
		(layer "In2.Cu")
		(net 279)
	)
	(segment
		(start 156.031073 172.176722)
		(end 154.650223 172.176722)
		(width 0.13)
		(layer "In2.Cu")
		(net 279)
	)
	(segment
		(start 169.562678 153.969999)
		(end 170.603663 153.969999)
		(width 0.13)
		(layer "In2.Cu")
		(net 279)
	)
	(segment
		(start 170.817324 155.12366)
		(end 170.817324 155.156338)
		(width 0.13)
		(layer "In2.Cu")
		(net 279)
	)
	(segment
		(start 147.475001 169.961078)
		(end 147.716423 170.2025)
		(width 0.1)
		(layer "In2.Cu")
		(net 279)
	)
	(segment
		(start 147.475001 168.9005)
		(end 147.475001 169.961078)
		(width 0.1)
		(layer "In2.Cu")
		(net 279)
	)
	(segment
		(start 169.562678 154.909999)
		(end 170.603663 154.909999)
		(width 0.13)
		(layer "In2.Cu")
		(net 279)
	)
	(segment
		(start 154.125223 171.970491)
		(end 154.125223 172.001722)
		(width 0.13)
		(layer "In2.Cu")
		(net 279)
	)
	(segment
		(start 169.800001 151.169999)
		(end 169.562678 151.169999)
		(width 0.13)
		(layer "In2.Cu")
		(net 279)
	)
	(segment
		(start 170.030001 147.492426)
		(end 170.030001 150.939999)
		(width 0.13)
		(layer "In2.Cu")
		(net 279)
	)
	(segment
		(start 148.666423 172.2025)
		(end 152.366558 172.2025)
		(width 0.1)
		(layer "In2.Cu")
		(net 279)
	)
	(segment
		(start 153.425223 171.970491)
		(end 153.425223 172.001722)
		(width 0.13)
		(layer "In2.Cu")
		(net 279)
	)
	(segment
		(start 170.817324 153.72366)
		(end 170.817324 153.756338)
		(width 0.13)
		(layer "In2.Cu")
		(net 279)
	)
	(arc
		(start 153.425223 172.001722)
		(mid 153.373967 172.125466)
		(end 153.250223 172.176722)
		(width 0.13)
		(layer "In2.Cu")
		(net 279)
	)
	(arc
		(start 169.562678 155.369999)
		(mid 169.230338 155.507659)
		(end 169.092678 155.839999)
		(width 0.13)
		(layer "In2.Cu")
		(net 279)
	)
	(arc
		(start 170.030001 157.883525)
		(mid 169.975923 158.155394)
		(end 169.821921 158.385874)
		(width 0.13)
		(layer "In2.Cu")
		(net 279)
	)
	(arc
		(start 169.800001 156.309999)
		(mid 169.962636 156.377364)
		(end 170.030001 156.539999)
		(width 0.13)
		(layer "In2.Cu")
		(net 279)
	)
	(arc
		(start 153.950223 172.176722)
		(mid 153.826479 172.125466)
		(end 153.775223 172.001722)
		(width 0.13)
		(layer "In2.Cu")
		(net 279)
	)
	(arc
		(start 170.817324 152.356338)
		(mid 170.754744 152.507419)
		(end 170.603663 152.569999)
		(width 0.13)
		(layer "In2.Cu")
		(net 279)
	)
	(arc
		(start 169.092678 155.839999)
		(mid 169.230338 156.172339)
		(end 169.562678 156.309999)
		(width 0.13)
		(layer "In2.Cu")
		(net 279)
	)
	(arc
		(start 169.562678 152.569999)
		(mid 169.230338 152.707659)
		(end 169.092678 153.039999)
		(width 0.13)
		(layer "In2.Cu")
		(net 279)
	)
	(arc
		(start 169.092678 153.039999)
		(mid 169.230338 153.372339)
		(end 169.562678 153.509999)
		(width 0.13)
		(layer "In2.Cu")
		(net 279)
	)
	(arc
		(start 154.475223 171.970491)
		(mid 154.423967 171.846747)
		(end 154.300223 171.795491)
		(width 0.13)
		(layer "In2.Cu")
		(net 279)
	)
	(arc
		(start 154.650223 172.176722)
		(mid 154.526479 172.125466)
		(end 154.475223 172.001722)
		(width 0.13)
		(layer "In2.Cu")
		(net 279)
	)
	(arc
		(start 154.300223 171.795491)
		(mid 154.176479 171.846747)
		(end 154.125223 171.970491)
		(width 0.13)
		(layer "In2.Cu")
		(net 279)
	)
	(arc
		(start 170.603663 153.509999)
		(mid 170.754744 153.572579)
		(end 170.817324 153.72366)
		(width 0.13)
		(layer "In2.Cu")
		(net 279)
	)
	(arc
		(start 169.562678 153.969999)
		(mid 169.230338 154.107659)
		(end 169.092678 154.439999)
		(width 0.13)
		(layer "In2.Cu")
		(net 279)
	)
	(arc
		(start 170.817324 153.756338)
		(mid 170.754744 153.907419)
		(end 170.603663 153.969999)
		(width 0.13)
		(layer "In2.Cu")
		(net 279)
	)
	(arc
		(start 154.125223 172.001722)
		(mid 154.073967 172.125466)
		(end 153.950223 172.176722)
		(width 0.13)
		(layer "In2.Cu")
		(net 279)
	)
	(arc
		(start 153.600223 171.795491)
		(mid 153.476479 171.846747)
		(end 153.425223 171.970491)
		(width 0.13)
		(layer "In2.Cu")
		(net 279)
	)
	(arc
		(start 170.603663 152.109999)
		(mid 170.754744 152.172579)
		(end 170.817324 152.32366)
		(width 0.13)
		(layer "In2.Cu")
		(net 279)
	)
	(arc
		(start 153.775223 171.970491)
		(mid 153.723967 171.846747)
		(end 153.600223 171.795491)
		(width 0.13)
		(layer "In2.Cu")
		(net 279)
	)
	(arc
		(start 169.092678 151.639999)
		(mid 169.230338 151.972339)
		(end 169.562678 152.109999)
		(width 0.13)
		(layer "In2.Cu")
		(net 279)
	)
	(arc
		(start 169.092678 154.439999)
		(mid 169.230338 154.772339)
		(end 169.562678 154.909999)
		(width 0.13)
		(layer "In2.Cu")
		(net 279)
	)
	(arc
		(start 169.562678 151.169999)
		(mid 169.230338 151.307659)
		(end 169.092678 151.639999)
		(width 0.13)
		(layer "In2.Cu")
		(net 279)
	)
	(arc
		(start 170.603663 154.909999)
		(mid 170.754744 154.972579)
		(end 170.817324 155.12366)
		(width 0.13)
		(layer "In2.Cu")
		(net 279)
	)
	(arc
		(start 170.817324 155.156338)
		(mid 170.754744 155.307419)
		(end 170.603663 155.369999)
		(width 0.13)
		(layer "In2.Cu")
		(net 279)
	)
	(arc
		(start 170.030001 150.939999)
		(mid 169.962636 151.102634)
		(end 169.800001 151.169999)
		(width 0.13)
		(layer "In2.Cu")
		(net 279)
	)
	(segment
		(start 170.274973 195.525027)
		(end 170.584499 195.215501)
		(width 0.201)
		(layer "F.Cu")
		(net 280)
	)
	(segment
		(start 179.085 182.39)
		(end 179.1 182.375)
		(width 0.182)
		(layer "F.Cu")
		(net 280)
	)
	(segment
		(start 170.584499 195.215501)
		(end 171.021501 195.215501)
		(width 0.201)
		(layer "F.Cu")
		(net 280)
	)
	(segment
		(start 178.385 182.39)
		(end 179.085 182.39)
		(width 0.182)
		(layer "F.Cu")
		(net 280)
	)
	(segment
		(start 170.177688 195.525027)
		(end 170.274973 195.525027)
		(width 0.201)
		(layer "F.Cu")
		(net 280)
	)
	(via
		(at 170.177688 195.525027)
		(size 0.45)
		(drill 0.1)
		(layers "F.Cu" "B.Cu")
		(net 280)
	)
	(via
		(at 179.1 182.375)
		(size 0.45)
		(drill 0.1)
		(layers "F.Cu" "B.Cu")
		(net 280)
	)
	(segment
		(start 167.7 186.9)
		(end 167.7 189.2)
		(width 0.15)
		(layer "B.Cu")
		(net 280)
	)
	(segment
		(start 167.7 189.2)
		(end 166.2 190.7)
		(width 0.15)
		(layer "B.Cu")
		(net 280)
	)
	(segment
		(start 173.05 183.25)
		(end 171.35 183.25)
		(width 0.15)
		(layer "B.Cu")
		(net 280)
	)
	(segment
		(start 171.35 183.25)
		(end 167.7 186.9)
		(width 0.15)
		(layer "B.Cu")
		(net 280)
	)
	(segment
		(start 179.1 182.375)
		(end 173.925 182.375)
		(width 0.15)
		(layer "B.Cu")
		(net 280)
	)
	(segment
		(start 166.2 192.8)
		(end 168.925027 195.525027)
		(width 0.15)
		(layer "B.Cu")
		(net 280)
	)
	(segment
		(start 173.925 182.375)
		(end 173.05 183.25)
		(width 0.15)
		(layer "B.Cu")
		(net 280)
	)
	(segment
		(start 166.2 190.7)
		(end 166.2 192.8)
		(width 0.15)
		(layer "B.Cu")
		(net 280)
	)
	(segment
		(start 168.925027 195.525027)
		(end 170.177688 195.525027)
		(width 0.15)
		(layer "B.Cu")
		(net 280)
	)
	(segment
		(start 178.3975 181.34)
		(end 179.0975 181.34)
		(width 0.182)
		(layer "F.Cu")
		(net 281)
	)
	(segment
		(start 179.0975 181.34)
		(end 179.1125 181.325)
		(width 0.182)
		(layer "F.Cu")
		(net 281)
	)
	(segment
		(start 201.158001 185.2855)
		(end 202.020501 185.2855)
		(width 0.182)
		(layer "F.Cu")
		(net 281)
	)
	(via
		(at 202.020501 185.2855)
		(size 0.45)
		(drill 0.1)
		(layers "F.Cu" "B.Cu")
		(net 281)
	)
	(via
		(at 179.1125 181.325)
		(size 0.45)
		(drill 0.1)
		(layers "F.Cu" "B.Cu")
		(net 281)
	)
	(segment
		(start 181.075 180.05)
		(end 179.8 181.325)
		(width 0.1)
		(layer "In4.Cu")
		(net 281)
	)
	(segment
		(start 201.525 176.1)
		(end 182.875 176.1)
		(width 0.1)
		(layer "In4.Cu")
		(net 281)
	)
	(segment
		(start 202.6 177.175)
		(end 201.525 176.1)
		(width 0.1)
		(layer "In4.Cu")
		(net 281)
	)
	(segment
		(start 202.6 184.766313)
		(end 202.6 177.175)
		(width 0.1)
		(layer "In4.Cu")
		(net 281)
	)
	(segment
		(start 202.080813 185.2855)
		(end 202.6 184.766313)
		(width 0.1)
		(layer "In4.Cu")
		(net 281)
	)
	(segment
		(start 181.075 177.9)
		(end 181.075 180.05)
		(width 0.1)
		(layer "In4.Cu")
		(net 281)
	)
	(segment
		(start 182.875 176.1)
		(end 181.075 177.9)
		(width 0.1)
		(layer "In4.Cu")
		(net 281)
	)
	(segment
		(start 179.8 181.325)
		(end 179.1125 181.325)
		(width 0.1)
		(layer "In4.Cu")
		(net 281)
	)
	(segment
		(start 202.020501 185.2855)
		(end 202.080813 185.2855)
		(width 0.1)
		(layer "In4.Cu")
		(net 281)
	)
	(segment
		(start 202.125 167.85)
		(end 202.1095 167.8345)
		(width 0.182)
		(layer "F.Cu")
		(net 282)
	)
	(segment
		(start 202.1095 167.8345)
		(end 201.131001 167.8345)
		(width 0.182)
		(layer "F.Cu")
		(net 282)
	)
	(segment
		(start 178.385 180.24)
		(end 179.085 180.24)
		(width 0.182)
		(layer "F.Cu")
		(net 282)
	)
	(segment
		(start 179.085 180.24)
		(end 179.1 180.225)
		(width 0.182)
		(layer "F.Cu")
		(net 282)
	)
	(via
		(at 179.1 180.225)
		(size 0.45)
		(drill 0.1)
		(layers "F.Cu" "B.Cu")
		(net 282)
	)
	(via
		(at 202.125 167.85)
		(size 0.45)
		(drill 0.1)
		(layers "F.Cu" "B.Cu")
		(net 282)
	)
	(segment
		(start 182.875 175.525)
		(end 199.925 175.525)
		(width 0.1)
		(layer "In4.Cu")
		(net 282)
	)
	(segment
		(start 201.575 168.4)
		(end 202.125 167.85)
		(width 0.1)
		(layer "In4.Cu")
		(net 282)
	)
	(segment
		(start 199.925 175.525)
		(end 201.575 173.875)
		(width 0.1)
		(layer "In4.Cu")
		(net 282)
	)
	(segment
		(start 179.1 180.225)
		(end 179.725 180.225)
		(width 0.1)
		(layer "In4.Cu")
		(net 282)
	)
	(segment
		(start 180.425 179.525)
		(end 180.425 177.975)
		(width 0.1)
		(layer "In4.Cu")
		(net 282)
	)
	(segment
		(start 180.425 177.975)
		(end 182.875 175.525)
		(width 0.1)
		(layer "In4.Cu")
		(net 282)
	)
	(segment
		(start 179.725 180.225)
		(end 180.425 179.525)
		(width 0.1)
		(layer "In4.Cu")
		(net 282)
	)
	(segment
		(start 201.575 173.875)
		(end 201.575 168.4)
		(width 0.1)
		(layer "In4.Cu")
		(net 282)
	)
	(segment
		(start 170.380001 146.8225)
		(end 170.380002 147.292427)
		(width 0.26)
		(layer "F.Cu")
		(net 283)
	)
	(segment
		(start 170.380002 147.292427)
		(end 170.425001 147.337426)
		(width 0.26)
		(layer "F.Cu")
		(net 283)
	)
	(segment
		(start 146.375501 169.302)
		(end 146.875001 168.8025)
		(width 0.256)
		(layer "F.Cu")
		(net 283)
	)
	(segment
		(start 170.400001 146.8025)
		(end 170.380001 146.8225)
		(width 0.26)
		(layer "F.Cu")
		(net 283)
	)
	(segment
		(start 170.400001 146.2025)
		(end 170.400001 146.8025)
		(width 0.26)
		(layer "F.Cu")
		(net 283)
	)
	(via
		(at 146.875001 168.8025)
		(size 0.45)
		(drill 0.1)
		(layers "F.Cu" "B.Cu")
		(net 283)
	)
	(via
		(at 170.425001 147.337426)
		(size 0.45)
		(drill 0.1)
		(layers "F.Cu" "B.Cu")
		(net 283)
	)
	(segment
		(start 170.004056 158.543151)
		(end 156.130485 172.416722)
		(width 0.13)
		(layer "In2.Cu")
		(net 283)
	)
	(segment
		(start 171.057324 152.32366)
		(end 171.057324 152.356338)
		(width 0.13)
		(layer "In2.Cu")
		(net 283)
	)
	(segment
		(start 170.425001 147.337426)
		(end 170.270001 147.492426)
		(width 0.13)
		(layer "In2.Cu")
		(net 283)
	)
	(segment
		(start 146.875001 168.8025)
		(end 147.173001 168.8025)
		(width 0.1)
		(layer "In2.Cu")
		(net 283)
	)
	(segment
		(start 148.183579 170.4025)
		(end 148.275001 170.493922)
		(width 0.1)
		(layer "In2.Cu")
		(net 283)
	)
	(segment
		(start 148.583579 172.4025)
		(end 152.378114 172.4025)
		(width 0.1)
		(layer "In2.Cu")
		(net 283)
	)
	(segment
		(start 147.173001 168.8025)
		(end 147.275001 168.9045)
		(width 0.1)
		(layer "In2.Cu")
		(net 283)
	)
	(segment
		(start 171.057324 153.72366)
		(end 171.057324 153.756338)
		(width 0.13)
		(layer "In2.Cu")
		(net 283)
	)
	(segment
		(start 170.270001 156.539999)
		(end 170.270001 157.901102)
		(width 0.13)
		(layer "In2.Cu")
		(net 283)
	)
	(segment
		(start 171.057324 155.12366)
		(end 171.057324 155.156338)
		(width 0.13)
		(layer "In2.Cu")
		(net 283)
	)
	(segment
		(start 169.562678 156.069999)
		(end 169.800001 156.069999)
		(width 0.13)
		(layer "In2.Cu")
		(net 283)
	)
	(segment
		(start 148.275001 170.493922)
		(end 148.275001 172.093922)
		(width 0.1)
		(layer "In2.Cu")
		(net 283)
	)
	(segment
		(start 169.800001 151.409999)
		(end 169.562678 151.409999)
		(width 0.13)
		(layer "In2.Cu")
		(net 283)
	)
	(segment
		(start 147.633579 170.4025)
		(end 148.183579 170.4025)
		(width 0.1)
		(layer "In2.Cu")
		(net 283)
	)
	(segment
		(start 152.378114 172.4025)
		(end 152.392336 172.416722)
		(width 0.1)
		(layer "In2.Cu")
		(net 283)
	)
	(segment
		(start 169.562678 154.209999)
		(end 170.603663 154.209999)
		(width 0.13)
		(layer "In2.Cu")
		(net 283)
	)
	(segment
		(start 169.562678 153.269999)
		(end 170.603663 153.269999)
		(width 0.13)
		(layer "In2.Cu")
		(net 283)
	)
	(segment
		(start 169.562678 152.809999)
		(end 170.603663 152.809999)
		(width 0.13)
		(layer "In2.Cu")
		(net 283)
	)
	(segment
		(start 148.275001 172.093922)
		(end 148.583579 172.4025)
		(width 0.1)
		(layer "In2.Cu")
		(net 283)
	)
	(segment
		(start 147.275001 170.043922)
		(end 147.633579 170.4025)
		(width 0.1)
		(layer "In2.Cu")
		(net 283)
	)
	(segment
		(start 147.275001 168.9045)
		(end 147.275001 170.043922)
		(width 0.1)
		(layer "In2.Cu")
		(net 283)
	)
	(segment
		(start 156.130485 172.416722)
		(end 152.392336 172.416722)
		(width 0.13)
		(layer "In2.Cu")
		(net 283)
	)
	(segment
		(start 169.562678 155.609999)
		(end 170.603663 155.609999)
		(width 0.13)
		(layer "In2.Cu")
		(net 283)
	)
	(segment
		(start 169.562678 151.869999)
		(end 170.603663 151.869999)
		(width 0.13)
		(layer "In2.Cu")
		(net 283)
	)
	(segment
		(start 170.270001 147.492426)
		(end 170.270001 150.939999)
		(width 0.13)
		(layer "In2.Cu")
		(net 283)
	)
	(segment
		(start 169.562678 154.669999)
		(end 170.603663 154.669999)
		(width 0.13)
		(layer "In2.Cu")
		(net 283)
	)
	(arc
		(start 169.332678 153.039999)
		(mid 169.400043 153.202634)
		(end 169.562678 153.269999)
		(width 0.13)
		(layer "In2.Cu")
		(net 283)
	)
	(arc
		(start 170.270001 157.901102)
		(mid 170.200884 158.248576)
		(end 170.004056 158.543151)
		(width 0.13)
		(layer "In2.Cu")
		(net 283)
	)
	(arc
		(start 171.057324 152.356338)
		(mid 170.92445 152.677125)
		(end 170.603663 152.809999)
		(width 0.13)
		(layer "In2.Cu")
		(net 283)
	)
	(arc
		(start 169.332678 151.639999)
		(mid 169.400043 151.802634)
		(end 169.562678 151.869999)
		(width 0.13)
		(layer "In2.Cu")
		(net 283)
	)
	(arc
		(start 169.800001 156.069999)
		(mid 170.132341 156.207659)
		(end 170.270001 156.539999)
		(width 0.13)
		(layer "In2.Cu")
		(net 283)
	)
	(arc
		(start 170.603663 151.869999)
		(mid 170.92445 152.002873)
		(end 171.057324 152.32366)
		(width 0.13)
		(layer "In2.Cu")
		(net 283)
	)
	(arc
		(start 169.332678 154.439999)
		(mid 169.400043 154.602634)
		(end 169.562678 154.669999)
		(width 0.13)
		(layer "In2.Cu")
		(net 283)
	)
	(arc
		(start 170.603663 153.269999)
		(mid 170.92445 153.402873)
		(end 171.057324 153.72366)
		(width 0.13)
		(layer "In2.Cu")
		(net 283)
	)
	(arc
		(start 169.562678 152.809999)
		(mid 169.400043 152.877364)
		(end 169.332678 153.039999)
		(width 0.13)
		(layer "In2.Cu")
		(net 283)
	)
	(arc
		(start 170.270001 150.939999)
		(mid 170.132341 151.272339)
		(end 169.800001 151.409999)
		(width 0.13)
		(layer "In2.Cu")
		(net 283)
	)
	(arc
		(start 169.562678 154.209999)
		(mid 169.400043 154.277364)
		(end 169.332678 154.439999)
		(width 0.13)
		(layer "In2.Cu")
		(net 283)
	)
	(arc
		(start 169.562678 155.609999)
		(mid 169.400043 155.677364)
		(end 169.332678 155.839999)
		(width 0.13)
		(layer "In2.Cu")
		(net 283)
	)
	(arc
		(start 171.057324 153.756338)
		(mid 170.92445 154.077125)
		(end 170.603663 154.209999)
		(width 0.13)
		(layer "In2.Cu")
		(net 283)
	)
	(arc
		(start 170.603663 154.669999)
		(mid 170.92445 154.802873)
		(end 171.057324 155.12366)
		(width 0.13)
		(layer "In2.Cu")
		(net 283)
	)
	(arc
		(start 171.057324 155.156338)
		(mid 170.92445 155.477125)
		(end 170.603663 155.609999)
		(width 0.13)
		(layer "In2.Cu")
		(net 283)
	)
	(arc
		(start 169.332678 155.839999)
		(mid 169.400043 156.002634)
		(end 169.562678 156.069999)
		(width 0.13)
		(layer "In2.Cu")
		(net 283)
	)
	(arc
		(start 169.562678 151.409999)
		(mid 169.400043 151.477364)
		(end 169.332678 151.639999)
		(width 0.13)
		(layer "In2.Cu")
		(net 283)
	)
	(segment
		(start 151.375501 171.302001)
		(end 151.875001 170.8025)
		(width 0.256)
		(layer "F.Cu")
		(net 284)
	)
	(segment
		(start 170.650001 138.8025)
		(end 170.650001 139.8775)
		(width 0.201)
		(layer "F.Cu")
		(net 284)
	)
	(via
		(at 170.650001 139.8775)
		(size 0.45)
		(drill 0.1)
		(layers "F.Cu" "B.Cu")
		(net 284)
	)
	(via
		(at 151.875001 170.8025)
		(size 0.45)
		(drill 0.1)
		(layers "F.Cu" "B.Cu")
		(net 284)
	)
	(segment
		(start 166.871304 153.552)
		(end 167.879698 153.552)
		(width 0.148)
		(layer "In2.Cu")
		(net 284)
	)
	(segment
		(start 170.125501 145.302)
		(end 168.425001 147.0025)
		(width 0.148)
		(layer "In2.Cu")
		(net 284)
	)
	(segment
		(start 166.871304 156.052)
		(end 167.879698 156.052)
		(width 0.148)
		(layer "In2.Cu")
		(net 284)
	)
	(segment
		(start 155.025001 170.7525)
		(end 151.925001 170.7525)
		(width 0.148)
		(layer "In2.Cu")
		(net 284)
	)
	(segment
		(start 167.375501 157.802)
		(end 167.375501 158.402)
		(width 0.148)
		(layer "In2.Cu")
		(net 284)
	)
	(segment
		(start 151.925001 170.7525)
		(end 151.875001 170.8025)
		(width 0.148)
		(layer "In2.Cu")
		(net 284)
	)
	(segment
		(start 167.125501 152.552)
		(end 166.871304 152.552)
		(width 0.148)
		(layer "In2.Cu")
		(net 284)
	)
	(segment
		(start 167.375501 158.402)
		(end 155.025001 170.7525)
		(width 0.148)
		(layer "In2.Cu")
		(net 284)
	)
	(segment
		(start 166.871304 154.552)
		(end 167.879698 154.552)
		(width 0.148)
		(layer "In2.Cu")
		(net 284)
	)
	(segment
		(start 170.125501 140.402)
		(end 170.125501 145.302)
		(width 0.148)
		(layer "In2.Cu")
		(net 284)
	)
	(segment
		(start 168.425001 148.0025)
		(end 167.375501 149.052)
		(width 0.148)
		(layer "In2.Cu")
		(net 284)
	)
	(segment
		(start 170.650001 139.8775)
		(end 170.125501 140.402)
		(width 0.148)
		(layer "In2.Cu")
		(net 284)
	)
	(segment
		(start 166.871304 157.052)
		(end 167.879698 157.052)
		(width 0.148)
		(layer "In2.Cu")
		(net 284)
	)
	(segment
		(start 166.871304 156.552)
		(end 167.879698 156.552)
		(width 0.148)
		(layer "In2.Cu")
		(net 284)
	)
	(segment
		(start 166.871304 154.052)
		(end 167.879698 154.052)
		(width 0.148)
		(layer "In2.Cu")
		(net 284)
	)
	(segment
		(start 166.871304 153.052)
		(end 167.879698 153.052)
		(width 0.148)
		(layer "In2.Cu")
		(net 284)
	)
	(segment
		(start 166.871304 155.552)
		(end 167.879698 155.552)
		(width 0.148)
		(layer "In2.Cu")
		(net 284)
	)
	(segment
		(start 167.375501 149.052)
		(end 167.375501 152.302)
		(width 0.148)
		(layer "In2.Cu")
		(net 284)
	)
	(segment
		(start 168.425001 147.0025)
		(end 168.425001 148.0025)
		(width 0.148)
		(layer "In2.Cu")
		(net 284)
	)
	(segment
		(start 167.879698 157.552)
		(end 167.625501 157.552)
		(width 0.148)
		(layer "In2.Cu")
		(net 284)
	)
	(segment
		(start 166.871304 155.052)
		(end 167.879698 155.052)
		(width 0.148)
		(layer "In2.Cu")
		(net 284)
	)
	(arc
		(start 168.129698 155.302)
		(mid 168.056475 155.478777)
		(end 167.879698 155.552)
		(width 0.148)
		(layer "In2.Cu")
		(net 284)
	)
	(arc
		(start 166.621304 155.802)
		(mid 166.694527 155.978777)
		(end 166.871304 156.052)
		(width 0.148)
		(layer "In2.Cu")
		(net 284)
	)
	(arc
		(start 168.129698 157.302)
		(mid 168.056475 157.478777)
		(end 167.879698 157.552)
		(width 0.148)
		(layer "In2.Cu")
		(net 284)
	)
	(arc
		(start 167.375501 152.302)
		(mid 167.302278 152.478777)
		(end 167.125501 152.552)
		(width 0.148)
		(layer "In2.Cu")
		(net 284)
	)
	(arc
		(start 166.871304 152.552)
		(mid 166.694527 152.625223)
		(end 166.621304 152.802)
		(width 0.148)
		(layer "In2.Cu")
		(net 284)
	)
	(arc
		(start 167.879698 156.052)
		(mid 168.056475 156.125223)
		(end 168.129698 156.302)
		(width 0.148)
		(layer "In2.Cu")
		(net 284)
	)
	(arc
		(start 166.621304 156.802)
		(mid 166.694527 156.978777)
		(end 166.871304 157.052)
		(width 0.148)
		(layer "In2.Cu")
		(net 284)
	)
	(arc
		(start 167.879698 154.052)
		(mid 168.056475 154.125223)
		(end 168.129698 154.302)
		(width 0.148)
		(layer "In2.Cu")
		(net 284)
	)
	(arc
		(start 166.621304 154.802)
		(mid 166.694527 154.978777)
		(end 166.871304 155.052)
		(width 0.148)
		(layer "In2.Cu")
		(net 284)
	)
	(arc
		(start 166.871304 154.552)
		(mid 166.694527 154.625223)
		(end 166.621304 154.802)
		(width 0.148)
		(layer "In2.Cu")
		(net 284)
	)
	(arc
		(start 168.129698 153.302)
		(mid 168.056475 153.478777)
		(end 167.879698 153.552)
		(width 0.148)
		(layer "In2.Cu")
		(net 284)
	)
	(arc
		(start 166.621304 152.802)
		(mid 166.694527 152.978777)
		(end 166.871304 153.052)
		(width 0.148)
		(layer "In2.Cu")
		(net 284)
	)
	(arc
		(start 167.625501 157.552)
		(mid 167.448724 157.625223)
		(end 167.375501 157.802)
		(width 0.148)
		(layer "In2.Cu")
		(net 284)
	)
	(arc
		(start 167.879698 155.052)
		(mid 168.056475 155.125223)
		(end 168.129698 155.302)
		(width 0.148)
		(layer "In2.Cu")
		(net 284)
	)
	(arc
		(start 166.871304 155.552)
		(mid 166.694527 155.625223)
		(end 166.621304 155.802)
		(width 0.148)
		(layer "In2.Cu")
		(net 284)
	)
	(arc
		(start 168.129698 154.302)
		(mid 168.056475 154.478777)
		(end 167.879698 154.552)
		(width 0.148)
		(layer "In2.Cu")
		(net 284)
	)
	(arc
		(start 167.879698 153.052)
		(mid 168.056475 153.125223)
		(end 168.129698 153.302)
		(width 0.148)
		(layer "In2.Cu")
		(net 284)
	)
	(arc
		(start 166.871304 153.552)
		(mid 166.694527 153.625223)
		(end 166.621304 153.802)
		(width 0.148)
		(layer "In2.Cu")
		(net 284)
	)
	(arc
		(start 168.129698 156.302)
		(mid 168.056475 156.478777)
		(end 167.879698 156.552)
		(width 0.148)
		(layer "In2.Cu")
		(net 284)
	)
	(arc
		(start 166.871304 156.552)
		(mid 166.694527 156.625223)
		(end 166.621304 156.802)
		(width 0.148)
		(layer "In2.Cu")
		(net 284)
	)
	(arc
		(start 166.621304 153.802)
		(mid 166.694527 153.978777)
		(end 166.871304 154.052)
		(width 0.148)
		(layer "In2.Cu")
		(net 284)
	)
	(arc
		(start 167.879698 157.052)
		(mid 168.056475 157.125223)
		(end 168.129698 157.302)
		(width 0.148)
		(layer "In2.Cu")
		(net 284)
	)
	(segment
		(start 197.65 162.7)
		(end 197.668501 162.718501)
		(width 0.177)
		(layer "F.Cu")
		(net 285)
	)
	(segment
		(start 197.668501 162.718501)
		(end 197.668501 163.7215)
		(width 0.177)
		(layer "F.Cu")
		(net 285)
	)
	(segment
		(start 205.0785 155.8025)
		(end 206.0795 155.8025)
		(width 0.256)
		(layer "F.Cu")
		(net 285)
	)
	(via
		(at 197.65 162.7)
		(size 0.45)
		(drill 0.1)
		(layers "F.Cu" "B.Cu")
		(net 285)
	)
	(via
		(at 206.0795 155.8025)
		(size 0.45)
		(drill 0.1)
		(layers "F.Cu" "B.Cu")
		(net 285)
	)
	(segment
		(start 197.65 162.7)
		(end 197.65 162.6)
		(width 0.198)
		(layer "B.Cu")
		(net 285)
	)
	(segment
		(start 197.65 162.6)
		(end 198.4 161.85)
		(width 0.198)
		(layer "B.Cu")
		(net 285)
	)
	(segment
		(start 198.4 161.85)
		(end 198.4 161.6)
		(width 0.198)
		(layer "B.Cu")
		(net 285)
	)
	(segment
		(start 195.2 159.55)
		(end 197.65 162)
		(width 0.1)
		(layer "In2.Cu")
		(net 285)
	)
	(segment
		(start 195.2 156.55)
		(end 195.2 159.55)
		(width 0.1)
		(layer "In2.Cu")
		(net 285)
	)
	(segment
		(start 206.0795 155.8025)
		(end 204.577 154.3)
		(width 0.1)
		(layer "In2.Cu")
		(net 285)
	)
	(segment
		(start 197.45 154.3)
		(end 195.2 156.55)
		(width 0.1)
		(layer "In2.Cu")
		(net 285)
	)
	(segment
		(start 204.577 154.3)
		(end 197.45 154.3)
		(width 0.1)
		(layer "In2.Cu")
		(net 285)
	)
	(segment
		(start 197.65 162)
		(end 197.65 162.7)
		(width 0.1)
		(layer "In2.Cu")
		(net 285)
	)
	(segment
		(start 146.375502 171.302)
		(end 146.875001 170.8025)
		(width 0.256)
		(layer "F.Cu")
		(net 286)
	)
	(segment
		(start 171.400001 146.2025)
		(end 171.400001 147.2775)
		(width 0.201)
		(layer "F.Cu")
		(net 286)
	)
	(via
		(at 171.400001 147.2775)
		(size 0.45)
		(drill 0.1)
		(layers "F.Cu" "B.Cu")
		(net 286)
	)
	(via
		(at 146.875001 170.8025)
		(size 0.45)
		(drill 0.1)
		(layers "F.Cu" "B.Cu")
		(net 286)
	)
	(segment
		(start 146.375001 171.3025)
		(end 146.875001 170.8025)
		(width 0.148)
		(layer "In2.Cu")
		(net 286)
	)
	(segment
		(start 152.578 174.2015)
		(end 147.709729 174.2015)
		(width 0.148)
		(layer "In2.Cu")
		(net 286)
	)
	(segment
		(start 172.090558 153.252)
		(end 172.660444 153.252)
		(width 0.148)
		(layer "In2.Cu")
		(net 286)
	)
	(segment
		(start 171.400001 147.2775)
		(end 171.400001 147.8755)
		(width 0.148)
		(layer "In2.Cu")
		(net 286)
	)
	(segment
		(start 172.375501 148.851)
		(end 172.375501 150.002)
		(width 0.148)
		(layer "In2.Cu")
		(net 286)
	)
	(segment
		(start 171.400001 147.8755)
		(end 172.375501 148.851)
		(width 0.148)
		(layer "In2.Cu")
		(net 286)
	)
	(segment
		(start 172.125501 150.252)
		(end 172.090558 150.252)
		(width 0.148)
		(layer "In2.Cu")
		(net 286)
	)
	(segment
		(start 172.090558 150.752)
		(end 172.125501 150.752)
		(width 0.148)
		(layer "In2.Cu")
		(net 286)
	)
	(segment
		(start 152.877 173.9025)
		(end 152.578 174.2015)
		(width 0.148)
		(layer "In2.Cu")
		(net 286)
	)
	(segment
		(start 157.150001 173.9025)
		(end 152.877 173.9025)
		(width 0.148)
		(layer "In2.Cu")
		(net 286)
	)
	(segment
		(start 147.04532 173.272819)
		(end 146.704682 173.272819)
		(width 0.148)
		(layer "In2.Cu")
		(net 286)
	)
	(segment
		(start 147.709729 174.2015)
		(end 147.375001 173.866772)
		(width 0.148)
		(layer "In2.Cu")
		(net 286)
	)
	(segment
		(start 146.375001 172.943138)
		(end 146.375001 171.3025)
		(width 0.148)
		(layer "In2.Cu")
		(net 286)
	)
	(segment
		(start 172.090558 151.752)
		(end 172.660444 151.752)
		(width 0.148)
		(layer "In2.Cu")
		(net 286)
	)
	(segment
		(start 147.375001 173.866772)
		(end 147.375001 173.6025)
		(width 0.148)
		(layer "In2.Cu")
		(net 286)
	)
	(segment
		(start 172.375501 156.502)
		(end 172.375501 158.677)
		(width 0.148)
		(layer "In2.Cu")
		(net 286)
	)
	(segment
		(start 172.090558 154.252)
		(end 172.660444 154.252)
		(width 0.148)
		(layer "In2.Cu")
		(net 286)
	)
	(segment
		(start 172.090558 155.752)
		(end 172.660444 155.752)
		(width 0.148)
		(layer "In2.Cu")
		(net 286)
	)
	(segment
		(start 146.704682 173.272819)
		(end 146.375001 172.943138)
		(width 0.148)
		(layer "In2.Cu")
		(net 286)
	)
	(segment
		(start 172.090558 153.752)
		(end 172.660444 153.752)
		(width 0.148)
		(layer "In2.Cu")
		(net 286)
	)
	(segment
		(start 172.660444 156.252)
		(end 172.625501 156.252)
		(width 0.148)
		(layer "In2.Cu")
		(net 286)
	)
	(segment
		(start 172.375501 158.677)
		(end 157.150001 173.9025)
		(width 0.148)
		(layer "In2.Cu")
		(net 286)
	)
	(segment
		(start 172.125501 150.752)
		(end 172.660444 150.752)
		(width 0.148)
		(layer "In2.Cu")
		(net 286)
	)
	(segment
		(start 172.090558 152.252)
		(end 172.660444 152.252)
		(width 0.148)
		(layer "In2.Cu")
		(net 286)
	)
	(segment
		(start 172.090558 155.252)
		(end 172.660444 155.252)
		(width 0.148)
		(layer "In2.Cu")
		(net 286)
	)
	(segment
		(start 172.090558 151.252)
		(end 172.660444 151.252)
		(width 0.148)
		(layer "In2.Cu")
		(net 286)
	)
	(segment
		(start 172.090558 154.752)
		(end 172.660444 154.752)
		(width 0.148)
		(layer "In2.Cu")
		(net 286)
	)
	(segment
		(start 172.090558 152.752)
		(end 172.660444 152.752)
		(width 0.148)
		(layer "In2.Cu")
		(net 286)
	)
	(segment
		(start 147.375001 173.6025)
		(end 147.04532 173.272819)
		(width 0.148)
		(layer "In2.Cu")
		(net 286)
	)
	(arc
		(start 171.840558 154.502)
		(mid 171.913781 154.678777)
		(end 172.090558 154.752)
		(width 0.148)
		(layer "In2.Cu")
		(net 286)
	)
	(arc
		(start 172.625501 156.252)
		(mid 172.448724 156.325223)
		(end 172.375501 156.502)
		(width 0.148)
		(layer "In2.Cu")
		(net 286)
	)
	(arc
		(start 172.090558 150.252)
		(mid 171.913781 150.325223)
		(end 171.840558 150.502)
		(width 0.148)
		(layer "In2.Cu")
		(net 286)
	)
	(arc
		(start 172.910444 154.002)
		(mid 172.837221 154.178777)
		(end 172.660444 154.252)
		(width 0.148)
		(layer "In2.Cu")
		(net 286)
	)
	(arc
		(start 172.660444 151.752)
		(mid 172.837221 151.825223)
		(end 172.910444 152.002)
		(width 0.148)
		(layer "In2.Cu")
		(net 286)
	)
	(arc
		(start 172.090558 154.252)
		(mid 171.913781 154.325223)
		(end 171.840558 154.502)
		(width 0.148)
		(layer "In2.Cu")
		(net 286)
	)
	(arc
		(start 171.840558 153.502)
		(mid 171.913781 153.678777)
		(end 172.090558 153.752)
		(width 0.148)
		(layer "In2.Cu")
		(net 286)
	)
	(arc
		(start 172.090558 153.252)
		(mid 171.913781 153.325223)
		(end 171.840558 153.502)
		(width 0.148)
		(layer "In2.Cu")
		(net 286)
	)
	(arc
		(start 172.090558 155.252)
		(mid 171.913781 155.325223)
		(end 171.840558 155.502)
		(width 0.148)
		(layer "In2.Cu")
		(net 286)
	)
	(arc
		(start 172.910444 156.002)
		(mid 172.837221 156.178777)
		(end 172.660444 156.252)
		(width 0.148)
		(layer "In2.Cu")
		(net 286)
	)
	(arc
		(start 171.840558 152.502)
		(mid 171.913781 152.678777)
		(end 172.090558 152.752)
		(width 0.148)
		(layer "In2.Cu")
		(net 286)
	)
	(arc
		(start 171.840558 155.502)
		(mid 171.913781 155.678777)
		(end 172.090558 155.752)
		(width 0.148)
		(layer "In2.Cu")
		(net 286)
	)
	(arc
		(start 172.660444 152.752)
		(mid 172.837221 152.825223)
		(end 172.910444 153.002)
		(width 0.148)
		(layer "In2.Cu")
		(net 286)
	)
	(arc
		(start 172.090558 151.252)
		(mid 171.913781 151.325223)
		(end 171.840558 151.502)
		(width 0.148)
		(layer "In2.Cu")
		(net 286)
	)
	(arc
		(start 172.910444 153.002)
		(mid 172.837221 153.178777)
		(end 172.660444 153.252)
		(width 0.148)
		(layer "In2.Cu")
		(net 286)
	)
	(arc
		(start 172.660444 154.752)
		(mid 172.837221 154.825223)
		(end 172.910444 155.002)
		(width 0.148)
		(layer "In2.Cu")
		(net 286)
	)
	(arc
		(start 172.910444 152.002)
		(mid 172.837221 152.178777)
		(end 172.660444 152.252)
		(width 0.148)
		(layer "In2.Cu")
		(net 286)
	)
	(arc
		(start 172.375501 150.002)
		(mid 172.302278 150.178777)
		(end 172.125501 150.252)
		(width 0.148)
		(layer "In2.Cu")
		(net 286)
	)
	(arc
		(start 172.660444 153.752)
		(mid 172.837221 153.825223)
		(end 172.910444 154.002)
		(width 0.148)
		(layer "In2.Cu")
		(net 286)
	)
	(arc
		(start 172.910444 151.002)
		(mid 172.837221 151.178777)
		(end 172.660444 151.252)
		(width 0.148)
		(layer "In2.Cu")
		(net 286)
	)
	(arc
		(start 172.090558 152.252)
		(mid 171.913781 152.325223)
		(end 171.840558 152.502)
		(width 0.148)
		(layer "In2.Cu")
		(net 286)
	)
	(arc
		(start 171.840558 151.502)
		(mid 171.913781 151.678777)
		(end 172.090558 151.752)
		(width 0.148)
		(layer "In2.Cu")
		(net 286)
	)
	(arc
		(start 172.660444 150.752)
		(mid 172.837221 150.825223)
		(end 172.910444 151.002)
		(width 0.148)
		(layer "In2.Cu")
		(net 286)
	)
	(arc
		(start 172.910444 155.002)
		(mid 172.837221 155.178777)
		(end 172.660444 155.252)
		(width 0.148)
		(layer "In2.Cu")
		(net 286)
	)
	(arc
		(start 172.660444 155.752)
		(mid 172.837221 155.825223)
		(end 172.910444 156.002)
		(width 0.148)
		(layer "In2.Cu")
		(net 286)
	)
	(arc
		(start 171.840558 150.502)
		(mid 171.913781 150.678777)
		(end 172.090558 150.752)
		(width 0.148)
		(layer "In2.Cu")
		(net 286)
	)
	(segment
		(start 171.650001 138.8025)
		(end 171.650001 139.8775)
		(width 0.201)
		(layer "F.Cu")
		(net 287)
	)
	(segment
		(start 147.3755 171.302)
		(end 147.875001 170.8025)
		(width 0.256)
		(layer "F.Cu")
		(net 287)
	)
	(via
		(at 171.650001 139.8775)
		(size 0.45)
		(drill 0.1)
		(layers "F.Cu" "B.Cu")
		(net 287)
	)
	(via
		(at 147.875001 170.8025)
		(size 0.45)
		(drill 0.1)
		(layers "F.Cu" "B.Cu")
		(net 287)
	)
	(segment
		(start 159.806896 170.406002)
		(end 159.471499 170.070604)
		(width 0.148)
		(layer "In2.Cu")
		(net 287)
	)
	(segment
		(start 159.789699 169.752406)
		(end 159.789699 169.752405)
		(width 0.148)
		(layer "In2.Cu")
		(net 287)
	)
	(segment
		(start 160.426098 169.116006)
		(end 160.761496 169.451403)
		(width 0.148)
		(layer "In2.Cu")
		(net 287)
	)
	(segment
		(start 171.375501 158.502)
		(end 171.375501 148.651)
		(width 0.148)
		(layer "In2.Cu")
		(net 287)
	)
	(segment
		(start 171.400001 146.1775)
		(end 171.400001 140.1275)
		(width 0.148)
		(layer "In2.Cu")
		(net 287)
	)
	(segment
		(start 161.079694 169.133203)
		(end 161.079694 169.133204)
		(width 0.148)
		(layer "In2.Cu")
		(net 287)
	)
	(segment
		(start 147.476001 171.2015)
		(end 147.476001 172.967772)
		(width 0.148)
		(layer "In2.Cu")
		(net 287)
	)
	(segment
		(start 159.1533 170.388805)
		(end 159.1533 170.388804)
		(width 0.148)
		(layer "In2.Cu")
		(net 287)
	)
	(segment
		(start 147.875001 170.8025)
		(end 147.476001 171.2015)
		(width 0.148)
		(layer "In2.Cu")
		(net 287)
	)
	(segment
		(start 147.476001 172.967772)
		(end 147.810729 173.3025)
		(width 0.148)
		(layer "In2.Cu")
		(net 287)
	)
	(segment
		(start 159.789699 169.752405)
		(end 160.125097 170.087802)
		(width 0.148)
		(layer "In2.Cu")
		(net 287)
	)
	(segment
		(start 147.810729 173.3025)
		(end 156.575001 173.3025)
		(width 0.148)
		(layer "In2.Cu")
		(net 287)
	)
	(segment
		(start 162.075501 167.802)
		(end 171.375501 158.502)
		(width 0.148)
		(layer "In2.Cu")
		(net 287)
	)
	(segment
		(start 161.389296 168.488208)
		(end 162.075501 167.802)
		(width 0.148)
		(layer "In2.Cu")
		(net 287)
	)
	(segment
		(start 159.170497 171.0424)
		(end 159.170497 171.042401)
		(width 0.148)
		(layer "In2.Cu")
		(net 287)
	)
	(segment
		(start 160.426098 169.116007)
		(end 160.426098 169.116006)
		(width 0.148)
		(layer "In2.Cu")
		(net 287)
	)
	(segment
		(start 160.443295 169.769602)
		(end 160.443295 169.769603)
		(width 0.148)
		(layer "In2.Cu")
		(net 287)
	)
	(segment
		(start 171.400001 140.1275)
		(end 171.650001 139.8775)
		(width 0.148)
		(layer "In2.Cu")
		(net 287)
	)
	(segment
		(start 160.443295 169.769603)
		(end 160.107898 169.434205)
		(width 0.148)
		(layer "In2.Cu")
		(net 287)
	)
	(segment
		(start 159.170497 171.042401)
		(end 158.8351 170.707003)
		(width 0.148)
		(layer "In2.Cu")
		(net 287)
	)
	(segment
		(start 170.875001 148.1505)
		(end 170.875001 146.7025)
		(width 0.148)
		(layer "In2.Cu")
		(net 287)
	)
	(segment
		(start 161.079694 169.133204)
		(end 160.744297 168.797806)
		(width 0.148)
		(layer "In2.Cu")
		(net 287)
	)
	(segment
		(start 171.375501 148.651)
		(end 170.875001 148.1505)
		(width 0.148)
		(layer "In2.Cu")
		(net 287)
	)
	(segment
		(start 159.1533 170.388804)
		(end 159.488698 170.724201)
		(width 0.148)
		(layer "In2.Cu")
		(net 287)
	)
	(segment
		(start 159.806896 170.406001)
		(end 159.806896 170.406002)
		(width 0.148)
		(layer "In2.Cu")
		(net 287)
	)
	(segment
		(start 158.843699 171.352)
		(end 158.852299 171.3606)
		(width 0.148)
		(layer "In2.Cu")
		(net 287)
	)
	(segment
		(start 161.062497 168.479608)
		(end 161.062497 168.479607)
		(width 0.148)
		(layer "In2.Cu")
		(net 287)
	)
	(segment
		(start 161.062497 168.479607)
		(end 161.071098 168.488208)
		(width 0.148)
		(layer "In2.Cu")
		(net 287)
	)
	(segment
		(start 156.575001 173.3025)
		(end 158.525501 171.352)
		(width 0.148)
		(layer "In2.Cu")
		(net 287)
	)
	(segment
		(start 170.875001 146.7025)
		(end 171.400001 146.1775)
		(width 0.148)
		(layer "In2.Cu")
		(net 287)
	)
	(arc
		(start 161.079694 169.451403)
		(mid 161.145595 169.292303)
		(end 161.079694 169.133203)
		(width 0.148)
		(layer "In2.Cu")
		(net 287)
	)
	(arc
		(start 158.852299 171.3606)
		(mid 159.011398 171.426501)
		(end 159.170497 171.3606)
		(width 0.148)
		(layer "In2.Cu")
		(net 287)
	)
	(arc
		(start 158.8351 170.707003)
		(mid 158.769199 170.547904)
		(end 158.8351 170.388805)
		(width 0.148)
		(layer "In2.Cu")
		(net 287)
	)
	(arc
		(start 160.744297 168.479608)
		(mid 160.903398 168.413706)
		(end 161.062497 168.479608)
		(width 0.148)
		(layer "In2.Cu")
		(net 287)
	)
	(arc
		(start 159.471499 169.752406)
		(mid 159.6306 169.686504)
		(end 159.789699 169.752406)
		(width 0.148)
		(layer "In2.Cu")
		(net 287)
	)
	(arc
		(start 160.761496 169.451403)
		(mid 160.920595 169.517304)
		(end 161.079694 169.451403)
		(width 0.148)
		(layer "In2.Cu")
		(net 287)
	)
	(arc
		(start 158.525501 171.352)
		(mid 158.6846 171.286099)
		(end 158.843699 171.352)
		(width 0.148)
		(layer "In2.Cu")
		(net 287)
	)
	(arc
		(start 160.125097 170.087802)
		(mid 160.284196 170.153703)
		(end 160.443295 170.087802)
		(width 0.148)
		(layer "In2.Cu")
		(net 287)
	)
	(arc
		(start 159.806896 170.724201)
		(mid 159.872797 170.565101)
		(end 159.806896 170.406001)
		(width 0.148)
		(layer "In2.Cu")
		(net 287)
	)
	(arc
		(start 161.071098 168.488208)
		(mid 161.230197 168.554109)
		(end 161.389296 168.488208)
		(width 0.148)
		(layer "In2.Cu")
		(net 287)
	)
	(arc
		(start 160.107898 169.116007)
		(mid 160.266999 169.050105)
		(end 160.426098 169.116007)
		(width 0.148)
		(layer "In2.Cu")
		(net 287)
	)
	(arc
		(start 159.471499 170.070604)
		(mid 159.405598 169.911505)
		(end 159.471499 169.752406)
		(width 0.148)
		(layer "In2.Cu")
		(net 287)
	)
	(arc
		(start 159.170497 171.3606)
		(mid 159.236398 171.2015)
		(end 159.170497 171.0424)
		(width 0.148)
		(layer "In2.Cu")
		(net 287)
	)
	(arc
		(start 160.443295 170.087802)
		(mid 160.509196 169.928702)
		(end 160.443295 169.769602)
		(width 0.148)
		(layer "In2.Cu")
		(net 287)
	)
	(arc
		(start 160.107898 169.434205)
		(mid 160.041997 169.275106)
		(end 160.107898 169.116007)
		(width 0.148)
		(layer "In2.Cu")
		(net 287)
	)
	(arc
		(start 160.744297 168.797806)
		(mid 160.678396 168.638707)
		(end 160.744297 168.479608)
		(width 0.148)
		(layer "In2.Cu")
		(net 287)
	)
	(arc
		(start 159.488698 170.724201)
		(mid 159.647797 170.790102)
		(end 159.806896 170.724201)
		(width 0.148)
		(layer "In2.Cu")
		(net 287)
	)
	(arc
		(start 158.8351 170.388805)
		(mid 158.994201 170.322903)
		(end 159.1533 170.388805)
		(width 0.148)
		(layer "In2.Cu")
		(net 287)
	)
	(segment
		(start 172.400001 146.2025)
		(end 172.400001 147.2775)
		(width 0.201)
		(layer "F.Cu")
		(net 288)
	)
	(segment
		(start 146.375501 170.302)
		(end 146.875001 169.8025)
		(width 0.256)
		(layer "F.Cu")
		(net 288)
	)
	(via
		(at 146.875001 169.8025)
		(size 0.45)
		(drill 0.1)
		(layers "F.Cu" "B.Cu")
		(net 288)
	)
	(via
		(at 172.400001 147.2775)
		(size 0.45)
		(drill 0.1)
		(layers "F.Cu" "B.Cu")
		(net 288)
	)
	(segment
		(start 144.476 173.103499)
		(end 144.476 170.637229)
		(width 0.148)
		(layer "In2.Cu")
		(net 288)
	)
	(segment
		(start 153.302501 176.375)
		(end 147.747501 176.375)
		(width 0.148)
		(layer "In2.Cu")
		(net 288)
	)
	(segment
		(start 145.375001 174.1025)
		(end 145.375001 173.536228)
		(width 0.148)
		(layer "In2.Cu")
		(net 288)
	)
	(segment
		(start 147.375001 175.2025)
		(end 146.975001 174.8025)
		(width 0.148)
		(layer "In2.Cu")
		(net 288)
	)
	(segment
		(start 146.475001 174.8025)
		(end 146.075001 174.4025)
		(width 0.148)
		(layer "In2.Cu")
		(net 288)
	)
	(segment
		(start 147.747501 176.375)
		(end 147.375001 176.0025)
		(width 0.148)
		(layer "In2.Cu")
		(net 288)
	)
	(segment
		(start 154.425001 175.2525)
		(end 153.302501 176.375)
		(width 0.148)
		(layer "In2.Cu")
		(net 288)
	)
	(segment
		(start 173.784799 148.187674)
		(end 173.7848 148.187675)
		(width 0.148)
		(layer "In2.Cu")
		(net 288)
	)
	(segment
		(start 145.375001 173.536228)
		(end 145.142272 173.303499)
		(width 0.148)
		(layer "In2.Cu")
		(net 288)
	)
	(segment
		(start 145.675001 174.4025)
		(end 145.375001 174.1025)
		(width 0.148)
		(layer "In2.Cu")
		(net 288)
	)
	(segment
		(start 174.375501 158.852)
		(end 157.975001 175.2525)
		(width 0.148)
		(layer "In2.Cu")
		(net 288)
	)
	(segment
		(start 174.375501 149.278)
		(end 174.375501 158.852)
		(width 0.148)
		(layer "In2.Cu")
		(net 288)
	)
	(segment
		(start 173.784799 148.435162)
		(end 173.784801 148.435163)
		(width 0.148)
		(layer "In2.Cu")
		(net 288)
	)
	(segment
		(start 173.782474 148.684973)
		(end 173.782475 148.684974)
		(width 0.148)
		(layer "In2.Cu")
		(net 288)
	)
	(segment
		(start 146.075001 174.4025)
		(end 145.675001 174.4025)
		(width 0.148)
		(layer "In2.Cu")
		(net 288)
	)
	(segment
		(start 173.784801 148.435163)
		(end 173.782475 148.437486)
		(width 0.148)
		(layer "In2.Cu")
		(net 288)
	)
	(segment
		(start 172.400001 147.2775)
		(end 172.400001 147.3025)
		(width 0.148)
		(layer "In2.Cu")
		(net 288)
	)
	(segment
		(start 173.534988 148.189999)
		(end 173.534989 148.190001)
		(width 0.148)
		(layer "In2.Cu")
		(net 288)
	)
	(segment
		(start 172.400001 147.3025)
		(end 173.287501 148.19)
		(width 0.148)
		(layer "In2.Cu")
		(net 288)
	)
	(segment
		(start 147.375001 176.0025)
		(end 147.375001 175.2025)
		(width 0.148)
		(layer "In2.Cu")
		(net 288)
	)
	(segment
		(start 146.325001 170.3525)
		(end 146.875001 169.8025)
		(width 0.148)
		(layer "In2.Cu")
		(net 288)
	)
	(segment
		(start 173.782475 148.684974)
		(end 174.375501 149.278)
		(width 0.148)
		(layer "In2.Cu")
		(net 288)
	)
	(segment
		(start 144.476 170.637229)
		(end 144.760729 170.3525)
		(width 0.148)
		(layer "In2.Cu")
		(net 288)
	)
	(segment
		(start 144.676 173.303499)
		(end 144.476 173.103499)
		(width 0.148)
		(layer "In2.Cu")
		(net 288)
	)
	(segment
		(start 146.975001 174.8025)
		(end 146.475001 174.8025)
		(width 0.148)
		(layer "In2.Cu")
		(net 288)
	)
	(segment
		(start 145.142272 173.303499)
		(end 144.676 173.303499)
		(width 0.148)
		(layer "In2.Cu")
		(net 288)
	)
	(segment
		(start 157.975001 175.2525)
		(end 154.425001 175.2525)
		(width 0.148)
		(layer "In2.Cu")
		(net 288)
	)
	(segment
		(start 173.534989 148.190001)
		(end 173.537312 148.187675)
		(width 0.148)
		(layer "In2.Cu")
		(net 288)
	)
	(segment
		(start 144.760729 170.3525)
		(end 146.325001 170.3525)
		(width 0.148)
		(layer "In2.Cu")
		(net 288)
	)
	(arc
		(start 173.7848 148.187675)
		(mid 173.836056 148.311419)
		(end 173.784799 148.435162)
		(width 0.148)
		(layer "In2.Cu")
		(net 288)
	)
	(arc
		(start 173.537312 148.187675)
		(mid 173.661055 148.136418)
		(end 173.784799 148.187674)
		(width 0.148)
		(layer "In2.Cu")
		(net 288)
	)
	(arc
		(start 173.287501 148.19)
		(mid 173.411245 148.241256)
		(end 173.534988 148.189999)
		(width 0.148)
		(layer "In2.Cu")
		(net 288)
	)
	(arc
		(start 173.782475 148.437486)
		(mid 173.731218 148.561229)
		(end 173.782474 148.684973)
		(width 0.148)
		(layer "In2.Cu")
		(net 288)
	)
	(segment
		(start 172.650001 138.8025)
		(end 172.650001 139.8775)
		(width 0.201)
		(layer "F.Cu")
		(net 289)
	)
	(segment
		(start 145.375501 171.302)
		(end 145.875001 170.8025)
		(width 0.256)
		(layer "F.Cu")
		(net 289)
	)
	(via
		(at 172.650001 139.8775)
		(size 0.45)
		(drill 0.1)
		(layers "F.Cu" "B.Cu")
		(net 289)
	)
	(via
		(at 145.875001 170.8025)
		(size 0.45)
		(drill 0.1)
		(layers "F.Cu" "B.Cu")
		(net 289)
	)
	(segment
		(start 145.875001 170.8025)
		(end 145.375001 171.3025)
		(width 0.148)
		(layer "In2.Cu")
		(net 289)
	)
	(segment
		(start 148.175001 175.3025)
		(end 149.675001 175.3025)
		(width 0.148)
		(layer "In2.Cu")
		(net 289)
	)
	(segment
		(start 146.125001 173.3025)
		(end 146.375001 173.5525)
		(width 0.148)
		(layer "In2.Cu")
		(net 289)
	)
	(segment
		(start 149.675001 175.3025)
		(end 149.976001 175.001501)
		(width 0.148)
		(layer "In2.Cu")
		(net 289)
	)
	(segment
		(start 173.375501 158.752)
		(end 173.375501 149.103)
		(width 0.148)
		(layer "In2.Cu")
		(net 289)
	)
	(segment
		(start 152.64 175.001501)
		(end 153.039001 174.6025)
		(width 0.148)
		(layer "In2.Cu")
		(net 289)
	)
	(segment
		(start 171.975001 147.7025)
		(end 171.975001 146.3875)
		(width 0.148)
		(layer "In2.Cu")
		(net 289)
	)
	(segment
		(start 172.375501 140.152)
		(end 172.650001 139.8775)
		(width 0.148)
		(layer "In2.Cu")
		(net 289)
	)
	(segment
		(start 172.375501 145.987)
		(end 172.375501 140.152)
		(width 0.148)
		(layer "In2.Cu")
		(net 289)
	)
	(segment
		(start 173.375501 149.103)
		(end 171.975001 147.7025)
		(width 0.148)
		(layer "In2.Cu")
		(net 289)
	)
	(segment
		(start 149.976001 175.001501)
		(end 152.64 175.001501)
		(width 0.148)
		(layer "In2.Cu")
		(net 289)
	)
	(segment
		(start 171.975001 146.3875)
		(end 172.375501 145.987)
		(width 0.148)
		(layer "In2.Cu")
		(net 289)
	)
	(segment
		(start 145.375001 173.0025)
		(end 145.675001 173.3025)
		(width 0.148)
		(layer "In2.Cu")
		(net 289)
	)
	(segment
		(start 146.375001 174.1025)
		(end 146.575001 174.3025)
		(width 0.148)
		(layer "In2.Cu")
		(net 289)
	)
	(segment
		(start 146.575001 174.3025)
		(end 147.175001 174.3025)
		(width 0.148)
		(layer "In2.Cu")
		(net 289)
	)
	(segment
		(start 153.039001 174.6025)
		(end 157.525001 174.6025)
		(width 0.148)
		(layer "In2.Cu")
		(net 289)
	)
	(segment
		(start 145.675001 173.3025)
		(end 146.125001 173.3025)
		(width 0.148)
		(layer "In2.Cu")
		(net 289)
	)
	(segment
		(start 145.375001 171.3025)
		(end 145.375001 173.0025)
		(width 0.148)
		(layer "In2.Cu")
		(net 289)
	)
	(segment
		(start 146.375001 173.5525)
		(end 146.375001 174.1025)
		(width 0.148)
		(layer "In2.Cu")
		(net 289)
	)
	(segment
		(start 157.525001 174.6025)
		(end 173.375501 158.752)
		(width 0.148)
		(layer "In2.Cu")
		(net 289)
	)
	(segment
		(start 147.175001 174.3025)
		(end 148.175001 175.3025)
		(width 0.148)
		(layer "In2.Cu")
		(net 289)
	)
	(segment
		(start 78.932002 155.8)
		(end 78.087 155.8)
		(width 0.201)
		(layer "F.Cu")
		(net 290)
	)
	(segment
		(start 87.335 162.668346)
		(end 80.132655 155.466001)
		(width 0.2)
		(layer "F.Cu")
		(net 290)
	)
	(segment
		(start 80.132655 155.466001)
		(end 79.266001 155.466001)
		(width 0.2)
		(layer "F.Cu")
		(net 290)
	)
	(segment
		(start 75.936 156.064)
		(end 75.200501 156.064)
		(width 0.201)
		(layer "F.Cu")
		(net 290)
	)
	(segment
		(start 93.950501 174.550501)
		(end 88.967155 174.550501)
		(width 0.2)
		(layer "F.Cu")
		(net 290)
	)
	(segment
		(start 78.087 155.8)
		(end 77.315 155.8)
		(width 0.201)
		(layer "F.Cu")
		(net 290)
	)
	(segment
		(start 78.932002 155.8)
		(end 79.266001 155.466001)
		(width 0.201)
		(layer "F.Cu")
		(net 290)
	)
	(segment
		(start 77.315 155.8)
		(end 76.2 155.8)
		(width 0.201)
		(layer "F.Cu")
		(net 290)
	)
	(segment
		(start 74.466 155.066)
		(end 74.3 154.9)
		(width 0.256)
		(layer "F.Cu")
		(net 290)
	)
	(segment
		(start 87.335 172.918346)
		(end 87.335 162.668346)
		(width 0.2)
		(layer "F.Cu")
		(net 290)
	)
	(segment
		(start 74.278102 156.447813)
		(end 74.661915 156.064)
		(width 0.201)
		(layer "F.Cu")
		(net 290)
	)
	(segment
		(start 74.661915 156.064)
		(end 75.200501 156.064)
		(width 0.201)
		(layer "F.Cu")
		(net 290)
	)
	(segment
		(start 76.2 155.8)
		(end 75.936 156.064)
		(width 0.201)
		(layer "F.Cu")
		(net 290)
	)
	(segment
		(start 94.035 174.635)
		(end 93.950501 174.550501)
		(width 0.2)
		(layer "F.Cu")
		(net 290)
	)
	(segment
		(start 88.967155 174.550501)
		(end 87.335 172.918346)
		(width 0.2)
		(layer "F.Cu")
		(net 290)
	)
	(segment
		(start 94.621501 174.635)
		(end 94.035 174.635)
		(width 0.2)
		(layer "F.Cu")
		(net 290)
	)
	(segment
		(start 75.200501 155.066)
		(end 74.466 155.066)
		(width 0.256)
		(layer "F.Cu")
		(net 290)
	)
	(via
		(at 74.3 154.9)
		(size 0.45)
		(drill 0.1)
		(layers "F.Cu" "B.Cu")
		(net 290)
	)
	(via
		(at 74.278102 156.447813)
		(size 0.45)
		(drill 0.1)
		(layers "F.Cu" "B.Cu")
		(net 290)
	)
	(segment
		(start 73.847 156.016711)
		(end 74.278102 156.447813)
		(width 0.114)
		(layer "In2.Cu")
		(net 290)
	)
	(segment
		(start 74.3 154.9)
		(end 73.847 155.353)
		(width 0.114)
		(layer "In2.Cu")
		(net 290)
	)
	(segment
		(start 73.847 155.353)
		(end 73.847 156.016711)
		(width 0.114)
		(layer "In2.Cu")
		(net 290)
	)
	(segment
		(start 80.269345 155.135999)
		(end 79.275 155.135999)
		(width 0.2)
		(layer "F.Cu")
		(net 291)
	)
	(segment
		(start 93.920499 174.220499)
		(end 89.103845 174.220499)
		(width 0.2)
		(layer "F.Cu")
		(net 291)
	)
	(segment
		(start 78.941001 154.802)
		(end 78.087 154.802)
		(width 0.201)
		(layer "F.Cu")
		(net 291)
	)
	(segment
		(start 76.236 154.802)
		(end 76 154.566)
		(width 0.201)
		(layer "F.Cu")
		(net 291)
	)
	(segment
		(start 76 154.566)
		(end 75.200501 154.566)
		(width 0.201)
		(layer "F.Cu")
		(net 291)
	)
	(segment
		(start 74.641665 154.564)
		(end 75.200501 154.564)
		(width 0.201)
		(layer "F.Cu")
		(net 291)
	)
	(segment
		(start 75.200501 155.564)
		(end 74.465999 155.564)
		(width 0.256)
		(layer "F.Cu")
		(net 291)
	)
	(segment
		(start 89.103845 174.220499)
		(end 87.665 172.781654)
		(width 0.2)
		(layer "F.Cu")
		(net 291)
	)
	(segment
		(start 78.941001 154.802)
		(end 79.275 155.135999)
		(width 0.201)
		(layer "F.Cu")
		(net 291)
	)
	(segment
		(start 77.315 154.802)
		(end 78.087 154.802)
		(width 0.201)
		(layer "F.Cu")
		(net 291)
	)
	(segment
		(start 94.621501 174.136)
		(end 94.004998 174.136)
		(width 0.2)
		(layer "F.Cu")
		(net 291)
	)
	(segment
		(start 77.315 154.802)
		(end 76.236 154.802)
		(width 0.201)
		(layer "F.Cu")
		(net 291)
	)
	(segment
		(start 87.665 162.531654)
		(end 80.269345 155.135999)
		(width 0.2)
		(layer "F.Cu")
		(net 291)
	)
	(segment
		(start 74.280533 154.202868)
		(end 74.641665 154.564)
		(width 0.201)
		(layer "F.Cu")
		(net 291)
	)
	(segment
		(start 74.465999 155.564)
		(end 74.3 155.73)
		(width 0.256)
		(layer "F.Cu")
		(net 291)
	)
	(segment
		(start 87.665 172.781654)
		(end 87.665 162.531654)
		(width 0.2)
		(layer "F.Cu")
		(net 291)
	)
	(segment
		(start 94.004998 174.136)
		(end 93.920499 174.220499)
		(width 0.2)
		(layer "F.Cu")
		(net 291)
	)
	(via
		(at 74.280533 154.202868)
		(size 0.45)
		(drill 0.1)
		(layers "F.Cu" "B.Cu")
		(net 291)
	)
	(via
		(at 74.3 155.73)
		(size 0.45)
		(drill 0.1)
		(layers "F.Cu" "B.Cu")
		(net 291)
	)
	(segment
		(start 74.280533 154.202868)
		(end 74.7255 154.647835)
		(width 0.114)
		(layer "In2.Cu")
		(net 291)
	)
	(segment
		(start 74.7255 155.3045)
		(end 74.3 155.73)
		(width 0.114)
		(layer "In2.Cu")
		(net 291)
	)
	(segment
		(start 74.7255 154.647835)
		(end 74.7255 155.3045)
		(width 0.114)
		(layer "In2.Cu")
		(net 291)
	)
	(segment
		(start 82.787 195.1)
		(end 82.015 195.1)
		(width 0.16)
		(layer "F.Cu")
		(net 292)
	)
	(segment
		(start 82.787 195.1)
		(end 83.198 195.1)
		(width 0.16)
		(layer "F.Cu")
		(net 292)
	)
	(segment
		(start 81.507001 195.005001)
		(end 81.602 195.1)
		(width 0.16)
		(layer "F.Cu")
		(net 292)
	)
	(segment
		(start 84.165 195.35)
		(end 83.820001 195.005001)
		(width 0.16)
		(layer "F.Cu")
		(net 292)
	)
	(segment
		(start 81.602 195.1)
		(end 82.015 195.1)
		(width 0.16)
		(layer "F.Cu")
		(net 292)
	)
	(segment
		(start 78.244501 195.3165)
		(end 80.3335 195.3165)
		(width 0.16)
		(layer "F.Cu")
		(net 292)
	)
	(segment
		(start 83.820001 195.005001)
		(end 83.292999 195.005001)
		(width 0.16)
		(layer "F.Cu")
		(net 292)
	)
	(segment
		(start 83.198 195.1)
		(end 83.292999 195.005001)
		(width 0.16)
		(layer "F.Cu")
		(net 292)
	)
	(segment
		(start 80.644999 195.005001)
		(end 81.507001 195.005001)
		(width 0.16)
		(layer "F.Cu")
		(net 292)
	)
	(segment
		(start 80.3335 195.3165)
		(end 80.644999 195.005001)
		(width 0.16)
		(layer "F.Cu")
		(net 292)
	)
	(segment
		(start 80.2655 194.3155)
		(end 80.644999 194.694999)
		(width 0.16)
		(layer "F.Cu")
		(net 293)
	)
	(segment
		(start 81.496999 194.694999)
		(end 81.591998 194.6)
		(width 0.16)
		(layer "F.Cu")
		(net 293)
	)
	(segment
		(start 82.787 194.6)
		(end 83.202 194.6)
		(width 0.16)
		(layer "F.Cu")
		(net 293)
	)
	(segment
		(start 81.591998 194.6)
		(end 82.015 194.6)
		(width 0.16)
		(layer "F.Cu")
		(net 293)
	)
	(segment
		(start 83.202 194.6)
		(end 83.296999 194.694999)
		(width 0.16)
		(layer "F.Cu")
		(net 293)
	)
	(segment
		(start 78.244501 194.3155)
		(end 80.2655 194.3155)
		(width 0.16)
		(layer "F.Cu")
		(net 293)
	)
	(segment
		(start 83.820001 194.694999)
		(end 83.296999 194.694999)
		(width 0.16)
		(layer "F.Cu")
		(net 293)
	)
	(segment
		(start 82.787 194.6)
		(end 82.015 194.6)
		(width 0.16)
		(layer "F.Cu")
		(net 293)
	)
	(segment
		(start 80.644999 194.694999)
		(end 81.496999 194.694999)
		(width 0.16)
		(layer "F.Cu")
		(net 293)
	)
	(segment
		(start 84.165 194.35)
		(end 83.820001 194.694999)
		(width 0.16)
		(layer "F.Cu")
		(net 293)
	)
	(segment
		(start 83.198 193.602)
		(end 83.292999 193.507001)
		(width 0.16)
		(layer "F.Cu")
		(net 294)
	)
	(segment
		(start 80.542999 193.507001)
		(end 81.507001 193.507001)
		(width 0.16)
		(layer "F.Cu")
		(net 294)
	)
	(segment
		(start 81.507001 193.507001)
		(end 81.602 193.602)
		(width 0.16)
		(layer "F.Cu")
		(net 294)
	)
	(segment
		(start 86.072 193.507)
		(end 86.415 193.85)
		(width 0.16)
		(layer "F.Cu")
		(net 294)
	)
	(segment
		(start 83.292999 193.507001)
		(end 86.072 193.507)
		(width 0.16)
		(layer "F.Cu")
		(net 294)
	)
	(segment
		(start 82.787 193.602)
		(end 83.198 193.602)
		(width 0.16)
		(layer "F.Cu")
		(net 294)
	)
	(segment
		(start 80.233 193.817)
		(end 80.542999 193.507001)
		(width 0.16)
		(layer "F.Cu")
		(net 294)
	)
	(segment
		(start 82.787 193.602)
		(end 82.015 193.602)
		(width 0.16)
		(layer "F.Cu")
		(net 294)
	)
	(segment
		(start 78.244501 193.817)
		(end 80.233 193.817)
		(width 0.16)
		(layer "F.Cu")
		(net 294)
	)
	(segment
		(start 81.602 193.602)
		(end 82.015 193.602)
		(width 0.16)
		(layer "F.Cu")
		(net 294)
	)
	(segment
		(start 80.19225 192.816)
		(end 80.573249 193.196999)
		(width 0.16)
		(layer "F.Cu")
		(net 295)
	)
	(segment
		(start 83.296999 193.196999)
		(end 86.068 193.197)
		(width 0.16)
		(layer "F.Cu")
		(net 295)
	)
	(segment
		(start 83.202 193.102)
		(end 83.296999 193.196999)
		(width 0.16)
		(layer "F.Cu")
		(net 295)
	)
	(segment
		(start 80.573249 193.196999)
		(end 81.496999 193.196999)
		(width 0.16)
		(layer "F.Cu")
		(net 295)
	)
	(segment
		(start 78.244501 192.816)
		(end 80.19225 192.816)
		(width 0.16)
		(layer "F.Cu")
		(net 295)
	)
	(segment
		(start 86.068 193.197)
		(end 86.415 192.85)
		(width 0.16)
		(layer "F.Cu")
		(net 295)
	)
	(segment
		(start 82.787 193.102)
		(end 83.202 193.102)
		(width 0.16)
		(layer "F.Cu")
		(net 295)
	)
	(segment
		(start 82.787 193.102)
		(end 82.015 193.102)
		(width 0.16)
		(layer "F.Cu")
		(net 295)
	)
	(segment
		(start 81.591998 193.102)
		(end 82.015 193.102)
		(width 0.16)
		(layer "F.Cu")
		(net 295)
	)
	(segment
		(start 81.496999 193.196999)
		(end 81.591998 193.102)
		(width 0.16)
		(layer "F.Cu")
		(net 295)
	)
	(segment
		(start 80.288751 192.317)
		(end 78.244501 192.317)
		(width 0.16)
		(layer "F.Cu")
		(net 296)
	)
	(segment
		(start 83.292 191.906)
		(end 83.198 192)
		(width 0.16)
		(layer "F.Cu")
		(net 296)
	)
	(segment
		(start 82.015 192)
		(end 81.602 192)
		(width 0.16)
		(layer "F.Cu")
		(net 296)
	)
	(segment
		(start 83.198 192)
		(end 82.787 192)
		(width 0.16)
		(layer "F.Cu")
		(net 296)
	)
	(segment
		(start 82.015 192)
		(end 82.787 192)
		(width 0.16)
		(layer "F.Cu")
		(net 296)
	)
	(segment
		(start 81.602 192)
		(end 81.552 191.95)
		(width 0.16)
		(layer "F.Cu")
		(net 296)
	)
	(segment
		(start 81.552 191.95)
		(end 80.655751 191.95)
		(width 0.16)
		(layer "F.Cu")
		(net 296)
	)
	(segment
		(start 83.819001 191.906001)
		(end 83.292 191.906)
		(width 0.16)
		(layer "F.Cu")
		(net 296)
	)
	(segment
		(start 84.165 192.252)
		(end 83.819001 191.906001)
		(width 0.16)
		(layer "F.Cu")
		(net 296)
	)
	(segment
		(start 80.655751 191.95)
		(end 80.288751 192.317)
		(width 0.16)
		(layer "F.Cu")
		(net 296)
	)
	(segment
		(start 181.640108 164.728)
		(end 181.404108 164.491999)
		(width 0.15)
		(layer "F.Cu")
		(net 297)
	)
	(segment
		(start 182.541 152.926)
		(end 182.541 153.441)
		(width 0.256)
		(layer "F.Cu")
		(net 297)
	)
	(segment
		(start 181.640107 183.45)
		(end 181.640107 182.940107)
		(width 0.177)
		(layer "F.Cu")
		(net 297)
	)
	(segment
		(start 205.0785 154.8025)
		(end 206.0795 154.8025)
		(width 0.256)
		(layer "F.Cu")
		(net 297)
	)
	(segment
		(start 181.640108 165.286)
		(end 181.640108 164.728)
		(width 0.15)
		(layer "F.Cu")
		(net 297)
	)
	(segment
		(start 181.640107 182.940107)
		(end 181.3 182.6)
		(width 0.177)
		(layer "F.Cu")
		(net 297)
	)
	(segment
		(start 182.541 153.441)
		(end 182.925 153.825)
		(width 0.256)
		(layer "F.Cu")
		(net 297)
	)
	(via
		(at 182.925 153.825)
		(size 0.45)
		(drill 0.1)
		(layers "F.Cu" "B.Cu")
		(net 297)
	)
	(via
		(at 181.404108 164.491999)
		(size 0.45)
		(drill 0.1)
		(layers "F.Cu" "B.Cu")
		(net 297)
	)
	(via
		(at 181.3 182.6)
		(size 0.45)
		(drill 0.1)
		(layers "F.Cu" "B.Cu")
		(net 297)
	)
	(via
		(at 206.0795 154.8025)
		(size 0.45)
		(drill 0.1)
		(layers "F.Cu" "B.Cu")
		(net 297)
	)
	(segment
		(start 178.54 165.08)
		(end 180.816107 165.08)
		(width 0.15)
		(layer "B.Cu")
		(net 297)
	)
	(segment
		(start 180.816107 165.08)
		(end 181.404108 164.491999)
		(width 0.15)
		(layer "B.Cu")
		(net 297)
	)
	(segment
		(start 177.74 165.88)
		(end 178.54 165.08)
		(width 0.15)
		(layer "B.Cu")
		(net 297)
	)
	(segment
		(start 181.404108 164.491999)
		(end 180.796107 165.1)
		(width 0.1)
		(layer "In2.Cu")
		(net 297)
	)
	(segment
		(start 180.7 182)
		(end 181.3 182.6)
		(width 0.1)
		(layer "In2.Cu")
		(net 297)
	)
	(segment
		(start 180.7 168.9)
		(end 180.7 182)
		(width 0.1)
		(layer "In2.Cu")
		(net 297)
	)
	(segment
		(start 180.796107 165.1)
		(end 179.919669 165.1)
		(width 0.1)
		(layer "In2.Cu")
		(net 297)
	)
	(segment
		(start 179.1 165.919669)
		(end 179.1 167.3)
		(width 0.1)
		(layer "In2.Cu")
		(net 297)
	)
	(segment
		(start 179.1 167.3)
		(end 180.7 168.9)
		(width 0.1)
		(layer "In2.Cu")
		(net 297)
	)
	(segment
		(start 179.919669 165.1)
		(end 179.1 165.919669)
		(width 0.1)
		(layer "In2.Cu")
		(net 297)
	)
	(segment
		(start 184.675 153.825)
		(end 196.125 153.825)
		(width 0.1)
		(layer "In4.Cu")
		(net 297)
	)
	(segment
		(start 205.0475 154.8025)
		(end 206.0795 154.8025)
		(width 0.1)
		(layer "In4.Cu")
		(net 297)
	)
	(segment
		(start 182.925 153.45)
		(end 183 153.375)
		(width 0.1)
		(layer "In4.Cu")
		(net 297)
	)
	(segment
		(start 182.925 153.375)
		(end 182.925 153.45)
		(width 0.1)
		(layer "In4.Cu")
		(net 297)
	)
	(segment
		(start 181.6 164.296107)
		(end 181.6 154.25)
		(width 0.1)
		(layer "In4.Cu")
		(net 297)
	)
	(segment
		(start 181.404108 164.491999)
		(end 181.6 164.296107)
		(width 0.1)
		(layer "In4.Cu")
		(net 297)
	)
	(segment
		(start 196.125 153.825)
		(end 197.6 155.3)
		(width 0.1)
		(layer "In4.Cu")
		(net 297)
	)
	(segment
		(start 182.925 153.45)
		(end 182.875 153.4)
		(width 0.1)
		(layer "In4.Cu")
		(net 297)
	)
	(segment
		(start 182.875 153.375)
		(end 182.925 153.375)
		(width 0.1)
		(layer "In4.Cu")
		(net 297)
	)
	(segment
		(start 182.875 153.4)
		(end 182.875 153.375)
		(width 0.1)
		(layer "In4.Cu")
		(net 297)
	)
	(segment
		(start 184.225 153.375)
		(end 184.675 153.825)
		(width 0.1)
		(layer "In4.Cu")
		(net 297)
	)
	(segment
		(start 182.475 153.375)
		(end 182.875 153.375)
		(width 0.1)
		(layer "In4.Cu")
		(net 297)
	)
	(segment
		(start 183.025 153.375)
		(end 184.225 153.375)
		(width 0.1)
		(layer "In4.Cu")
		(net 297)
	)
	(segment
		(start 183 153.375)
		(end 183.025 153.375)
		(width 0.1)
		(layer "In4.Cu")
		(net 297)
	)
	(segment
		(start 204.55 155.3)
		(end 205.0475 154.8025)
		(width 0.1)
		(layer "In4.Cu")
		(net 297)
	)
	(segment
		(start 181.6 154.25)
		(end 182.475 153.375)
		(width 0.1)
		(layer "In4.Cu")
		(net 297)
	)
	(segment
		(start 182.925 153.45)
		(end 182.925 153.825)
		(width 0.1)
		(layer "In4.Cu")
		(net 297)
	)
	(segment
		(start 182.925 153.375)
		(end 183.025 153.375)
		(width 0.1)
		(layer "In4.Cu")
		(net 297)
	)
	(segment
		(start 197.6 155.3)
		(end 204.55 155.3)
		(width 0.1)
		(layer "In4.Cu")
		(net 297)
	)
	(segment
		(start 180.664 184.164)
		(end 180.3 183.8)
		(width 0.177)
		(layer "F.Cu")
		(net 298)
	)
	(segment
		(start 205.0785 153.8015)
		(end 206.0795 153.8015)
		(width 0.256)
		(layer "F.Cu")
		(net 298)
	)
	(segment
		(start 183.191 152.926)
		(end 183.191 153.316)
		(width 0.256)
		(layer "F.Cu")
		(net 298)
	)
	(segment
		(start 180.926108 165.999999)
		(end 180.312108 166)
		(width 0.15)
		(layer "F.Cu")
		(net 298)
	)
	(segment
		(start 180.926107 184.164)
		(end 180.664 184.164)
		(width 0.177)
		(layer "F.Cu")
		(net 298)
	)
	(segment
		(start 183.191 153.316)
		(end 183.7 153.825)
		(width 0.256)
		(layer "F.Cu")
		(net 298)
	)
	(segment
		(start 180.312108 166)
		(end 180.004108 165.692)
		(width 0.15)
		(layer "F.Cu")
		(net 298)
	)
	(via
		(at 180.004108 165.692)
		(size 0.45)
		(drill 0.1)
		(layers "F.Cu" "B.Cu")
		(net 298)
	)
	(via
		(at 206.0795 153.8015)
		(size 0.45)
		(drill 0.1)
		(layers "F.Cu" "B.Cu")
		(net 298)
	)
	(via
		(at 180.3 183.8)
		(size 0.45)
		(drill 0.1)
		(layers "F.Cu" "B.Cu")
		(net 298)
	)
	(via
		(at 183.7 153.825)
		(size 0.45)
		(drill 0.1)
		(layers "F.Cu" "B.Cu")
		(net 298)
	)
	(segment
		(start 178.94 167.18)
		(end 177.74 168.38)
		(width 0.15)
		(layer "B.Cu")
		(net 298)
	)
	(segment
		(start 180.004108 165.692)
		(end 179.298 165.692)
		(width 0.15)
		(layer "B.Cu")
		(net 298)
	)
	(segment
		(start 179.298 165.692)
		(end 178.94 166.05)
		(width 0.15)
		(layer "B.Cu")
		(net 298)
	)
	(segment
		(start 178.94 166.05)
		(end 178.94 167.18)
		(width 0.15)
		(layer "B.Cu")
		(net 298)
	)
	(segment
		(start 181.7 183.8)
		(end 182.6 182.9)
		(width 0.1)
		(layer "In2.Cu")
		(net 298)
	)
	(segment
		(start 182.6 182)
		(end 181.1 180.5)
		(width 0.1)
		(layer "In2.Cu")
		(net 298)
	)
	(segment
		(start 182.6 182.9)
		(end 182.6 182)
		(width 0.1)
		(layer "In2.Cu")
		(net 298)
	)
	(segment
		(start 181.1 166.787892)
		(end 180.004108 165.692)
		(width 0.1)
		(layer "In2.Cu")
		(net 298)
	)
	(segment
		(start 181.1 180.5)
		(end 181.1 166.787892)
		(width 0.1)
		(layer "In2.Cu")
		(net 298)
	)
	(segment
		(start 180.3 183.8)
		(end 181.7 183.8)
		(width 0.1)
		(layer "In2.Cu")
		(net 298)
	)
	(segment
		(start 183.15 155.0875)
		(end 183.15 164.05)
		(width 0.1)
		(layer "In4.Cu")
		(net 298)
	)
	(segment
		(start 183.71875 154.51875)
		(end 183.15 155.0875)
		(width 0.1)
		(layer "In4.Cu")
		(net 298)
	)
	(segment
		(start 183.15 164.05)
		(end 181.155331 166.044669)
		(width 0.1)
		(layer "In4.Cu")
		(net 298)
	)
	(segment
		(start 183.7 154.525)
		(end 183.7125 154.525)
		(width 0.1)
		(layer "In4.Cu")
		(net 298)
	)
	(segment
		(start 195.7 154.45)
		(end 184.075 154.45)
		(width 0.1)
		(layer "In4.Cu")
		(net 298)
	)
	(segment
		(start 183.7 153.825)
		(end 183.7 154.3625)
		(width 0.1)
		(layer "In4.Cu")
		(net 298)
	)
	(segment
		(start 183.7 154.3625)
		(end 183.7 154.525)
		(width 0.1)
		(layer "In4.Cu")
		(net 298)
	)
	(segment
		(start 183.7 154.3625)
		(end 183.7875 154.45)
		(width 0.1)
		(layer "In4.Cu")
		(net 298)
	)
	(segment
		(start 206.0795 153.8015)
		(end 206.4545 154.1765)
		(width 0.1)
		(layer "In4.Cu")
		(net 298)
	)
	(segment
		(start 204.8 156.25)
		(end 197.5 156.25)
		(width 0.1)
		(layer "In4.Cu")
		(net 298)
	)
	(segment
		(start 206.4545 154.1765)
		(end 206.4545 155.1455)
		(width 0.1)
		(layer "In4.Cu")
		(net 298)
	)
	(segment
		(start 205.7 155.35)
		(end 204.8 156.25)
		(width 0.1)
		(layer "In4.Cu")
		(net 298)
	)
	(segment
		(start 180.356777 166.044669)
		(end 180.004108 165.692)
		(width 0.1)
		(layer "In4.Cu")
		(net 298)
	)
	(segment
		(start 181.155331 166.044669)
		(end 180.356777 166.044669)
		(width 0.1)
		(layer "In4.Cu")
		(net 298)
	)
	(segment
		(start 206.25 155.35)
		(end 205.7 155.35)
		(width 0.1)
		(layer "In4.Cu")
		(net 298)
	)
	(segment
		(start 183.7875 154.45)
		(end 183.71875 154.51875)
		(width 0.1)
		(layer "In4.Cu")
		(net 298)
	)
	(segment
		(start 183.7125 154.525)
		(end 183.71875 154.51875)
		(width 0.1)
		(layer "In4.Cu")
		(net 298)
	)
	(segment
		(start 197.5 156.25)
		(end 195.7 154.45)
		(width 0.1)
		(layer "In4.Cu")
		(net 298)
	)
	(segment
		(start 206.4545 155.1455)
		(end 206.25 155.35)
		(width 0.1)
		(layer "In4.Cu")
		(net 298)
	)
	(segment
		(start 184.075 154.45)
		(end 183.7875 154.45)
		(width 0.1)
		(layer "In4.Cu")
		(net 298)
	)
	(segment
		(start 104.500501 151.708851)
		(end 104.500501 150.173851)
		(width 0.15)
		(layer "F.Cu")
		(net 299)
	)
	(segment
		(start 100.400501 152.873851)
		(end 101.085501 152.873851)
		(width 0.15)
		(layer "F.Cu")
		(net 299)
	)
	(segment
		(start 101.085501 152.873851)
		(end 101.400501 152.558851)
		(width 0.15)
		(layer "F.Cu")
		(net 299)
	)
	(segment
		(start 103.650501 152.558851)
		(end 101.400501 152.558851)
		(width 0.15)
		(layer "F.Cu")
		(net 299)
	)
	(segment
		(start 103.650501 152.558851)
		(end 104.500501 151.708851)
		(width 0.15)
		(layer "F.Cu")
		(net 299)
	)
	(segment
		(start 99.699799 152.873851)
		(end 99.53765 153.036)
		(width 0.15)
		(layer "F.Cu")
		(net 299)
	)
	(segment
		(start 99.53765 153.036)
		(end 96.97765 153.036)
		(width 0.15)
		(layer "F.Cu")
		(net 299)
	)
	(segment
		(start 100.400501 152.873851)
		(end 99.699799 152.873851)
		(width 0.15)
		(layer "F.Cu")
		(net 299)
	)
	(segment
		(start 102.315501 154.958851)
		(end 102.315501 153.623851)
		(width 0.15)
		(layer "F.Cu")
		(net 300)
	)
	(segment
		(start 100.400501 153.843851)
		(end 101.635501 153.843851)
		(width 0.15)
		(layer "F.Cu")
		(net 300)
	)
	(segment
		(start 96.97765 153.536)
		(end 99.463352 153.536)
		(width 0.15)
		(layer "F.Cu")
		(net 300)
	)
	(segment
		(start 99.463352 153.536)
		(end 99.771203 153.843851)
		(width 0.15)
		(layer "F.Cu")
		(net 300)
	)
	(segment
		(start 99.771203 153.843851)
		(end 100.400501 153.843851)
		(width 0.15)
		(layer "F.Cu")
		(net 300)
	)
	(segment
		(start 99.756501 117.3)
		(end 99.850501 117.206)
		(width 0.15)
		(layer "F.Cu")
		(net 301)
	)
	(segment
		(start 97.849501 117.3)
		(end 99.756501 117.3)
		(width 0.15)
		(layer "F.Cu")
		(net 301)
	)
	(segment
		(start 96.852502 118.4255)
		(end 96.852501 117.299999)
		(width 0.15)
		(layer "F.Cu")
		(net 302)
	)
	(segment
		(start 98.230001 119.806)
		(end 96.851001 118.427)
		(width 0.15)
		(layer "F.Cu")
		(net 302)
	)
	(segment
		(start 99.850501 119.806)
		(end 98.230001 119.806)
		(width 0.15)
		(layer "F.Cu")
		(net 302)
	)
	(segment
		(start 96.851001 118.427)
		(end 96.852502 118.4255)
		(width 0.15)
		(layer "F.Cu")
		(net 302)
	)
	(segment
		(start 177.085501 197.291)
		(end 177.100501 197.291)
		(width 0.1)
		(layer "F.Cu")
		(net 303)
	)
	(segment
		(start 177.055502 196.214503)
		(end 177.055503 194.214502)
		(width 0.177)
		(layer "F.Cu")
		(net 303)
	)
	(segment
		(start 177.100501 196.217504)
		(end 177.103502 196.214503)
		(width 0.256)
		(layer "F.Cu")
		(net 303)
	)
	(segment
		(start 176.115501 198.261)
		(end 177.085501 197.291)
		(width 0.198)
		(layer "F.Cu")
		(net 303)
	)
	(segment
		(start 176.080501 198.261)
		(end 176.115501 198.261)
		(width 0.1)
		(layer "F.Cu")
		(net 303)
	)
	(segment
		(start 177.100501 197.291)
		(end 177.100501 196.217504)
		(width 0.256)
		(layer "F.Cu")
		(net 303)
	)
	(segment
		(start 89.872187 125)
		(end 89.866187 125.006)
		(width 0.15)
		(layer "F.Cu")
		(net 304)
	)
	(segment
		(start 97.650461 126.250461)
		(end 96.4 125)
		(width 0.15)
		(layer "F.Cu")
		(net 304)
	)
	(segment
		(start 97.700501 126.250461)
		(end 97.650461 126.250461)
		(width 0.15)
		(layer "F.Cu")
		(net 304)
	)
	(segment
		(start 90.934815 125.006)
		(end 90.928815 125)
		(width 0.15)
		(layer "F.Cu")
		(net 304)
	)
	(segment
		(start 79.894 125.006)
		(end 79.349 125.551)
		(width 0.15)
		(layer "F.Cu")
		(net 304)
	)
	(segment
		(start 89.866187 125.006)
		(end 79.894 125.006)
		(width 0.15)
		(layer "F.Cu")
		(net 304)
	)
	(segment
		(start 96.4 125)
		(end 96.394 125.006)
		(width 0.15)
		(layer "F.Cu")
		(net 304)
	)
	(segment
		(start 79.349 125.551)
		(end 79.349 126.299)
		(width 0.15)
		(layer "F.Cu")
		(net 304)
	)
	(segment
		(start 90.928815 125)
		(end 89.872187 125)
		(width 0.15)
		(layer "F.Cu")
		(net 304)
	)
	(segment
		(start 96.394 125.006)
		(end 90.934815 125.006)
		(width 0.15)
		(layer "F.Cu")
		(net 304)
	)
	(segment
		(start 77.934501 127.4)
		(end 81.7 127.4)
		(width 0.15)
		(layer "F.Cu")
		(net 305)
	)
	(segment
		(start 76.809501 126.275)
		(end 77.934501 127.4)
		(width 0.15)
		(layer "F.Cu")
		(net 305)
	)
	(segment
		(start 94.748501 125.791251)
		(end 94.748501 126.234)
		(width 0.15)
		(layer "F.Cu")
		(net 305)
	)
	(segment
		(start 83.8 125.3)
		(end 94.25725 125.3)
		(width 0.15)
		(layer "F.Cu")
		(net 305)
	)
	(segment
		(start 94.25725 125.3)
		(end 94.748501 125.791251)
		(width 0.15)
		(layer "F.Cu")
		(net 305)
	)
	(segment
		(start 81.7 127.4)
		(end 83.8 125.3)
		(width 0.15)
		(layer "F.Cu")
		(net 305)
	)
	(segment
		(start 82.2 127.9)
		(end 75.194 127.9)
		(width 0.15)
		(layer "F.Cu")
		(net 306)
	)
	(segment
		(start 74.249 126.955)
		(end 74.249 126.299)
		(width 0.15)
		(layer "F.Cu")
		(net 306)
	)
	(segment
		(start 91.748501 126.234)
		(end 91.114501 125.6)
		(width 0.15)
		(layer "F.Cu")
		(net 306)
	)
	(segment
		(start 91.114501 125.6)
		(end 84.5 125.6)
		(width 0.15)
		(layer "F.Cu")
		(net 306)
	)
	(segment
		(start 75.194 127.9)
		(end 74.249 126.955)
		(width 0.15)
		(layer "F.Cu")
		(net 306)
	)
	(segment
		(start 84.5 125.6)
		(end 82.2 127.9)
		(width 0.15)
		(layer "F.Cu")
		(net 306)
	)
	(segment
		(start 83.650501 119.441)
		(end 83.650501 117.176)
		(width 0.15)
		(layer "F.Cu")
		(net 307)
	)
	(segment
		(start 89.050501 119.441)
		(end 89.050501 117.176)
		(width 0.15)
		(layer "F.Cu")
		(net 308)
	)
	(segment
		(start 86.350501 119.441)
		(end 86.350501 117.176)
		(width 0.15)
		(layer "F.Cu")
		(net 309)
	)
	(segment
		(start 91.750501 119.441)
		(end 91.750501 117.176)
		(width 0.15)
		(layer "F.Cu")
		(net 310)
	)
	(segment
		(start 80.317 191.317)
		(end 80.64 191.64)
		(width 0.16)
		(layer "F.Cu")
		(net 311)
	)
	(segment
		(start 80.64 191.64)
		(end 81.530999 191.64)
		(width 0.16)
		(layer "F.Cu")
		(net 311)
	)
	(segment
		(start 81.530999 191.64)
		(end 81.670999 191.5)
		(width 0.16)
		(layer "F.Cu")
		(net 311)
	)
	(segment
		(start 83.819001 191.595999)
		(end 83.298 191.596)
		(width 0.16)
		(layer "F.Cu")
		(net 311)
	)
	(segment
		(start 83.298 191.596)
		(end 83.202 191.5)
		(width 0.16)
		(layer "F.Cu")
		(net 311)
	)
	(segment
		(start 78.244501 191.317)
		(end 80.317 191.317)
		(width 0.16)
		(layer "F.Cu")
		(net 311)
	)
	(segment
		(start 84.165 191.25)
		(end 83.819001 191.595999)
		(width 0.16)
		(layer "F.Cu")
		(net 311)
	)
	(segment
		(start 83.202 191.5)
		(end 82.787 191.5)
		(width 0.16)
		(layer "F.Cu")
		(net 311)
	)
	(segment
		(start 81.670999 191.5)
		(end 82.015 191.5)
		(width 0.16)
		(layer "F.Cu")
		(net 311)
	)
	(segment
		(start 82.787 191.5)
		(end 82.015 191.5)
		(width 0.16)
		(layer "F.Cu")
		(net 311)
	)
	(segment
		(start 97.160501 114.47)
		(end 96.852501 114.778)
		(width 0.15)
		(layer "F.Cu")
		(net 312)
	)
	(segment
		(start 99.850501 114.541)
		(end 99.779501 114.47)
		(width 0.15)
		(layer "F.Cu")
		(net 312)
	)
	(segment
		(start 96.852501 114.778)
		(end 96.852501 115.552)
		(width 0.15)
		(layer "F.Cu")
		(net 312)
	)
	(segment
		(start 99.779501 114.47)
		(end 97.160501 114.47)
		(width 0.15)
		(layer "F.Cu")
		(net 312)
	)
	(segment
		(start 107.900001 146.2025)
		(end 107.900001 147.2775)
		(width 0.201)
		(layer "F.Cu")
		(net 313)
	)
	(via
		(at 107.900001 147.2775)
		(size 0.45)
		(drill 0.1)
		(layers "F.Cu" "B.Cu")
		(net 313)
	)
	(segment
		(start 106.65 141.45)
		(end 107.2 140.9)
		(width 0.15)
		(layer "B.Cu")
		(net 313)
	)
	(segment
		(start 135.550001 138.449999)
		(end 135.550001 137.149999)
		(width 0.15)
		(layer "B.Cu")
		(net 313)
	)
	(segment
		(start 135.550001 137.149999)
		(end 135.9 136.8)
		(width 0.15)
		(layer "B.Cu")
		(net 313)
	)
	(segment
		(start 145.7 139.2)
		(end 145.7 140.6)
		(width 0.15)
		(layer "B.Cu")
		(net 313)
	)
	(segment
		(start 145.15 138.65)
		(end 145.7 139.2)
		(width 0.15)
		(layer "B.Cu")
		(net 313)
	)
	(segment
		(start 133.05 139.4)
		(end 133.5 138.95)
		(width 0.15)
		(layer "B.Cu")
		(net 313)
	)
	(segment
		(start 111.2 142.5)
		(end 129.6 142.5)
		(width 0.15)
		(layer "B.Cu")
		(net 313)
	)
	(segment
		(start 131.025 141.075)
		(end 129.6 142.5)
		(width 0.15)
		(layer "B.Cu")
		(net 313)
	)
	(segment
		(start 135.9 136.8)
		(end 144.9 136.8)
		(width 0.15)
		(layer "B.Cu")
		(net 313)
	)
	(segment
		(start 133.05 140.7)
		(end 133.05 139.4)
		(width 0.15)
		(layer "B.Cu")
		(net 313)
	)
	(segment
		(start 109.6 140.9)
		(end 111.2 142.5)
		(width 0.15)
		(layer "B.Cu")
		(net 313)
	)
	(segment
		(start 132.675 141.075)
		(end 133.05 140.7)
		(width 0.15)
		(layer "B.Cu")
		(net 313)
	)
	(segment
		(start 133.5 138.95)
		(end 135.05 138.95)
		(width 0.15)
		(layer "B.Cu")
		(net 313)
	)
	(segment
		(start 146.05 140.95)
		(end 146.05 141.915)
		(width 0.15)
		(layer "B.Cu")
		(net 313)
	)
	(segment
		(start 106.65 146.027499)
		(end 106.65 141.45)
		(width 0.15)
		(layer "B.Cu")
		(net 313)
	)
	(segment
		(start 132.675 141.075)
		(end 131.025 141.075)
		(width 0.15)
		(layer "B.Cu")
		(net 313)
	)
	(segment
		(start 135.05 138.95)
		(end 135.550001 138.449999)
		(width 0.15)
		(layer "B.Cu")
		(net 313)
	)
	(segment
		(start 145.15 137.05)
		(end 145.15 138.65)
		(width 0.15)
		(layer "B.Cu")
		(net 313)
	)
	(segment
		(start 144.9 136.8)
		(end 145.15 137.05)
		(width 0.15)
		(layer "B.Cu")
		(net 313)
	)
	(segment
		(start 107.900001 147.2775)
		(end 106.65 146.027499)
		(width 0.15)
		(layer "B.Cu")
		(net 313)
	)
	(segment
		(start 107.2 140.9)
		(end 109.6 140.9)
		(width 0.15)
		(layer "B.Cu")
		(net 313)
	)
	(segment
		(start 145.7 140.6)
		(end 146.05 140.95)
		(width 0.15)
		(layer "B.Cu")
		(net 313)
	)
	(segment
		(start 108.150001 138.8025)
		(end 108.150001 139.8775)
		(width 0.201)
		(layer "F.Cu")
		(net 314)
	)
	(via
		(at 108.150001 139.8775)
		(size 0.45)
		(drill 0.1)
		(layers "F.Cu" "B.Cu")
		(net 314)
	)
	(segment
		(start 148.15 137.993186)
		(end 148.55 138.393186)
		(width 0.15)
		(layer "B.Cu")
		(net 314)
	)
	(segment
		(start 148.15 137.15)
		(end 148.15 137.993186)
		(width 0.15)
		(layer "B.Cu")
		(net 314)
	)
	(segment
		(start 128.75 141.45)
		(end 129.671593 140.528407)
		(width 0.15)
		(layer "B.Cu")
		(net 314)
	)
	(segment
		(start 108.150001 139.8775)
		(end 108.722501 140.45)
		(width 0.15)
		(layer "B.Cu")
		(net 314)
	)
	(segment
		(start 129.671593 140.528407)
		(end 129.671593 139.228407)
		(width 0.15)
		(layer "B.Cu")
		(net 314)
	)
	(segment
		(start 130.8 138.75)
		(end 131.35 138.2)
		(width 0.15)
		(layer "B.Cu")
		(net 314)
	)
	(segment
		(start 132.45 136.2)
		(end 147.2 136.2)
		(width 0.15)
		(layer "B.Cu")
		(net 314)
	)
	(segment
		(start 130.15 138.75)
		(end 130.8 138.75)
		(width 0.15)
		(layer "B.Cu")
		(net 314)
	)
	(segment
		(start 147.2 136.2)
		(end 148.15 137.15)
		(width 0.15)
		(layer "B.Cu")
		(net 314)
	)
	(segment
		(start 129.671593 139.228407)
		(end 130.15 138.75)
		(width 0.15)
		(layer "B.Cu")
		(net 314)
	)
	(segment
		(start 111.2 141.45)
		(end 128.75 141.45)
		(width 0.15)
		(layer "B.Cu")
		(net 314)
	)
	(segment
		(start 131.35 138.2)
		(end 131.35 137.3)
		(width 0.15)
		(layer "B.Cu")
		(net 314)
	)
	(segment
		(start 110.2 140.45)
		(end 111.2 141.45)
		(width 0.15)
		(layer "B.Cu")
		(net 314)
	)
	(segment
		(start 108.722501 140.45)
		(end 110.2 140.45)
		(width 0.15)
		(layer "B.Cu")
		(net 314)
	)
	(segment
		(start 148.55 138.393186)
		(end 148.55 141.915)
		(width 0.15)
		(layer "B.Cu")
		(net 314)
	)
	(segment
		(start 131.35 137.3)
		(end 132.45 136.2)
		(width 0.15)
		(layer "B.Cu")
		(net 314)
	)
	(segment
		(start 92.7 196.349)
		(end 92.7 195.3)
		(width 0.201)
		(layer "F.Cu")
		(net 315)
	)
	(segment
		(start 94.3 196.348)
		(end 94.301 196.349)
		(width 0.201)
		(layer "F.Cu")
		(net 316)
	)
	(segment
		(start 94.3 195.3)
		(end 94.3 196.348)
		(width 0.201)
		(layer "F.Cu")
		(net 316)
	)
	(segment
		(start 96.3 195.315)
		(end 96.3 196.348)
		(width 0.201)
		(layer "F.Cu")
		(net 317)
	)
	(segment
		(start 96.3 196.348)
		(end 96.301 196.349)
		(width 0.201)
		(layer "F.Cu")
		(net 317)
	)
	(segment
		(start 97.9 196.348)
		(end 97.901 196.349)
		(width 0.201)
		(layer "F.Cu")
		(net 318)
	)
	(segment
		(start 97.9 195.3)
		(end 97.9 196.348)
		(width 0.201)
		(layer "F.Cu")
		(net 318)
	)
	(segment
		(start 76.349 154.066)
		(end 75.200501 154.066)
		(width 0.201)
		(layer "F.Cu")
		(net 321)
	)
	(segment
		(start 76.349 154.066)
		(end 77.215 153.2)
		(width 0.201)
		(layer "F.Cu")
		(net 321)
	)
	(segment
		(start 76.78 157.065)
		(end 77.215 157.5)
		(width 0.201)
		(layer "F.Cu")
		(net 323)
	)
	(segment
		(start 76.78 157.065)
		(end 75.200501 157.065)
		(width 0.201)
		(layer "F.Cu")
		(net 323)
	)
	(segment
		(start 81.71 188.9)
		(end 82.41 188.2)
		(width 0.2)
		(layer "F.Cu")
		(net 325)
	)
	(segment
		(start 82.41 188.2)
		(end 84.3 188.2)
		(width 0.2)
		(layer "F.Cu")
		(net 325)
	)
	(segment
		(start 79.7605 189.3195)
		(end 80.18 188.9)
		(width 0.2)
		(layer "F.Cu")
		(net 325)
	)
	(segment
		(start 78.250501 189.3195)
		(end 79.7605 189.3195)
		(width 0.2)
		(layer "F.Cu")
		(net 325)
	)
	(segment
		(start 80.18 188.9)
		(end 81.71 188.9)
		(width 0.2)
		(layer "F.Cu")
		(net 325)
	)
	(segment
		(start 81.2805 188.3195)
		(end 82.3 187.3)
		(width 0.2)
		(layer "F.Cu")
		(net 327)
	)
	(segment
		(start 78.250501 188.3195)
		(end 81.2805 188.3195)
		(width 0.2)
		(layer "F.Cu")
		(net 327)
	)
	(segment
		(start 82.3 187.3)
		(end 83 187.3)
		(width 0.2)
		(layer "F.Cu")
		(net 327)
	)
	(segment
		(start 82.591159 186.108841)
		(end 84.291159 186.108841)
		(width 0.2)
		(layer "F.Cu")
		(net 328)
	)
	(segment
		(start 78.250501 187.8195)
		(end 80.8805 187.8195)
		(width 0.2)
		(layer "F.Cu")
		(net 328)
	)
	(segment
		(start 80.8805 187.8195)
		(end 82.591159 186.108841)
		(width 0.2)
		(layer "F.Cu")
		(net 328)
	)
	(segment
		(start 84.291159 186.108841)
		(end 84.3 186.1)
		(width 0.2)
		(layer "F.Cu")
		(net 328)
	)
	(segment
		(start 78.250501 186.3195)
		(end 80.523375 186.3195)
		(width 0.2)
		(layer "F.Cu")
		(net 329)
	)
	(segment
		(start 80.523375 186.3195)
		(end 82.642875 184.2)
		(width 0.2)
		(layer "F.Cu")
		(net 329)
	)
	(segment
		(start 82.642875 184.2)
		(end 84.3 184.2)
		(width 0.2)
		(layer "F.Cu")
		(net 329)
	)
	(segment
		(start 82.029501 165.866)
		(end 84.110501 165.866)
		(width 0.2)
		(layer "F.Cu")
		(net 330)
	)
	(segment
		(start 158.224 177.476)
		(end 157.650501 177.476)
		(width 0.4)
		(layer "F.Cu")
		(net 332)
	)
	(segment
		(start 159.3995 174.4265)
		(end 159.3995 175.578001)
		(width 0.4)
		(layer "F.Cu")
		(net 332)
	)
	(segment
		(start 159.3995 175.578001)
		(end 159.001501 175.976)
		(width 0.4)
		(layer "F.Cu")
		(net 332)
	)
	(segment
		(start 159.001501 175.976)
		(end 159.001501 176.698499)
		(width 0.4)
		(layer "F.Cu")
		(net 332)
	)
	(segment
		(start 159.001501 176.698499)
		(end 158.224 177.476)
		(width 0.4)
		(layer "F.Cu")
		(net 332)
	)
	(via
		(at 159.001501 175.976)
		(size 0.45)
		(drill 0.1)
		(layers "F.Cu" "B.Cu")
		(net 332)
	)
	(segment
		(start 159.001501 175.292)
		(end 158.985501 175.276)
		(width 0.4)
		(layer "B.Cu")
		(net 332)
	)
	(segment
		(start 159.001501 175.976)
		(end 159.001501 175.292)
		(width 0.4)
		(layer "B.Cu")
		(net 332)
	)
	(segment
		(start 121.525501 206.774499)
		(end 122 206.3)
		(width 0.256)
		(layer "F.Cu")
		(net 337)
	)
	(segment
		(start 121.525501 210.801)
		(end 121.525501 206.774499)
		(width 0.256)
		(layer "F.Cu")
		(net 337)
	)
	(via
		(at 122 206.3)
		(size 0.45)
		(drill 0.1)
		(layers "F.Cu" "B.Cu")
		(net 337)
	)
	(segment
		(start 123.25 207.8)
		(end 122.551002 207.8)
		(width 0.256)
		(layer "B.Cu")
		(net 337)
	)
	(segment
		(start 122.525501 210.801)
		(end 122.525501 207.774499)
		(width 0.256)
		(layer "B.Cu")
		(net 337)
	)
	(segment
		(start 122.551002 207.8)
		(end 122.525501 207.774499)
		(width 0.256)
		(layer "B.Cu")
		(net 337)
	)
	(segment
		(start 122.525501 207.774499)
		(end 122.525501 206.825501)
		(width 0.256)
		(layer "B.Cu")
		(net 337)
	)
	(segment
		(start 122.525501 206.825501)
		(end 122 206.3)
		(width 0.256)
		(layer "B.Cu")
		(net 337)
	)
	(segment
		(start 123.525501 208.075501)
		(end 123.25 207.8)
		(width 0.256)
		(layer "B.Cu")
		(net 337)
	)
	(segment
		(start 123.525501 210.801)
		(end 123.525501 208.075501)
		(width 0.256)
		(layer "B.Cu")
		(net 337)
	)
	(segment
		(start 97.700501 127.220461)
		(end 97.700501 128.185461)
		(width 0.15)
		(layer "F.Cu")
		(net 347)
	)
	(segment
		(start 83.292999 190.407001)
		(end 86.010876 190.407)
		(width 0.16)
		(layer "F.Cu")
		(net 348)
	)
	(segment
		(start 82.787 190.502)
		(end 83.198 190.502)
		(width 0.16)
		(layer "F.Cu")
		(net 348)
	)
	(segment
		(start 82.787 190.502)
		(end 82.015 190.502)
		(width 0.16)
		(layer "F.Cu")
		(net 348)
	)
	(segment
		(start 83.198 190.502)
		(end 83.292999 190.407001)
		(width 0.16)
		(layer "F.Cu")
		(net 348)
	)
	(segment
		(start 80.052258 190.817)
		(end 80.462258 190.407)
		(width 0.16)
		(layer "F.Cu")
		(net 348)
	)
	(segment
		(start 78.244501 190.817)
		(end 80.052258 190.817)
		(width 0.16)
		(layer "F.Cu")
		(net 348)
	)
	(segment
		(start 86.010876 190.407)
		(end 86.382877 190.779001)
		(width 0.16)
		(layer "F.Cu")
		(net 348)
	)
	(segment
		(start 82.015 190.502)
		(end 81.602 190.502)
		(width 0.16)
		(layer "F.Cu")
		(net 348)
	)
	(segment
		(start 81.602 190.502)
		(end 81.507001 190.407001)
		(width 0.16)
		(layer "F.Cu")
		(net 348)
	)
	(segment
		(start 80.462258 190.407)
		(end 81.507001 190.407001)
		(width 0.16)
		(layer "F.Cu")
		(net 348)
	)
	(segment
		(start 82.787 190.002)
		(end 83.202 190.002)
		(width 0.16)
		(layer "F.Cu")
		(net 349)
	)
	(segment
		(start 81.496999 190.096999)
		(end 80.423071 190.097)
		(width 0.16)
		(layer "F.Cu")
		(net 349)
	)
	(segment
		(start 83.202 190.002)
		(end 83.296999 190.096999)
		(width 0.16)
		(layer "F.Cu")
		(net 349)
	)
	(segment
		(start 81.591998 190.002)
		(end 81.496999 190.096999)
		(width 0.16)
		(layer "F.Cu")
		(net 349)
	)
	(segment
		(start 83.296999 190.096999)
		(end 86.064878 190.097)
		(width 0.16)
		(layer "F.Cu")
		(net 349)
	)
	(segment
		(start 80.142071 189.816)
		(end 78.244501 189.816)
		(width 0.16)
		(layer "F.Cu")
		(net 349)
	)
	(segment
		(start 80.423071 190.097)
		(end 80.142071 189.816)
		(width 0.16)
		(layer "F.Cu")
		(net 349)
	)
	(segment
		(start 82.787 190.002)
		(end 82.015 190.002)
		(width 0.16)
		(layer "F.Cu")
		(net 349)
	)
	(segment
		(start 86.064878 190.097)
		(end 86.382877 189.779001)
		(width 0.16)
		(layer "F.Cu")
		(net 349)
	)
	(segment
		(start 82.015 190.002)
		(end 81.591998 190.002)
		(width 0.16)
		(layer "F.Cu")
		(net 349)
	)
	(segment
		(start 84.413 173.948)
		(end 83.952 173.948)
		(width 0.256)
		(layer "F.Cu")
		(net 350)
	)
	(segment
		(start 85.185 173.948)
		(end 84.413 173.948)
		(width 0.256)
		(layer "F.Cu")
		(net 350)
	)
	(segment
		(start 143.375501 185.301)
		(end 143.875001 185.8005)
		(width 0.256)
		(layer "F.Cu")
		(net 350)
	)
	(segment
		(start 83.952 173.948)
		(end 83.235 174.665)
		(width 0.256)
		(layer "F.Cu")
		(net 350)
	)
	(segment
		(start 85.185 173.948)
		(end 85.498 173.948)
		(width 0.256)
		(layer "F.Cu")
		(net 350)
	)
	(segment
		(start 83.235 174.665)
		(end 82.039501 174.665)
		(width 0.256)
		(layer "F.Cu")
		(net 350)
	)
	(segment
		(start 85.498 173.948)
		(end 86 174.45)
		(width 0.256)
		(layer "F.Cu")
		(net 350)
	)
	(via
		(at 143.875001 185.8005)
		(size 0.45)
		(drill 0.1)
		(layers "F.Cu" "B.Cu")
		(net 350)
	)
	(via
		(at 86 174.45)
		(size 0.45)
		(drill 0.1)
		(layers "F.Cu" "B.Cu")
		(net 350)
	)
	(segment
		(start 85.235 174.4)
		(end 85.285 174.45)
		(width 0.256)
		(layer "B.Cu")
		(net 350)
	)
	(segment
		(start 85.285 174.45)
		(end 86 174.45)
		(width 0.256)
		(layer "B.Cu")
		(net 350)
	)
	(segment
		(start 88.1 188.7)
		(end 116.75 188.7)
		(width 0.1)
		(layer "In6.Cu")
		(net 350)
	)
	(segment
		(start 132.7 186.3)
		(end 143.378001 186.3)
		(width 0.1)
		(layer "In6.Cu")
		(net 350)
	)
	(segment
		(start 143.378001 186.3)
		(end 143.877501 185.8005)
		(width 0.1)
		(layer "In6.Cu")
		(net 350)
	)
	(segment
		(start 86 175.2)
		(end 85.4 175.8)
		(width 0.1)
		(layer "In6.Cu")
		(net 350)
	)
	(segment
		(start 132.4 187.95)
		(end 132.4 186.6)
		(width 0.1)
		(layer "In6.Cu")
		(net 350)
	)
	(segment
		(start 116.75 188.7)
		(end 117.2 188.25)
		(width 0.1)
		(layer "In6.Cu")
		(net 350)
	)
	(segment
		(start 85.4 186)
		(end 88.1 188.7)
		(width 0.1)
		(layer "In6.Cu")
		(net 350)
	)
	(segment
		(start 132.1 188.25)
		(end 132.4 187.95)
		(width 0.1)
		(layer "In6.Cu")
		(net 350)
	)
	(segment
		(start 117.2 188.25)
		(end 132.1 188.25)
		(width 0.1)
		(layer "In6.Cu")
		(net 350)
	)
	(segment
		(start 85.4 175.8)
		(end 85.4 186)
		(width 0.1)
		(layer "In6.Cu")
		(net 350)
	)
	(segment
		(start 86 174.45)
		(end 86 175.2)
		(width 0.1)
		(layer "In6.Cu")
		(net 350)
	)
	(segment
		(start 132.4 186.6)
		(end 132.7 186.3)
		(width 0.1)
		(layer "In6.Cu")
		(net 350)
	)
	(segment
		(start 94.750501 127.206)
		(end 94.748501 127.204)
		(width 0.15)
		(layer "F.Cu")
		(net 351)
	)
	(segment
		(start 94.750501 128.299)
		(end 94.750501 127.206)
		(width 0.15)
		(layer "F.Cu")
		(net 351)
	)
	(segment
		(start 91.750501 128.299)
		(end 91.750501 127.206)
		(width 0.15)
		(layer "F.Cu")
		(net 352)
	)
	(segment
		(start 91.750501 127.206)
		(end 91.748501 127.204)
		(width 0.15)
		(layer "F.Cu")
		(net 352)
	)
	(segment
		(start 83.650501 121.976)
		(end 83.650501 120.411)
		(width 0.15)
		(layer "F.Cu")
		(net 353)
	)
	(segment
		(start 89.050501 121.976)
		(end 89.050501 120.411)
		(width 0.15)
		(layer "F.Cu")
		(net 354)
	)
	(segment
		(start 86.350501 121.976)
		(end 86.350501 120.411)
		(width 0.15)
		(layer "F.Cu")
		(net 355)
	)
	(segment
		(start 91.750501 121.976)
		(end 91.750501 120.411)
		(width 0.15)
		(layer "F.Cu")
		(net 356)
	)
	(segment
		(start 94.450501 121.976)
		(end 94.450501 120.411)
		(width 0.15)
		(layer "F.Cu")
		(net 357)
	)
	(segment
		(start 101.150501 115.476)
		(end 99.885501 115.476)
		(width 0.15)
		(layer "F.Cu")
		(net 358)
	)
	(segment
		(start 99.885501 115.476)
		(end 99.850501 115.511)
		(width 0.15)
		(layer "F.Cu")
		(net 358)
	)
	(segment
		(start 99.950501 120.876)
		(end 101.150501 120.876)
		(width 0.15)
		(layer "F.Cu")
		(net 359)
	)
	(segment
		(start 99.850501 120.776)
		(end 99.950501 120.876)
		(width 0.15)
		(layer "F.Cu")
		(net 359)
	)
	(segment
		(start 112.95 183.280501)
		(end 112.95 184.25)
		(width 0.256)
		(layer "F.Cu")
		(net 360)
	)
	(segment
		(start 112.95 184.25)
		(end 114.15 185.45)
		(width 0.256)
		(layer "F.Cu")
		(net 360)
	)
	(segment
		(start 115.2 185.45)
		(end 115.45 185.7)
		(width 0.256)
		(layer "F.Cu")
		(net 360)
	)
	(segment
		(start 113.650501 182.58)
		(end 112.95 183.280501)
		(width 0.256)
		(layer "F.Cu")
		(net 360)
	)
	(segment
		(start 114.6505 182.5655)
		(end 113.665001 182.5655)
		(width 0.256)
		(layer "F.Cu")
		(net 360)
	)
	(segment
		(start 113.665001 182.5655)
		(end 113.650501 182.58)
		(width 0.256)
		(layer "F.Cu")
		(net 360)
	)
	(segment
		(start 114.15 185.45)
		(end 115.2 185.45)
		(width 0.256)
		(layer "F.Cu")
		(net 360)
	)
	(segment
		(start 115.45 185.7)
		(end 115.45 186.115)
		(width 0.256)
		(layer "F.Cu")
		(net 360)
	)
	(via
		(at 113.650501 182.58)
		(size 0.45)
		(drill 0.1)
		(layers "F.Cu" "B.Cu")
		(net 360)
	)
	(segment
		(start 114.315501 182.6)
		(end 113.670501 182.6)
		(width 0.256)
		(layer "B.Cu")
		(net 360)
	)
	(segment
		(start 113.670501 182.6)
		(end 113.650501 182.58)
		(width 0.256)
		(layer "B.Cu")
		(net 360)
	)
	(segment
		(start 124.8 185.35)
		(end 124.8 182.401501)
		(width 0.256)
		(layer "F.Cu")
		(net 361)
	)
	(segment
		(start 122.649501 181.265501)
		(end 123.635 181.265501)
		(width 0.256)
		(layer "F.Cu")
		(net 361)
	)
	(segment
		(start 124.8 182.401501)
		(end 123.6495 181.251001)
		(width 0.256)
		(layer "F.Cu")
		(net 361)
	)
	(segment
		(start 124.035 186.115)
		(end 124.8 185.35)
		(width 0.256)
		(layer "F.Cu")
		(net 361)
	)
	(segment
		(start 123.635 181.265501)
		(end 123.6495 181.251001)
		(width 0.256)
		(layer "F.Cu")
		(net 361)
	)
	(segment
		(start 122.85 186.115)
		(end 124.035 186.115)
		(width 0.256)
		(layer "F.Cu")
		(net 361)
	)
	(via
		(at 123.6495 181.251001)
		(size 0.45)
		(drill 0.1)
		(layers "F.Cu" "B.Cu")
		(net 361)
	)
	(segment
		(start 123.635001 181.265499)
		(end 123.6495 181.251001)
		(width 0.256)
		(layer "B.Cu")
		(net 361)
	)
	(segment
		(start 123.635001 182)
		(end 123.635001 181.265499)
		(width 0.256)
		(layer "B.Cu")
		(net 361)
	)
	(segment
		(start 113.615 186.115)
		(end 112.25 184.75)
		(width 0.256)
		(layer "F.Cu")
		(net 362)
	)
	(segment
		(start 112.25 184.75)
		(end 112.25 181.348999)
		(width 0.256)
		(layer "F.Cu")
		(net 362)
	)
	(segment
		(start 113.5745 180.024499)
		(end 114.6505 180.0245)
		(width 0.256)
		(layer "F.Cu")
		(net 362)
	)
	(segment
		(start 114.4 186.115)
		(end 113.615 186.115)
		(width 0.256)
		(layer "F.Cu")
		(net 362)
	)
	(segment
		(start 112.25 181.348999)
		(end 113.5745 180.024499)
		(width 0.256)
		(layer "F.Cu")
		(net 362)
	)
	(segment
		(start 122 185.4)
		(end 123.8 185.4)
		(width 0.256)
		(layer "F.Cu")
		(net 363)
	)
	(segment
		(start 121.799499 185.600501)
		(end 122 185.4)
		(width 0.256)
		(layer "F.Cu")
		(net 363)
	)
	(segment
		(start 124.3 183)
		(end 123.8355 182.5355)
		(width 0.256)
		(layer "F.Cu")
		(net 363)
	)
	(segment
		(start 123.8 185.4)
		(end 124.3 184.9)
		(width 0.256)
		(layer "F.Cu")
		(net 363)
	)
	(segment
		(start 124.3 184.9)
		(end 124.3 183)
		(width 0.256)
		(layer "F.Cu")
		(net 363)
	)
	(segment
		(start 121.799499 186.115)
		(end 121.799499 185.600501)
		(width 0.256)
		(layer "F.Cu")
		(net 363)
	)
	(segment
		(start 123.8355 182.5355)
		(end 122.6495 182.5355)
		(width 0.256)
		(layer "F.Cu")
		(net 363)
	)
	(segment
		(start 99.850501 118.176)
		(end 101.150501 118.176)
		(width 0.15)
		(layer "F.Cu")
		(net 364)
	)
	(segment
		(start 188.858501 134.058501)
		(end 188.858501 134.559)
		(width 0.15)
		(layer "F.Cu")
		(net 365)
	)
	(segment
		(start 184.394759 134.155241)
		(end 184.95 133.6)
		(width 0.15)
		(layer "F.Cu")
		(net 365)
	)
	(segment
		(start 184.394759 134.4211)
		(end 184.394759 134.155241)
		(width 0.15)
		(layer "F.Cu")
		(net 365)
	)
	(segment
		(start 188.525 133.725)
		(end 188.858501 134.058501)
		(width 0.15)
		(layer "F.Cu")
		(net 365)
	)
	(segment
		(start 186.2 133.6)
		(end 186.325 133.725)
		(width 0.15)
		(layer "F.Cu")
		(net 365)
	)
	(segment
		(start 186.325 133.725)
		(end 188.525 133.725)
		(width 0.15)
		(layer "F.Cu")
		(net 365)
	)
	(segment
		(start 184.95 133.6)
		(end 186.2 133.6)
		(width 0.15)
		(layer "F.Cu")
		(net 365)
	)
	(segment
		(start 117.91 201.86)
		(end 119.96 201.86)
		(width 0.201)
		(layer "F.Cu")
		(net 366)
	)
	(segment
		(start 117.682 201.034)
		(end 117.682 201.632)
		(width 0.201)
		(layer "F.Cu")
		(net 366)
	)
	(segment
		(start 121.6 202.3)
		(end 122.097 201.803)
		(width 0.201)
		(layer "F.Cu")
		(net 366)
	)
	(segment
		(start 122.097 201.803)
		(end 122.097 201.486)
		(width 0.201)
		(layer "F.Cu")
		(net 366)
	)
	(segment
		(start 120.4 202.3)
		(end 121.6 202.3)
		(width 0.201)
		(layer "F.Cu")
		(net 366)
	)
	(segment
		(start 117.682 201.632)
		(end 117.91 201.86)
		(width 0.201)
		(layer "F.Cu")
		(net 366)
	)
	(segment
		(start 119.96 201.86)
		(end 120.4 202.3)
		(width 0.201)
		(layer "F.Cu")
		(net 366)
	)
	(segment
		(start 194.25 142.925)
		(end 193.7 142.375)
		(width 0.15)
		(layer "F.Cu")
		(net 367)
	)
	(segment
		(start 197.1475 143.7725)
		(end 196.3 142.925)
		(width 0.15)
		(layer "F.Cu")
		(net 367)
	)
	(segment
		(start 196.3 142.925)
		(end 194.25 142.925)
		(width 0.15)
		(layer "F.Cu")
		(net 367)
	)
	(segment
		(start 193.7 142.375)
		(end 193.7 141.7)
		(width 0.15)
		(layer "F.Cu")
		(net 367)
	)
	(segment
		(start 194.4875 141.7375)
		(end 194.45 141.7)
		(width 0.15)
		(layer "F.Cu")
		(net 367)
	)
	(segment
		(start 194.45 141.7)
		(end 193.7 141.7)
		(width 0.15)
		(layer "F.Cu")
		(net 367)
	)
	(segment
		(start 197.5495 143.7725)
		(end 197.1475 143.7725)
		(width 0.15)
		(layer "F.Cu")
		(net 367)
	)
	(via
		(at 194.4875 141.7375)
		(size 0.45)
		(drill 0.1)
		(layers "F.Cu" "B.Cu")
		(net 367)
	)
	(segment
		(start 195.05 142.3)
		(end 196.09 142.3)
		(width 0.256)
		(layer "B.Cu")
		(net 367)
	)
	(segment
		(start 194.4875 141.7375)
		(end 195.05 142.3)
		(width 0.256)
		(layer "B.Cu")
		(net 367)
	)
	(segment
		(start 195.5515 143.7725)
		(end 194.2225 143.7725)
		(width 0.15)
		(layer "F.Cu")
		(net 368)
	)
	(segment
		(start 191.514 143.835)
		(end 190.859 143.835)
		(width 0.201)
		(layer "F.Cu")
		(net 368)
	)
	(segment
		(start 190.859 143.835)
		(end 190.844 143.85)
		(width 0.201)
		(layer "F.Cu")
		(net 368)
	)
	(segment
		(start 191.514 143.835)
		(end 191.599 143.75)
		(width 0.201)
		(layer "F.Cu")
		(net 368)
	)
	(segment
		(start 194.2225 143.7725)
		(end 193.5 143.05)
		(width 0.15)
		(layer "F.Cu")
		(net 368)
	)
	(segment
		(start 192.349 143.05)
		(end 191.599 143.8)
		(width 0.15)
		(layer "F.Cu")
		(net 368)
	)
	(segment
		(start 193.5 143.05)
		(end 192.349 143.05)
		(width 0.15)
		(layer "F.Cu")
		(net 368)
	)
	(via
		(at 190.844 143.85)
		(size 0.45)
		(drill 0.1)
		(layers "F.Cu" "B.Cu")
		(net 368)
	)
	(segment
		(start 146.375501 176.300999)
		(end 146.875001 176.8005)
		(width 0.256)
		(layer "F.Cu")
		(net 369)
	)
	(via
		(at 146.875001 176.8005)
		(size 0.45)
		(drill 0.1)
		(layers "F.Cu" "B.Cu")
		(net 369)
	)
	(segment
		(start 147.377001 177.3025)
		(end 146.875001 176.8005)
		(width 0.4)
		(layer "B.Cu")
		(net 369)
	)
	(segment
		(start 91.685 178)
		(end 91.7 178)
		(width 0.256)
		(layer "F.Cu")
		(net 370)
	)
	(segment
		(start 93.565 176.135)
		(end 94.621501 176.135)
		(width 0.256)
		(layer "F.Cu")
		(net 370)
	)
	(segment
		(start 91.7 178)
		(end 93.565 176.135)
		(width 0.256)
		(layer "F.Cu")
		(net 370)
	)
	(segment
		(start 85.185 173.448)
		(end 84.413 173.448)
		(width 0.256)
		(layer "F.Cu")
		(net 371)
	)
	(segment
		(start 143.375501 184.301)
		(end 143.875001 184.8005)
		(width 0.256)
		(layer "F.Cu")
		(net 371)
	)
	(segment
		(start 85.948 173.448)
		(end 86.2 173.7)
		(width 0.256)
		(layer "F.Cu")
		(net 371)
	)
	(segment
		(start 85.185 173.448)
		(end 85.948 173.448)
		(width 0.256)
		(layer "F.Cu")
		(net 371)
	)
	(segment
		(start 84.413 173.448)
		(end 82.155501 173.448)
		(width 0.256)
		(layer "F.Cu")
		(net 371)
	)
	(segment
		(start 82.155501 173.448)
		(end 82.039501 173.564)
		(width 0.256)
		(layer "F.Cu")
		(net 371)
	)
	(via
		(at 86.2 173.7)
		(size 0.45)
		(drill 0.1)
		(layers "F.Cu" "B.Cu")
		(net 371)
	)
	(via
		(at 143.875001 184.8005)
		(size 0.45)
		(drill 0.1)
		(layers "F.Cu" "B.Cu")
		(net 371)
	)
	(segment
		(start 85.435 173.6)
		(end 86.1 173.6)
		(width 0.256)
		(layer "B.Cu")
		(net 371)
	)
	(segment
		(start 85.235 173.4)
		(end 85.435 173.6)
		(width 0.256)
		(layer "B.Cu")
		(net 371)
	)
	(segment
		(start 86.1 173.6)
		(end 86.2 173.7)
		(width 0.256)
		(layer "B.Cu")
		(net 371)
	)
	(segment
		(start 116.175 188.075)
		(end 117 187.25)
		(width 0.1)
		(layer "In6.Cu")
		(net 371)
	)
	(segment
		(start 86.85 177.25)
		(end 86.191003 177.25)
		(width 0.1)
		(layer "In6.Cu")
		(net 371)
	)
	(segment
		(start 87.008997 178.25)
		(end 86.6 178.25)
		(width 0.1)
		(layer "In6.Cu")
		(net 371)
	)
	(segment
		(start 131.207831 187.25)
		(end 131.4 187.057831)
		(width 0.1)
		(layer "In6.Cu")
		(net 371)
	)
	(segment
		(start 131.4 187.057831)
		(end 131.4 185.55)
		(width 0.1)
		(layer "In6.Cu")
		(net 371)
	)
	(segment
		(start 86.6 179)
		(end 86.6 180.423884)
		(width 0.1)
		(layer "In6.Cu")
		(net 371)
	)
	(segment
		(start 131.55 185.4)
		(end 143.278001 185.4)
		(width 0.1)
		(layer "In6.Cu")
		(net 371)
	)
	(segment
		(start 86.6 178.25)
		(end 86.191003 178.25)
		(width 0.1)
		(layer "In6.Cu")
		(net 371)
	)
	(segment
		(start 86.6 180.423884)
		(end 86.6 185.2)
		(width 0.1)
		(layer "In6.Cu")
		(net 371)
	)
	(segment
		(start 143.278001 185.4)
		(end 143.877501 184.8005)
		(width 0.1)
		(layer "In6.Cu")
		(net 371)
	)
	(segment
		(start 86.2 173.7)
		(end 86.6 174.1)
		(width 0.1)
		(layer "In6.Cu")
		(net 371)
	)
	(segment
		(start 86.6 185.2)
		(end 89.475 188.075)
		(width 0.1)
		(layer "In6.Cu")
		(net 371)
	)
	(segment
		(start 89.475 188.075)
		(end 116.175 188.075)
		(width 0.1)
		(layer "In6.Cu")
		(net 371)
	)
	(segment
		(start 86.191003 177.75)
		(end 86.6 177.75)
		(width 0.1)
		(layer "In6.Cu")
		(net 371)
	)
	(segment
		(start 86.6 177.75)
		(end 87.008997 177.75)
		(width 0.1)
		(layer "In6.Cu")
		(net 371)
	)
	(segment
		(start 87.008997 177.25)
		(end 86.85 177.25)
		(width 0.1)
		(layer "In6.Cu")
		(net 371)
	)
	(segment
		(start 86.85 176.75)
		(end 87.008997 176.75)
		(width 0.1)
		(layer "In6.Cu")
		(net 371)
	)
	(segment
		(start 86.191003 178.75)
		(end 86.35 178.75)
		(width 0.1)
		(layer "In6.Cu")
		(net 371)
	)
	(segment
		(start 86.6 174.1)
		(end 86.6 176.5)
		(width 0.1)
		(layer "In6.Cu")
		(net 371)
	)
	(segment
		(start 131.4 185.55)
		(end 131.55 185.4)
		(width 0.1)
		(layer "In6.Cu")
		(net 371)
	)
	(segment
		(start 117 187.25)
		(end 131.207831 187.25)
		(width 0.1)
		(layer "In6.Cu")
		(net 371)
	)
	(arc
		(start 85.941003 178.5)
		(mid 86.014226 178.676777)
		(end 86.191003 178.75)
		(width 0.1)
		(layer "In6.Cu")
		(net 371)
	)
	(arc
		(start 87.258997 177)
		(mid 87.185774 177.176777)
		(end 87.008997 177.25)
		(width 0.1)
		(layer "In6.Cu")
		(net 371)
	)
	(arc
		(start 85.941003 177.5)
		(mid 86.014226 177.676777)
		(end 86.191003 177.75)
		(width 0.1)
		(layer "In6.Cu")
		(net 371)
	)
	(arc
		(start 87.258997 178)
		(mid 87.185774 178.176777)
		(end 87.008997 178.25)
		(width 0.1)
		(layer "In6.Cu")
		(net 371)
	)
	(arc
		(start 87.008997 176.75)
		(mid 87.185774 176.823223)
		(end 87.258997 177)
		(width 0.1)
		(layer "In6.Cu")
		(net 371)
	)
	(arc
		(start 86.35 178.75)
		(mid 86.526777 178.823223)
		(end 86.6 179)
		(width 0.1)
		(layer "In6.Cu")
		(net 371)
	)
	(arc
		(start 86.191003 178.25)
		(mid 86.014226 178.323223)
		(end 85.941003 178.5)
		(width 0.1)
		(layer "In6.Cu")
		(net 371)
	)
	(arc
		(start 86.6 176.5)
		(mid 86.673223 176.676777)
		(end 86.85 176.75)
		(width 0.1)
		(layer "In6.Cu")
		(net 371)
	)
	(arc
		(start 87.008997 177.75)
		(mid 87.185774 177.823223)
		(end 87.258997 178)
		(width 0.1)
		(layer "In6.Cu")
		(net 371)
	)
	(arc
		(start 86.191003 177.25)
		(mid 86.014226 177.323223)
		(end 85.941003 177.5)
		(width 0.1)
		(layer "In6.Cu")
		(net 371)
	)
	(segment
		(start 144.375501 184.301)
		(end 144.875001 184.8005)
		(width 0.256)
		(layer "F.Cu")
		(net 372)
	)
	(segment
		(start 85.95 172.45)
		(end 86.25 172.15)
		(width 0.256)
		(layer "F.Cu")
		(net 372)
	)
	(segment
		(start 85.185 172.45)
		(end 84.413 172.45)
		(width 0.256)
		(layer "F.Cu")
		(net 372)
	)
	(segment
		(start 84.413 172.45)
		(end 82.055501 172.45)
		(width 0.256)
		(layer "F.Cu")
		(net 372)
	)
	(segment
		(start 85.185 172.45)
		(end 85.95 172.45)
		(width 0.256)
		(layer "F.Cu")
		(net 372)
	)
	(segment
		(start 82.055501 172.45)
		(end 82.039501 172.466)
		(width 0.256)
		(layer "F.Cu")
		(net 372)
	)
	(via
		(at 144.875001 184.8005)
		(size 0.45)
		(drill 0.1)
		(layers "F.Cu" "B.Cu")
		(net 372)
	)
	(via
		(at 86.25 172.15)
		(size 0.45)
		(drill 0.1)
		(layers "F.Cu" "B.Cu")
		(net 372)
	)
	(segment
		(start 86.2 172.2)
		(end 86.25 172.15)
		(width 0.256)
		(layer "B.Cu")
		(net 372)
	)
	(segment
		(start 85.235 172.4)
		(end 85.435 172.2)
		(width 0.256)
		(layer "B.Cu")
		(net 372)
	)
	(segment
		(start 85.435 172.2)
		(end 86.2 172.2)
		(width 0.256)
		(layer "B.Cu")
		(net 372)
	)
	(segment
		(start 143.383001 184.616999)
		(end 143.724 184.276)
		(width 0.1)
		(layer "In6.Cu")
		(net 372)
	)
	(segment
		(start 88.599999 185.124265)
		(end 88.6 185.124264)
		(width 0.1)
		(layer "In6.Cu")
		(net 372)
	)
	(segment
		(start 142.4 184.7)
		(end 142.4 185)
		(width 0.1)
		(layer "In6.Cu")
		(net 372)
	)
	(segment
		(start 88.6 185.124264)
		(end 88.432443 185.29182)
		(width 0.1)
		(layer "In6.Cu")
		(net 372)
	)
	(segment
		(start 130.6 184.4)
		(end 142.1 184.4)
		(width 0.1)
		(layer "In6.Cu")
		(net 372)
	)
	(segment
		(start 144.353001 184.276)
		(end 144.877501 184.8005)
		(width 0.1)
		(layer "In6.Cu")
		(net 372)
	)
	(segment
		(start 130.4 186.05)
		(end 130.4 184.6)
		(width 0.1)
		(layer "In6.Cu")
		(net 372)
	)
	(segment
		(start 87.7 175.4)
		(end 87.7 183.8)
		(width 0.1)
		(layer "In6.Cu")
		(net 372)
	)
	(segment
		(start 130.4 184.6)
		(end 130.6 184.4)
		(width 0.1)
		(layer "In6.Cu")
		(net 372)
	)
	(segment
		(start 88.856708 185.716083)
		(end 88.856707 185.716084)
		(width 0.1)
		(layer "In6.Cu")
		(net 372)
	)
	(segment
		(start 89.448527 185.548527)
		(end 89.448528 185.548528)
		(width 0.1)
		(layer "In6.Cu")
		(net 372)
	)
	(segment
		(start 115.4 187.1)
		(end 116.25 186.25)
		(width 0.1)
		(layer "In6.Cu")
		(net 372)
	)
	(segment
		(start 116.25 186.25)
		(end 130.2 186.25)
		(width 0.1)
		(layer "In6.Cu")
		(net 372)
	)
	(segment
		(start 86.25 172.15)
		(end 87.1 173)
		(width 0.1)
		(layer "In6.Cu")
		(net 372)
	)
	(segment
		(start 87.7 183.8)
		(end 88.6 184.7)
		(width 0.1)
		(layer "In6.Cu")
		(net 372)
	)
	(segment
		(start 142.1 184.4)
		(end 142.4 184.7)
		(width 0.1)
		(layer "In6.Cu")
		(net 372)
	)
	(segment
		(start 143.383001 185)
		(end 143.383001 184.616999)
		(width 0.1)
		(layer "In6.Cu")
		(net 372)
	)
	(segment
		(start 91 187.1)
		(end 115.4 187.1)
		(width 0.1)
		(layer "In6.Cu")
		(net 372)
	)
	(segment
		(start 142.5755 185.1755)
		(end 143.207501 185.1755)
		(width 0.1)
		(layer "In6.Cu")
		(net 372)
	)
	(segment
		(start 87.1 174.8)
		(end 87.7 175.4)
		(width 0.1)
		(layer "In6.Cu")
		(net 372)
	)
	(segment
		(start 130.2 186.25)
		(end 130.4 186.05)
		(width 0.1)
		(layer "In6.Cu")
		(net 372)
	)
	(segment
		(start 88.856707 185.716084)
		(end 89.024263 185.548527)
		(width 0.1)
		(layer "In6.Cu")
		(net 372)
	)
	(segment
		(start 89.448528 185.548528)
		(end 91 187.1)
		(width 0.1)
		(layer "In6.Cu")
		(net 372)
	)
	(segment
		(start 143.724 184.276)
		(end 144.353001 184.276)
		(width 0.1)
		(layer "In6.Cu")
		(net 372)
	)
	(segment
		(start 87.1 173)
		(end 87.1 174.8)
		(width 0.1)
		(layer "In6.Cu")
		(net 372)
	)
	(segment
		(start 142.4 185)
		(end 142.5755 185.1755)
		(width 0.1)
		(layer "In6.Cu")
		(net 372)
	)
	(segment
		(start 143.207501 185.1755)
		(end 143.383001 185)
		(width 0.1)
		(layer "In6.Cu")
		(net 372)
	)
	(arc
		(start 89.024263 185.548527)
		(mid 89.236395 185.460659)
		(end 89.448527 185.548527)
		(width 0.1)
		(layer "In6.Cu")
		(net 372)
	)
	(arc
		(start 88.432443 185.29182)
		(mid 88.344575 185.503952)
		(end 88.432443 185.716084)
		(width 0.1)
		(layer "In6.Cu")
		(net 372)
	)
	(arc
		(start 88.6 184.7)
		(mid 88.687868 184.912133)
		(end 88.599999 185.124265)
		(width 0.1)
		(layer "In6.Cu")
		(net 372)
	)
	(arc
		(start 88.432443 185.716084)
		(mid 88.644576 185.803952)
		(end 88.856708 185.716083)
		(width 0.1)
		(layer "In6.Cu")
		(net 372)
	)
	(segment
		(start 84 171.7)
		(end 84 170.9)
		(width 0.256)
		(layer "F.Cu")
		(net 373)
	)
	(segment
		(start 142.375501 184.301001)
		(end 142.875001 184.8005)
		(width 0.256)
		(layer "F.Cu")
		(net 373)
	)
	(segment
		(start 84 170.9)
		(end 83.366 170.266)
		(width 0.256)
		(layer "F.Cu")
		(net 373)
	)
	(segment
		(start 85.65 171.95)
		(end 86.15 171.45)
		(width 0.256)
		(layer "F.Cu")
		(net 373)
	)
	(segment
		(start 84.413 171.95)
		(end 84.25 171.95)
		(width 0.256)
		(layer "F.Cu")
		(net 373)
	)
	(segment
		(start 85.185 171.95)
		(end 84.413 171.95)
		(width 0.256)
		(layer "F.Cu")
		(net 373)
	)
	(segment
		(start 83.366 170.266)
		(end 82.039501 170.266)
		(width 0.256)
		(layer "F.Cu")
		(net 373)
	)
	(segment
		(start 84.25 171.95)
		(end 84 171.7)
		(width 0.256)
		(layer "F.Cu")
		(net 373)
	)
	(segment
		(start 85.185 171.95)
		(end 85.65 171.95)
		(width 0.256)
		(layer "F.Cu")
		(net 373)
	)
	(via
		(at 142.875001 184.8005)
		(size 0.45)
		(drill 0.1)
		(layers "F.Cu" "B.Cu")
		(net 373)
	)
	(via
		(at 86.15 171.45)
		(size 0.45)
		(drill 0.1)
		(layers "F.Cu" "B.Cu")
		(net 373)
	)
	(segment
		(start 86.1 171.5)
		(end 86.15 171.45)
		(width 0.256)
		(layer "B.Cu")
		(net 373)
	)
	(segment
		(start 85.235 171.4)
		(end 85.335 171.5)
		(width 0.256)
		(layer "B.Cu")
		(net 373)
	)
	(segment
		(start 85.335 171.5)
		(end 86.1 171.5)
		(width 0.256)
		(layer "B.Cu")
		(net 373)
	)
	(segment
		(start 88.4 175.669906)
		(end 88.4 175.6)
		(width 0.1)
		(layer "In6.Cu")
		(net 373)
	)
	(segment
		(start 88.4 175.6)
		(end 88.4 174.5)
		(width 0.1)
		(layer "In6.Cu")
		(net 373)
	)
	(segment
		(start 142.877501 184.8005)
		(end 142.877501 184.477501)
		(width 0.1)
		(layer "In6.Cu")
		(net 373)
	)
	(segment
		(start 138.5 183.3)
		(end 122.7 183.3)
		(width 0.1)
		(layer "In6.Cu")
		(net 373)
	)
	(segment
		(start 91.775 186.275)
		(end 88.4 182.9)
		(width 0.1)
		(layer "In6.Cu")
		(net 373)
	)
	(segment
		(start 88.65 179.35)
		(end 88.75 179.35)
		(width 0.1)
		(layer "In6.Cu")
		(net 373)
	)
	(segment
		(start 142.6 184.2)
		(end 141.6 184.2)
		(width 0.1)
		(layer "In6.Cu")
		(net 373)
	)
	(segment
		(start 89.125 176.875)
		(end 88.675 176.875)
		(width 0.1)
		(layer "In6.Cu")
		(net 373)
	)
	(segment
		(start 88.565047 176.234953)
		(end 88.565048 176.234953)
		(width 0.1)
		(layer "In6.Cu")
		(net 373)
	)
	(segment
		(start 88.4 182.9)
		(end 88.4 179.6)
		(width 0.1)
		(layer "In6.Cu")
		(net 373)
	)
	(segment
		(start 88.4 178.6)
		(end 88.4 177.7)
		(width 0.1)
		(layer "In6.Cu")
		(net 373)
	)
	(segment
		(start 141.080502 183.3755)
		(end 138.5755 183.3755)
		(width 0.1)
		(layer "In6.Cu")
		(net 373)
	)
	(segment
		(start 120.625 185.375)
		(end 115.925 185.375)
		(width 0.1)
		(layer "In6.Cu")
		(net 373)
	)
	(segment
		(start 115.025 186.275)
		(end 91.775 186.275)
		(width 0.1)
		(layer "In6.Cu")
		(net 373)
	)
	(segment
		(start 86.95 171.45)
		(end 86.15 171.45)
		(width 0.1)
		(layer "In6.Cu")
		(net 373)
	)
	(segment
		(start 88.730095 176.069906)
		(end 88.730095 176)
		(width 0.1)
		(layer "In6.Cu")
		(net 373)
	)
	(segment
		(start 87.7 172.2)
		(end 86.95 171.45)
		(width 0.1)
		(layer "In6.Cu")
		(net 373)
	)
	(segment
		(start 88.4 176.6)
		(end 88.4 176.4)
		(width 0.1)
		(layer "In6.Cu")
		(net 373)
	)
	(segment
		(start 142.877501 184.477501)
		(end 142.6 184.2)
		(width 0.1)
		(layer "In6.Cu")
		(net 373)
	)
	(segment
		(start 88.675 177.425)
		(end 89.125 177.425)
		(width 0.1)
		(layer "In6.Cu")
		(net 373)
	)
	(segment
		(start 122.7 183.3)
		(end 120.625 185.375)
		(width 0.1)
		(layer "In6.Cu")
		(net 373)
	)
	(segment
		(start 88.95 179.55)
		(end 88.95 180.2)
		(width 0.1)
		(layer "In6.Cu")
		(net 373)
	)
	(segment
		(start 88.565048 175.834953)
		(end 88.565047 175.834953)
		(width 0.1)
		(layer "In6.Cu")
		(net 373)
	)
	(segment
		(start 115.925 185.375)
		(end 115.025 186.275)
		(width 0.1)
		(layer "In6.Cu")
		(net 373)
	)
	(segment
		(start 141.4 183.694998)
		(end 141.080502 183.3755)
		(width 0.1)
		(layer "In6.Cu")
		(net 373)
	)
	(segment
		(start 89.55 178.85)
		(end 88.65 178.85)
		(width 0.1)
		(layer "In6.Cu")
		(net 373)
	)
	(segment
		(start 141.6 184.2)
		(end 141.4 184)
		(width 0.1)
		(layer "In6.Cu")
		(net 373)
	)
	(segment
		(start 87.7 173.8)
		(end 87.7 172.2)
		(width 0.1)
		(layer "In6.Cu")
		(net 373)
	)
	(segment
		(start 88.4 174.5)
		(end 87.7 173.8)
		(width 0.1)
		(layer "In6.Cu")
		(net 373)
	)
	(segment
		(start 89.35 180.2)
		(end 89.35 179.55)
		(width 0.1)
		(layer "In6.Cu")
		(net 373)
	)
	(segment
		(start 138.5755 183.3755)
		(end 138.5 183.3)
		(width 0.1)
		(layer "In6.Cu")
		(net 373)
	)
	(segment
		(start 141.4 184)
		(end 141.4 183.694998)
		(width 0.1)
		(layer "In6.Cu")
		(net 373)
	)
	(arc
		(start 89.35 179.55)
		(mid 89.408579 179.408579)
		(end 89.55 179.35)
		(width 0.1)
		(layer "In6.Cu")
		(net 373)
	)
	(arc
		(start 88.565048 176.234953)
		(mid 88.681754 176.186612)
		(end 88.730095 176.069906)
		(width 0.1)
		(layer "In6.Cu")
		(net 373)
	)
	(arc
		(start 88.675 176.875)
		(mid 88.480546 176.794454)
		(end 88.4 176.6)
		(width 0.1)
		(layer "In6.Cu")
		(net 373)
	)
	(arc
		(start 89.125 177.425)
		(mid 89.319454 177.344454)
		(end 89.4 177.15)
		(width 0.1)
		(layer "In6.Cu")
		(net 373)
	)
	(arc
		(start 89.55 179.35)
		(mid 89.726777 179.276777)
		(end 89.8 179.1)
		(width 0.1)
		(layer "In6.Cu")
		(net 373)
	)
	(arc
		(start 88.75 179.35)
		(mid 88.891421 179.408579)
		(end 88.95 179.55)
		(width 0.1)
		(layer "In6.Cu")
		(net 373)
	)
	(arc
		(start 88.4 177.7)
		(mid 88.480546 177.505546)
		(end 88.675 177.425)
		(width 0.1)
		(layer "In6.Cu")
		(net 373)
	)
	(arc
		(start 88.730095 176)
		(mid 88.681754 175.883294)
		(end 88.565048 175.834953)
		(width 0.1)
		(layer "In6.Cu")
		(net 373)
	)
	(arc
		(start 89.8 179.1)
		(mid 89.726777 178.923223)
		(end 89.55 178.85)
		(width 0.1)
		(layer "In6.Cu")
		(net 373)
	)
	(arc
		(start 89.15 180.4)
		(mid 89.291421 180.341421)
		(end 89.35 180.2)
		(width 0.1)
		(layer "In6.Cu")
		(net 373)
	)
	(arc
		(start 88.65 178.85)
		(mid 88.473223 178.776777)
		(end 88.4 178.6)
		(width 0.1)
		(layer "In6.Cu")
		(net 373)
	)
	(arc
		(start 88.95 180.2)
		(mid 89.008579 180.341421)
		(end 89.15 180.4)
		(width 0.1)
		(layer "In6.Cu")
		(net 373)
	)
	(arc
		(start 88.4 176.4)
		(mid 88.448341 176.283294)
		(end 88.565047 176.234953)
		(width 0.1)
		(layer "In6.Cu")
		(net 373)
	)
	(arc
		(start 89.4 177.15)
		(mid 89.319454 176.955546)
		(end 89.125 176.875)
		(width 0.1)
		(layer "In6.Cu")
		(net 373)
	)
	(arc
		(start 88.565047 175.834953)
		(mid 88.448341 175.786612)
		(end 88.4 175.669906)
		(width 0.1)
		(layer "In6.Cu")
		(net 373)
	)
	(arc
		(start 88.4 179.6)
		(mid 88.473223 179.423223)
		(end 88.65 179.35)
		(width 0.1)
		(layer "In6.Cu")
		(net 373)
	)
	(segment
		(start 83.115 168.065)
		(end 84.048 168.998)
		(width 0.256)
		(layer "F.Cu")
		(net 374)
	)
	(segment
		(start 85.185 168.998)
		(end 84.413 168.998)
		(width 0.256)
		(layer "F.Cu")
		(net 374)
	)
	(segment
		(start 84.048 168.998)
		(end 84.413 168.998)
		(width 0.256)
		(layer "F.Cu")
		(net 374)
	)
	(segment
		(start 85.185 168.998)
		(end 85.948 168.998)
		(width 0.256)
		(layer "F.Cu")
		(net 374)
	)
	(segment
		(start 85.948 168.998)
		(end 86.2 169.25)
		(width 0.256)
		(layer "F.Cu")
		(net 374)
	)
	(segment
		(start 142.375501 183.301)
		(end 142.875001 183.8005)
		(width 0.256)
		(layer "F.Cu")
		(net 374)
	)
	(segment
		(start 82.039501 168.065)
		(end 83.115 168.065)
		(width 0.256)
		(layer "F.Cu")
		(net 374)
	)
	(via
		(at 86.2 169.25)
		(size 0.45)
		(drill 0.1)
		(layers "F.Cu" "B.Cu")
		(net 374)
	)
	(via
		(at 142.875001 183.8005)
		(size 0.45)
		(drill 0.1)
		(layers "F.Cu" "B.Cu")
		(net 374)
	)
	(segment
		(start 85.245 168.925)
		(end 85.32 169)
		(width 0.256)
		(layer "B.Cu")
		(net 374)
	)
	(segment
		(start 85.95 169)
		(end 86.2 169.25)
		(width 0.256)
		(layer "B.Cu")
		(net 374)
	)
	(segment
		(start 85.32 169)
		(end 85.95 169)
		(width 0.256)
		(layer "B.Cu")
		(net 374)
	)
	(segment
		(start 138.45 182.3)
		(end 139.3255 183.1755)
		(width 0.1)
		(layer "In6.Cu")
		(net 374)
	)
	(segment
		(start 90.4 175)
		(end 90.4 176.216658)
		(width 0.1)
		(layer "In6.Cu")
		(net 374)
	)
	(segment
		(start 89.5 180.75)
		(end 89.5 182.5)
		(width 0.1)
		(layer "In6.Cu")
		(net 374)
	)
	(segment
		(start 89.8 174.8)
		(end 89.4 174.8)
		(width 0.1)
		(layer "In6.Cu")
		(net 374)
	)
	(segment
		(start 139.3255 183.1755)
		(end 141.8755 183.1755)
		(width 0.1)
		(layer "In6.Cu")
		(net 374)
	)
	(segment
		(start 121.15 182.55)
		(end 125.2 182.55)
		(width 0.1)
		(layer "In6.Cu")
		(net 374)
	)
	(segment
		(start 113.2 185.3)
		(end 114.65 183.85)
		(width 0.1)
		(layer "In6.Cu")
		(net 374)
	)
	(segment
		(start 142.5005 183.8005)
		(end 142.877501 183.8005)
		(width 0.1)
		(layer "In6.Cu")
		(net 374)
	)
	(segment
		(start 90.3 177.3)
		(end 90.3 179.95)
		(width 0.1)
		(layer "In6.Cu")
		(net 374)
	)
	(segment
		(start 89.4 174.4)
		(end 90.7 174.4)
		(width 0.1)
		(layer "In6.Cu")
		(net 374)
	)
	(segment
		(start 141.8755 183.1755)
		(end 142.5005 183.8005)
		(width 0.1)
		(layer "In6.Cu")
		(net 374)
	)
	(segment
		(start 90.3 179.95)
		(end 89.5 180.75)
		(width 0.1)
		(layer "In6.Cu")
		(net 374)
	)
	(segment
		(start 86.2 169.25)
		(end 86.315686 169.25)
		(width 0.1)
		(layer "In6.Cu")
		(net 374)
	)
	(segment
		(start 125.2 182.55)
		(end 125.45 182.3)
		(width 0.1)
		(layer "In6.Cu")
		(net 374)
	)
	(segment
		(start 88.657843 171.592157)
		(end 88.657843 173.557843)
		(width 0.1)
		(layer "In6.Cu")
		(net 374)
	)
	(segment
		(start 125.45 182.3)
		(end 138.45 182.3)
		(width 0.1)
		(layer "In6.Cu")
		(net 374)
	)
	(segment
		(start 88.657843 173.557843)
		(end 89.2 174.1)
		(width 0.1)
		(layer "In6.Cu")
		(net 374)
	)
	(segment
		(start 92.3 185.3)
		(end 113.2 185.3)
		(width 0.1)
		(layer "In6.Cu")
		(net 374)
	)
	(segment
		(start 89.2 176.2)
		(end 90.3 177.3)
		(width 0.1)
		(layer "In6.Cu")
		(net 374)
	)
	(segment
		(start 119.85 183.85)
		(end 121.15 182.55)
		(width 0.1)
		(layer "In6.Cu")
		(net 374)
	)
	(segment
		(start 86.315686 169.25)
		(end 88.657843 171.592157)
		(width 0.1)
		(layer "In6.Cu")
		(net 374)
	)
	(segment
		(start 89.2 175)
		(end 89.2 176.2)
		(width 0.1)
		(layer "In6.Cu")
		(net 374)
	)
	(segment
		(start 114.65 183.85)
		(end 119.85 183.85)
		(width 0.1)
		(layer "In6.Cu")
		(net 374)
	)
	(segment
		(start 89.2 174.1)
		(end 89.2 174.2)
		(width 0.1)
		(layer "In6.Cu")
		(net 374)
	)
	(segment
		(start 89.5 182.5)
		(end 92.3 185.3)
		(width 0.1)
		(layer "In6.Cu")
		(net 374)
	)
	(segment
		(start 90.7 174.8)
		(end 90.6 174.8)
		(width 0.1)
		(layer "In6.Cu")
		(net 374)
	)
	(segment
		(start 90 176.216658)
		(end 90 175)
		(width 0.1)
		(layer "In6.Cu")
		(net 374)
	)
	(arc
		(start 89.2 174.2)
		(mid 89.258579 174.341421)
		(end 89.4 174.4)
		(width 0.1)
		(layer "In6.Cu")
		(net 374)
	)
	(arc
		(start 90.6 174.8)
		(mid 90.458579 174.858579)
		(end 90.4 175)
		(width 0.1)
		(layer "In6.Cu")
		(net 374)
	)
	(arc
		(start 90.7 174.4)
		(mid 90.841421 174.458579)
		(end 90.9 174.6)
		(width 0.1)
		(layer "In6.Cu")
		(net 374)
	)
	(arc
		(start 90.2 176.416658)
		(mid 90.058579 176.358079)
		(end 90 176.216658)
		(width 0.1)
		(layer "In6.Cu")
		(net 374)
	)
	(arc
		(start 90.4 176.216658)
		(mid 90.341421 176.358079)
		(end 90.2 176.416658)
		(width 0.1)
		(layer "In6.Cu")
		(net 374)
	)
	(arc
		(start 89.4 174.8)
		(mid 89.258579 174.858579)
		(end 89.2 175)
		(width 0.1)
		(layer "In6.Cu")
		(net 374)
	)
	(arc
		(start 90.9 174.6)
		(mid 90.841421 174.741421)
		(end 90.7 174.8)
		(width 0.1)
		(layer "In6.Cu")
		(net 374)
	)
	(arc
		(start 90 175)
		(mid 89.941421 174.858579)
		(end 89.8 174.8)
		(width 0.1)
		(layer "In6.Cu")
		(net 374)
	)
	(segment
		(start 91.537344 173.382328)
		(end 92.132328 173.382328)
		(width 0.256)
		(layer "F.Cu")
		(net 375)
	)
	(segment
		(start 92.132328 173.382328)
		(end 92.356 173.606)
		(width 0.256)
		(layer "F.Cu")
		(net 375)
	)
	(segment
		(start 92.356 173.606)
		(end 94.592001 173.606)
		(width 0.256)
		(layer "F.Cu")
		(net 375)
	)
	(segment
		(start 94.592001 173.606)
		(end 94.622001 173.636)
		(width 0.15)
		(layer "F.Cu")
		(net 375)
	)
	(segment
		(start 127.376501 175.301)
		(end 126.877001 175.8005)
		(width 0.256)
		(layer "F.Cu")
		(net 376)
	)
	(segment
		(start 130.376501 174.302)
		(end 129.877001 173.8025)
		(width 0.256)
		(layer "F.Cu")
		(net 376)
	)
	(segment
		(start 126.376501 172.302)
		(end 125.877001 171.8025)
		(width 0.256)
		(layer "F.Cu")
		(net 376)
	)
	(segment
		(start 128.376501 178.301)
		(end 127.877001 178.8005)
		(width 0.256)
		(layer "F.Cu")
		(net 376)
	)
	(segment
		(start 136.376501 172.302)
		(end 135.877001 171.8025)
		(width 0.256)
		(layer "F.Cu")
		(net 376)
	)
	(segment
		(start 133.376501 173.302)
		(end 132.877001 172.8025)
		(width 0.256)
		(layer "F.Cu")
		(net 376)
	)
	(via
		(at 126.877001 175.8005)
		(size 0.45)
		(drill 0.1)
		(layers "F.Cu" "B.Cu")
		(net 376)
	)
	(via
		(at 132.877001 172.8025)
		(size 0.45)
		(drill 0.1)
		(layers "F.Cu" "B.Cu")
		(net 376)
	)
	(via
		(at 127.877001 178.8005)
		(size 0.45)
		(drill 0.1)
		(layers "F.Cu" "B.Cu")
		(net 376)
	)
	(via
		(at 125.877001 171.8025)
		(size 0.45)
		(drill 0.1)
		(layers "F.Cu" "B.Cu")
		(net 376)
	)
	(via
		(at 129.877001 173.8025)
		(size 0.45)
		(drill 0.1)
		(layers "F.Cu" "B.Cu")
		(net 376)
	)
	(via
		(at 135.877001 171.8025)
		(size 0.45)
		(drill 0.1)
		(layers "F.Cu" "B.Cu")
		(net 376)
	)
	(segment
		(start 135.330001 172.3495)
		(end 133.330001 172.3495)
		(width 0.1)
		(layer "B.Cu")
		(net 376)
	)
	(segment
		(start 127.877001 178.8005)
		(end 127.424001 178.3475)
		(width 0.1)
		(layer "B.Cu")
		(net 376)
	)
	(segment
		(start 129.425501 176.026)
		(end 129.425501 174.254)
		(width 0.1)
		(layer "B.Cu")
		(net 376)
	)
	(segment
		(start 132.502001 173.1775)
		(end 130.502001 173.1775)
		(width 0.1)
		(layer "B.Cu")
		(net 376)
	)
	(segment
		(start 126.325501 173.25)
		(end 126.376001 173.3005)
		(width 0.1)
		(layer "B.Cu")
		(net 376)
	)
	(segment
		(start 133.330001 172.3495)
		(end 132.877001 172.8025)
		(width 0.1)
		(layer "B.Cu")
		(net 376)
	)
	(segment
		(start 135.877001 171.8025)
		(end 135.330001 172.3495)
		(width 0.1)
		(layer "B.Cu")
		(net 376)
	)
	(segment
		(start 127.424001 176.3475)
		(end 128.860333 176.3475)
		(width 0.1)
		(layer "B.Cu")
		(net 376)
	)
	(segment
		(start 129.375501 173.301)
		(end 126.376501 173.301)
		(width 0.1)
		(layer "B.Cu")
		(net 376)
	)
	(segment
		(start 127.424001 178.3475)
		(end 127.424001 176.3475)
		(width 0.1)
		(layer "B.Cu")
		(net 376)
	)
	(segment
		(start 128.863833 176.351)
		(end 129.100501 176.351)
		(width 0.1)
		(layer "B.Cu")
		(net 376)
	)
	(segment
		(start 129.425501 174.254)
		(end 129.877001 173.8025)
		(width 0.1)
		(layer "B.Cu")
		(net 376)
	)
	(segment
		(start 126.325501 172.251)
		(end 126.325501 173.25)
		(width 0.1)
		(layer "B.Cu")
		(net 376)
	)
	(segment
		(start 129.877001 173.8025)
		(end 129.375501 173.301)
		(width 0.1)
		(layer "B.Cu")
		(net 376)
	)
	(segment
		(start 129.100501 176.351)
		(end 129.425501 176.026)
		(width 0.1)
		(layer "B.Cu")
		(net 376)
	)
	(segment
		(start 128.860333 176.3475)
		(end 128.863833 176.351)
		(width 0.1)
		(layer "B.Cu")
		(net 376)
	)
	(segment
		(start 130.502001 173.1775)
		(end 129.877001 173.8025)
		(width 0.1)
		(layer "B.Cu")
		(net 376)
	)
	(segment
		(start 126.376501 173.301)
		(end 126.376001 173.3005)
		(width 0.1)
		(layer "B.Cu")
		(net 376)
	)
	(segment
		(start 132.877001 172.8025)
		(end 132.502001 173.1775)
		(width 0.1)
		(layer "B.Cu")
		(net 376)
	)
	(segment
		(start 125.877001 171.8025)
		(end 126.325501 172.251)
		(width 0.1)
		(layer "B.Cu")
		(net 376)
	)
	(segment
		(start 127.424001 176.3475)
		(end 126.877001 175.8005)
		(width 0.1)
		(layer "B.Cu")
		(net 376)
	)
	(segment
		(start 132.376501 180.301)
		(end 131.877001 180.8005)
		(width 0.256)
		(layer "F.Cu")
		(net 377)
	)
	(segment
		(start 136.3765 182.301)
		(end 135.877001 182.800499)
		(width 0.256)
		(layer "F.Cu")
		(net 377)
	)
	(segment
		(start 134.376501 186.301)
		(end 133.877001 186.8005)
		(width 0.256)
		(layer "F.Cu")
		(net 377)
	)
	(segment
		(start 134.376501 176.301)
		(end 133.877001 176.8005)
		(width 0.256)
		(layer "F.Cu")
		(net 377)
	)
	(segment
		(start 135.376501 179.301)
		(end 134.877001 179.8005)
		(width 0.256)
		(layer "F.Cu")
		(net 377)
	)
	(segment
		(start 133.376501 183.301)
		(end 132.877001 183.8005)
		(width 0.256)
		(layer "F.Cu")
		(net 377)
	)
	(via
		(at 131.877001 180.8005)
		(size 0.45)
		(drill 0.1)
		(layers "F.Cu" "B.Cu")
		(net 377)
	)
	(via
		(at 135.877001 182.800499)
		(size 0.45)
		(drill 0.1)
		(layers "F.Cu" "B.Cu")
		(net 377)
	)
	(via
		(at 132.877001 183.8005)
		(size 0.45)
		(drill 0.1)
		(layers "F.Cu" "B.Cu")
		(net 377)
	)
	(via
		(at 133.877001 186.8005)
		(size 0.45)
		(drill 0.1)
		(layers "F.Cu" "B.Cu")
		(net 377)
	)
	(via
		(at 133.877001 176.8005)
		(size 0.45)
		(drill 0.1)
		(layers "F.Cu" "B.Cu")
		(net 377)
	)
	(via
		(at 134.877001 179.8005)
		(size 0.45)
		(drill 0.1)
		(layers "F.Cu" "B.Cu")
		(net 377)
	)
	(segment
		(start 134.376 186.301501)
		(end 133.877001 186.8005)
		(width 0.256)
		(layer "B.Cu")
		(net 377)
	)
	(segment
		(start 134.425501 179.176)
		(end 134.425501 179.349)
		(width 0.1)
		(layer "B.Cu")
		(net 377)
	)
	(segment
		(start 134.376 186.3)
		(end 134.376 186.301501)
		(width 0.256)
		(layer "B.Cu")
		(net 377)
	)
	(segment
		(start 133.677502 182.323999)
		(end 133.375501 182.626)
		(width 0.1)
		(layer "B.Cu")
		(net 377)
	)
	(segment
		(start 135.400501 182.323999)
		(end 133.677502 182.323999)
		(width 0.1)
		(layer "B.Cu")
		(net 377)
	)
	(segment
		(start 134.425501 179.349)
		(end 134.877001 179.8005)
		(width 0.1)
		(layer "B.Cu")
		(net 377)
	)
	(segment
		(start 133.375501 183.302)
		(end 132.877001 183.8005)
		(width 0.1)
		(layer "B.Cu")
		(net 377)
	)
	(segment
		(start 134.425501 177.349)
		(end 134.425501 179.176)
		(width 0.1)
		(layer "B.Cu")
		(net 377)
	)
	(segment
		(start 133.375501 182.626)
		(end 133.375501 183.302)
		(width 0.1)
		(layer "B.Cu")
		(net 377)
	)
	(segment
		(start 132.325501 179.651)
		(end 132.325501 180.352)
		(width 0.1)
		(layer "B.Cu")
		(net 377)
	)
	(segment
		(start 135.400501 182.323999)
		(end 135.877001 182.800499)
		(width 0.1)
		(layer "B.Cu")
		(net 377)
	)
	(segment
		(start 133.375501 184.299)
		(end 133.375501 186.299)
		(width 0.1)
		(layer "B.Cu")
		(net 377)
	)
	(segment
		(start 132.877001 183.8005)
		(end 133.375501 184.299)
		(width 0.1)
		(layer "B.Cu")
		(net 377)
	)
	(segment
		(start 132.325501 180.352)
		(end 131.877001 180.8005)
		(width 0.1)
		(layer "B.Cu")
		(net 377)
	)
	(segment
		(start 134.425501 179.176)
		(end 132.800501 179.176)
		(width 0.1)
		(layer "B.Cu")
		(net 377)
	)
	(segment
		(start 132.800501 179.176)
		(end 132.325501 179.651)
		(width 0.1)
		(layer "B.Cu")
		(net 377)
	)
	(segment
		(start 133.375501 186.299)
		(end 133.877001 186.8005)
		(width 0.1)
		(layer "B.Cu")
		(net 377)
	)
	(segment
		(start 135.400501 180.324)
		(end 135.400501 182.323999)
		(width 0.1)
		(layer "B.Cu")
		(net 377)
	)
	(segment
		(start 133.877001 176.8005)
		(end 134.425501 177.349)
		(width 0.1)
		(layer "B.Cu")
		(net 377)
	)
	(segment
		(start 134.877001 179.8005)
		(end 135.400501 180.324)
		(width 0.1)
		(layer "B.Cu")
		(net 377)
	)
	(segment
		(start 95.6 184.115)
		(end 95.565 184.115)
		(width 0.15)
		(layer "F.Cu")
		(net 378)
	)
	(segment
		(start 94.9 183.45)
		(end 94.9 182.949)
		(width 0.15)
		(layer "F.Cu")
		(net 378)
	)
	(segment
		(start 95.565 184.115)
		(end 94.9 183.45)
		(width 0.15)
		(layer "F.Cu")
		(net 378)
	)
	(segment
		(start 138.262001 160.8005)
		(end 138.412501 160.65)
		(width 0.4)
		(layer "B.Cu")
		(net 379)
	)
	(segment
		(start 140.035 160.65)
		(end 140.1 160.585)
		(width 0.4)
		(layer "B.Cu")
		(net 379)
	)
	(segment
		(start 138.412501 160.65)
		(end 140.035 160.65)
		(width 0.4)
		(layer "B.Cu")
		(net 379)
	)
	(segment
		(start 138.262001 159.5755)
		(end 138.262001 160.8005)
		(width 0.4)
		(layer "B.Cu")
		(net 379)
	)
	(segment
		(start 94.4 182.949)
		(end 94.4 184.015)
		(width 0.15)
		(layer "F.Cu")
		(net 380)
	)
	(segment
		(start 94.4 184.015)
		(end 94.5 184.115)
		(width 0.15)
		(layer "F.Cu")
		(net 380)
	)
	(segment
		(start 93.9 183.636171)
		(end 93.422843 184.113328)
		(width 0.15)
		(layer "F.Cu")
		(net 381)
	)
	(segment
		(start 93.9 182.949)
		(end 93.9 183.636171)
		(width 0.15)
		(layer "F.Cu")
		(net 381)
	)
	(segment
		(start 92.8275 183.7775)
		(end 92.6375 183.7775)
		(width 0.15)
		(layer "F.Cu")
		(net 382)
	)
	(segment
		(start 93.406 183.199)
		(end 92.8275 183.7775)
		(width 0.15)
		(layer "F.Cu")
		(net 382)
	)
	(segment
		(start 92.6375 183.7775)
		(end 92.3 184.115)
		(width 0.15)
		(layer "F.Cu")
		(net 382)
	)
	(segment
		(start 93.406 182.949)
		(end 93.406 183.199)
		(width 0.15)
		(layer "F.Cu")
		(net 382)
	)
	(segment
		(start 100.606 181.929)
		(end 100.6 181.935)
		(width 0.15)
		(layer "F.Cu")
		(net 383)
	)
	(segment
		(start 103.152 181.929)
		(end 100.606 181.929)
		(width 0.15)
		(layer "F.Cu")
		(net 383)
	)
	(segment
		(start 96.97765 152.036)
		(end 100.208352 152.036)
		(width 0.15)
		(layer "F.Cu")
		(net 384)
	)
	(segment
		(start 183.851107 184.164)
		(end 184.436 184.164)
		(width 0.182)
		(layer "F.Cu")
		(net 385)
	)
	(segment
		(start 184.436 184.164)
		(end 185 183.6)
		(width 0.182)
		(layer "F.Cu")
		(net 385)
	)
	(segment
		(start 183.851107 166)
		(end 184.436 166)
		(width 0.182)
		(layer "F.Cu")
		(net 386)
	)
	(segment
		(start 184.436 166)
		(end 185 165.436)
		(width 0.182)
		(layer "F.Cu")
		(net 386)
	)
	(segment
		(start 98.25 145.226501)
		(end 98.100501 145.376)
		(width 0.256)
		(layer "F.Cu")
		(net 387)
	)
	(segment
		(start 98.25 143.790501)
		(end 98.25 145.226501)
		(width 0.256)
		(layer "F.Cu")
		(net 387)
	)
	(segment
		(start 98.313501 143.727)
		(end 98.25 143.790501)
		(width 0.256)
		(layer "F.Cu")
		(net 387)
	)
	(segment
		(start 143.375501 187.301)
		(end 143.875001 187.8005)
		(width 0.256)
		(layer "F.Cu")
		(net 394)
	)
	(via
		(at 143.875001 187.8005)
		(size 0.45)
		(drill 0.1)
		(layers "F.Cu" "B.Cu")
		(net 394)
	)
	(segment
		(start 135.376502 187.301)
		(end 134.877001 187.8005)
		(width 0.256)
		(layer "F.Cu")
		(net 395)
	)
	(via
		(at 134.877001 187.8005)
		(size 0.45)
		(drill 0.1)
		(layers "F.Cu" "B.Cu")
		(net 395)
	)
	(segment
		(start 134.376501 187.301)
		(end 133.877001 187.8005)
		(width 0.256)
		(layer "F.Cu")
		(net 396)
	)
	(via
		(at 133.877001 187.8005)
		(size 0.45)
		(drill 0.1)
		(layers "F.Cu" "B.Cu")
		(net 396)
	)
	(segment
		(start 133.376501 187.301)
		(end 132.877001 187.8005)
		(width 0.256)
		(layer "F.Cu")
		(net 397)
	)
	(via
		(at 132.877001 187.8005)
		(size 0.45)
		(drill 0.1)
		(layers "F.Cu" "B.Cu")
		(net 397)
	)
	(segment
		(start 128.376501 166.302)
		(end 127.877001 165.8025)
		(width 0.256)
		(layer "F.Cu")
		(net 398)
	)
	(via
		(at 127.877001 165.8025)
		(size 0.45)
		(drill 0.1)
		(layers "F.Cu" "B.Cu")
		(net 398)
	)
	(segment
		(start 127.376501 166.302)
		(end 126.877001 165.8025)
		(width 0.256)
		(layer "F.Cu")
		(net 399)
	)
	(via
		(at 126.877001 165.8025)
		(size 0.45)
		(drill 0.1)
		(layers "F.Cu" "B.Cu")
		(net 399)
	)
	(segment
		(start 129.376501 165.302)
		(end 128.877001 164.8025)
		(width 0.256)
		(layer "F.Cu")
		(net 400)
	)
	(via
		(at 128.877001 164.8025)
		(size 0.45)
		(drill 0.1)
		(layers "F.Cu" "B.Cu")
		(net 400)
	)
	(segment
		(start 143.375501 186.301)
		(end 143.875002 186.8005)
		(width 0.256)
		(layer "F.Cu")
		(net 401)
	)
	(via
		(at 143.875002 186.8005)
		(size 0.45)
		(drill 0.1)
		(layers "F.Cu" "B.Cu")
		(net 401)
	)
	(segment
		(start 141.375501 186.301)
		(end 141.875001 186.8005)
		(width 0.256)
		(layer "F.Cu")
		(net 402)
	)
	(via
		(at 141.875001 186.8005)
		(size 0.45)
		(drill 0.1)
		(layers "F.Cu" "B.Cu")
		(net 402)
	)
	(segment
		(start 136.376501 186.301)
		(end 135.877002 186.8005)
		(width 0.256)
		(layer "F.Cu")
		(net 404)
	)
	(via
		(at 135.877002 186.8005)
		(size 0.45)
		(drill 0.1)
		(layers "F.Cu" "B.Cu")
		(net 404)
	)
	(segment
		(start 135.376501 186.301)
		(end 134.877001 186.8005)
		(width 0.256)
		(layer "F.Cu")
		(net 405)
	)
	(via
		(at 134.877001 186.8005)
		(size 0.45)
		(drill 0.1)
		(layers "F.Cu" "B.Cu")
		(net 405)
	)
	(segment
		(start 133.376501 186.301)
		(end 132.877001 186.8005)
		(width 0.256)
		(layer "F.Cu")
		(net 406)
	)
	(via
		(at 132.877001 186.8005)
		(size 0.45)
		(drill 0.1)
		(layers "F.Cu" "B.Cu")
		(net 406)
	)
	(segment
		(start 141.375501 185.301)
		(end 141.875001 185.8005)
		(width 0.256)
		(layer "F.Cu")
		(net 407)
	)
	(via
		(at 141.875001 185.8005)
		(size 0.45)
		(drill 0.1)
		(layers "F.Cu" "B.Cu")
		(net 407)
	)
	(segment
		(start 139.375501 185.301)
		(end 139.875001 185.8005)
		(width 0.256)
		(layer "F.Cu")
		(net 408)
	)
	(via
		(at 139.875001 185.8005)
		(size 0.45)
		(drill 0.1)
		(layers "F.Cu" "B.Cu")
		(net 408)
	)
	(segment
		(start 138.376501 185.300999)
		(end 137.877001 185.8005)
		(width 0.256)
		(layer "F.Cu")
		(net 409)
	)
	(via
		(at 137.877001 185.8005)
		(size 0.45)
		(drill 0.1)
		(layers "F.Cu" "B.Cu")
		(net 409)
	)
	(segment
		(start 136.376501 185.301)
		(end 135.877001 185.8005)
		(width 0.256)
		(layer "F.Cu")
		(net 410)
	)
	(via
		(at 135.877001 185.8005)
		(size 0.45)
		(drill 0.1)
		(layers "F.Cu" "B.Cu")
		(net 410)
	)
	(segment
		(start 135.376501 185.301)
		(end 134.877001 185.8005)
		(width 0.256)
		(layer "F.Cu")
		(net 411)
	)
	(via
		(at 134.877001 185.8005)
		(size 0.45)
		(drill 0.1)
		(layers "F.Cu" "B.Cu")
		(net 411)
	)
	(segment
		(start 134.376501 185.301)
		(end 133.877001 185.8005)
		(width 0.256)
		(layer "F.Cu")
		(net 412)
	)
	(via
		(at 133.877001 185.8005)
		(size 0.45)
		(drill 0.1)
		(layers "F.Cu" "B.Cu")
		(net 412)
	)
	(segment
		(start 133.376501 185.300999)
		(end 132.877001 185.8005)
		(width 0.256)
		(layer "F.Cu")
		(net 413)
	)
	(via
		(at 132.877001 185.8005)
		(size 0.45)
		(drill 0.1)
		(layers "F.Cu" "B.Cu")
		(net 413)
	)
	(segment
		(start 141.375501 184.301)
		(end 141.875002 184.8005)
		(width 0.256)
		(layer "F.Cu")
		(net 414)
	)
	(via
		(at 141.875002 184.8005)
		(size 0.45)
		(drill 0.1)
		(layers "F.Cu" "B.Cu")
		(net 414)
	)
	(segment
		(start 139.375501 184.301)
		(end 139.875001 184.8005)
		(width 0.256)
		(layer "F.Cu")
		(net 415)
	)
	(via
		(at 139.875001 184.8005)
		(size 0.45)
		(drill 0.1)
		(layers "F.Cu" "B.Cu")
		(net 415)
	)
	(segment
		(start 138.376501 184.301001)
		(end 137.877002 184.8005)
		(width 0.256)
		(layer "F.Cu")
		(net 416)
	)
	(via
		(at 137.877002 184.8005)
		(size 0.45)
		(drill 0.1)
		(layers "F.Cu" "B.Cu")
		(net 416)
	)
	(segment
		(start 137.376501 184.301)
		(end 136.877001 184.8005)
		(width 0.256)
		(layer "F.Cu")
		(net 417)
	)
	(via
		(at 136.877001 184.8005)
		(size 0.45)
		(drill 0.1)
		(layers "F.Cu" "B.Cu")
		(net 417)
	)
	(segment
		(start 136.376501 184.301)
		(end 135.877001 184.8005)
		(width 0.256)
		(layer "F.Cu")
		(net 418)
	)
	(via
		(at 135.877001 184.8005)
		(size 0.45)
		(drill 0.1)
		(layers "F.Cu" "B.Cu")
		(net 418)
	)
	(segment
		(start 134.376501 184.301)
		(end 133.877001 184.800499)
		(width 0.256)
		(layer "F.Cu")
		(net 419)
	)
	(via
		(at 133.877001 184.800499)
		(size 0.45)
		(drill 0.1)
		(layers "F.Cu" "B.Cu")
		(net 419)
	)
	(segment
		(start 133.376501 184.301001)
		(end 132.877001 184.8005)
		(width 0.256)
		(layer "F.Cu")
		(net 420)
	)
	(via
		(at 132.877001 184.8005)
		(size 0.45)
		(drill 0.1)
		(layers "F.Cu" "B.Cu")
		(net 420)
	)
	(segment
		(start 132.376501 184.301)
		(end 131.877001 184.8005)
		(width 0.256)
		(layer "F.Cu")
		(net 421)
	)
	(via
		(at 131.877001 184.8005)
		(size 0.45)
		(drill 0.1)
		(layers "F.Cu" "B.Cu")
		(net 421)
	)
	(segment
		(start 141.375501 183.301)
		(end 141.875001 183.8005)
		(width 0.256)
		(layer "F.Cu")
		(net 422)
	)
	(via
		(at 141.875001 183.8005)
		(size 0.45)
		(drill 0.1)
		(layers "F.Cu" "B.Cu")
		(net 422)
	)
	(segment
		(start 140.375501 183.301)
		(end 140.875001 183.8005)
		(width 0.256)
		(layer "F.Cu")
		(net 423)
	)
	(via
		(at 140.875001 183.8005)
		(size 0.45)
		(drill 0.1)
		(layers "F.Cu" "B.Cu")
		(net 423)
	)
	(segment
		(start 139.375501 183.301)
		(end 139.875001 183.8005)
		(width 0.256)
		(layer "F.Cu")
		(net 424)
	)
	(via
		(at 139.875001 183.8005)
		(size 0.45)
		(drill 0.1)
		(layers "F.Cu" "B.Cu")
		(net 424)
	)
	(segment
		(start 137.376501 183.301)
		(end 136.877001 183.8005)
		(width 0.256)
		(layer "F.Cu")
		(net 425)
	)
	(via
		(at 136.877001 183.8005)
		(size 0.45)
		(drill 0.1)
		(layers "F.Cu" "B.Cu")
		(net 425)
	)
	(segment
		(start 136.376501 183.301)
		(end 135.877001 183.8005)
		(width 0.256)
		(layer "F.Cu")
		(net 426)
	)
	(via
		(at 135.877001 183.8005)
		(size 0.45)
		(drill 0.1)
		(layers "F.Cu" "B.Cu")
		(net 426)
	)
	(segment
		(start 135.376501 183.301)
		(end 134.877001 183.8005)
		(width 0.256)
		(layer "F.Cu")
		(net 427)
	)
	(via
		(at 134.877001 183.8005)
		(size 0.45)
		(drill 0.1)
		(layers "F.Cu" "B.Cu")
		(net 427)
	)
	(segment
		(start 134.376501 183.301)
		(end 133.877001 183.8005)
		(width 0.256)
		(layer "F.Cu")
		(net 428)
	)
	(via
		(at 133.877001 183.8005)
		(size 0.45)
		(drill 0.1)
		(layers "F.Cu" "B.Cu")
		(net 428)
	)
	(segment
		(start 132.376501 183.301)
		(end 131.877001 183.8005)
		(width 0.256)
		(layer "F.Cu")
		(net 429)
	)
	(via
		(at 131.877001 183.8005)
		(size 0.45)
		(drill 0.1)
		(layers "F.Cu" "B.Cu")
		(net 429)
	)
	(segment
		(start 129.376501 183.301)
		(end 128.877001 183.8005)
		(width 0.256)
		(layer "F.Cu")
		(net 430)
	)
	(via
		(at 128.877001 183.8005)
		(size 0.45)
		(drill 0.1)
		(layers "F.Cu" "B.Cu")
		(net 430)
	)
	(segment
		(start 147.875001 182.8005)
		(end 147.375501 182.301)
		(width 0.256)
		(layer "F.Cu")
		(net 431)
	)
	(via
		(at 147.875001 182.8005)
		(size 0.45)
		(drill 0.1)
		(layers "F.Cu" "B.Cu")
		(net 431)
	)
	(segment
		(start 146.875001 182.8005)
		(end 146.375501 182.301)
		(width 0.256)
		(layer "F.Cu")
		(net 432)
	)
	(via
		(at 146.875001 182.8005)
		(size 0.45)
		(drill 0.1)
		(layers "F.Cu" "B.Cu")
		(net 432)
	)
	(segment
		(start 142.375501 182.301)
		(end 142.875001 182.8005)
		(width 0.256)
		(layer "F.Cu")
		(net 433)
	)
	(via
		(at 142.875001 182.8005)
		(size 0.45)
		(drill 0.1)
		(layers "F.Cu" "B.Cu")
		(net 433)
	)
	(segment
		(start 140.3755 182.301)
		(end 140.875001 182.8005)
		(width 0.256)
		(layer "F.Cu")
		(net 434)
	)
	(via
		(at 140.875001 182.8005)
		(size 0.45)
		(drill 0.1)
		(layers "F.Cu" "B.Cu")
		(net 434)
	)
	(segment
		(start 139.375502 182.301)
		(end 139.875001 182.800499)
		(width 0.256)
		(layer "F.Cu")
		(net 435)
	)
	(via
		(at 139.875001 182.800499)
		(size 0.45)
		(drill 0.1)
		(layers "F.Cu" "B.Cu")
		(net 435)
	)
	(segment
		(start 138.376501 182.301)
		(end 137.877001 182.8005)
		(width 0.256)
		(layer "F.Cu")
		(net 436)
	)
	(via
		(at 137.877001 182.8005)
		(size 0.45)
		(drill 0.1)
		(layers "F.Cu" "B.Cu")
		(net 436)
	)
	(segment
		(start 137.376501 182.301)
		(end 136.877001 182.8005)
		(width 0.256)
		(layer "F.Cu")
		(net 437)
	)
	(via
		(at 136.877001 182.8005)
		(size 0.45)
		(drill 0.1)
		(layers "F.Cu" "B.Cu")
		(net 437)
	)
	(segment
		(start 135.376502 182.301)
		(end 134.877001 182.8005)
		(width 0.256)
		(layer "F.Cu")
		(net 438)
	)
	(via
		(at 134.877001 182.8005)
		(size 0.45)
		(drill 0.1)
		(layers "F.Cu" "B.Cu")
		(net 438)
	)
	(segment
		(start 134.376501 182.301)
		(end 133.877001 182.8005)
		(width 0.256)
		(layer "F.Cu")
		(net 439)
	)
	(via
		(at 133.877001 182.8005)
		(size 0.45)
		(drill 0.1)
		(layers "F.Cu" "B.Cu")
		(net 439)
	)
	(segment
		(start 133.376501 182.301)
		(end 132.877001 182.8005)
		(width 0.256)
		(layer "F.Cu")
		(net 440)
	)
	(via
		(at 132.877001 182.8005)
		(size 0.45)
		(drill 0.1)
		(layers "F.Cu" "B.Cu")
		(net 440)
	)
	(segment
		(start 132.376501 182.301)
		(end 131.877001 182.800499)
		(width 0.256)
		(layer "F.Cu")
		(net 441)
	)
	(via
		(at 131.877001 182.800499)
		(size 0.45)
		(drill 0.1)
		(layers "F.Cu" "B.Cu")
		(net 441)
	)
	(segment
		(start 130.376501 182.301)
		(end 129.877001 182.8005)
		(width 0.256)
		(layer "F.Cu")
		(net 442)
	)
	(via
		(at 129.877001 182.8005)
		(size 0.45)
		(drill 0.1)
		(layers "F.Cu" "B.Cu")
		(net 442)
	)
	(segment
		(start 128.376501 182.301)
		(end 127.877001 182.8005)
		(width 0.256)
		(layer "F.Cu")
		(net 443)
	)
	(via
		(at 127.877001 182.8005)
		(size 0.45)
		(drill 0.1)
		(layers "F.Cu" "B.Cu")
		(net 443)
	)
	(segment
		(start 143.375501 181.301)
		(end 143.875001 181.800501)
		(width 0.256)
		(layer "F.Cu")
		(net 444)
	)
	(via
		(at 143.875001 181.800501)
		(size 0.45)
		(drill 0.1)
		(layers "F.Cu" "B.Cu")
		(net 444)
	)
	(segment
		(start 142.375501 181.301)
		(end 142.875001 181.8005)
		(width 0.256)
		(layer "F.Cu")
		(net 445)
	)
	(via
		(at 142.875001 181.8005)
		(size 0.45)
		(drill 0.1)
		(layers "F.Cu" "B.Cu")
		(net 445)
	)
	(segment
		(start 141.375501 181.301)
		(end 141.875001 181.8005)
		(width 0.256)
		(layer "F.Cu")
		(net 446)
	)
	(via
		(at 141.875001 181.8005)
		(size 0.45)
		(drill 0.1)
		(layers "F.Cu" "B.Cu")
		(net 446)
	)
	(segment
		(start 140.375501 181.301)
		(end 140.875001 181.8005)
		(width 0.256)
		(layer "F.Cu")
		(net 447)
	)
	(via
		(at 140.875001 181.8005)
		(size 0.45)
		(drill 0.1)
		(layers "F.Cu" "B.Cu")
		(net 447)
	)
	(segment
		(start 138.376501 181.301)
		(end 137.877001 181.8005)
		(width 0.256)
		(layer "F.Cu")
		(net 448)
	)
	(via
		(at 137.877001 181.8005)
		(size 0.45)
		(drill 0.1)
		(layers "F.Cu" "B.Cu")
		(net 448)
	)
	(segment
		(start 137.376501 181.301)
		(end 136.877001 181.8005)
		(width 0.256)
		(layer "F.Cu")
		(net 449)
	)
	(via
		(at 136.877001 181.8005)
		(size 0.45)
		(drill 0.1)
		(layers "F.Cu" "B.Cu")
		(net 449)
	)
	(segment
		(start 136.376501 181.301)
		(end 135.877001 181.800501)
		(width 0.256)
		(layer "F.Cu")
		(net 450)
	)
	(via
		(at 135.877001 181.800501)
		(size 0.45)
		(drill 0.1)
		(layers "F.Cu" "B.Cu")
		(net 450)
	)
	(segment
		(start 135.376501 181.301)
		(end 134.877001 181.8005)
		(width 0.256)
		(layer "F.Cu")
		(net 451)
	)
	(via
		(at 134.877001 181.8005)
		(size 0.45)
		(drill 0.1)
		(layers "F.Cu" "B.Cu")
		(net 451)
	)
	(segment
		(start 133.376501 181.301)
		(end 132.877001 181.8005)
		(width 0.256)
		(layer "F.Cu")
		(net 452)
	)
	(via
		(at 132.877001 181.8005)
		(size 0.45)
		(drill 0.1)
		(layers "F.Cu" "B.Cu")
		(net 452)
	)
	(segment
		(start 132.376501 181.301)
		(end 131.877001 181.800501)
		(width 0.256)
		(layer "F.Cu")
		(net 453)
	)
	(via
		(at 131.877001 181.800501)
		(size 0.45)
		(drill 0.1)
		(layers "F.Cu" "B.Cu")
		(net 453)
	)
	(segment
		(start 131.376501 181.301)
		(end 130.877001 181.8005)
		(width 0.256)
		(layer "F.Cu")
		(net 454)
	)
	(via
		(at 130.877001 181.8005)
		(size 0.45)
		(drill 0.1)
		(layers "F.Cu" "B.Cu")
		(net 454)
	)
	(segment
		(start 130.376501 181.301)
		(end 129.877001 181.8005)
		(width 0.256)
		(layer "F.Cu")
		(net 455)
	)
	(via
		(at 129.877001 181.8005)
		(size 0.45)
		(drill 0.1)
		(layers "F.Cu" "B.Cu")
		(net 455)
	)
	(segment
		(start 151.875001 180.8005)
		(end 151.375501 180.301)
		(width 0.256)
		(layer "F.Cu")
		(net 456)
	)
	(via
		(at 151.875001 180.8005)
		(size 0.45)
		(drill 0.1)
		(layers "F.Cu" "B.Cu")
		(net 456)
	)
	(segment
		(start 150.875002 180.8005)
		(end 150.375501 180.301)
		(width 0.256)
		(layer "F.Cu")
		(net 457)
	)
	(via
		(at 150.875002 180.8005)
		(size 0.45)
		(drill 0.1)
		(layers "F.Cu" "B.Cu")
		(net 457)
	)
	(segment
		(start 147.875001 180.8005)
		(end 147.3755 180.301)
		(width 0.256)
		(layer "F.Cu")
		(net 458)
	)
	(via
		(at 147.875001 180.8005)
		(size 0.45)
		(drill 0.1)
		(layers "F.Cu" "B.Cu")
		(net 458)
	)
	(segment
		(start 146.875001 180.8005)
		(end 146.375502 180.301)
		(width 0.256)
		(layer "F.Cu")
		(net 459)
	)
	(via
		(at 146.875001 180.8005)
		(size 0.45)
		(drill 0.1)
		(layers "F.Cu" "B.Cu")
		(net 459)
	)
	(segment
		(start 144.375501 180.301)
		(end 144.875001 180.8005)
		(width 0.256)
		(layer "F.Cu")
		(net 460)
	)
	(via
		(at 144.875001 180.8005)
		(size 0.45)
		(drill 0.1)
		(layers "F.Cu" "B.Cu")
		(net 460)
	)
	(segment
		(start 143.375501 180.301)
		(end 143.875001 180.8005)
		(width 0.256)
		(layer "F.Cu")
		(net 461)
	)
	(via
		(at 143.875001 180.8005)
		(size 0.45)
		(drill 0.1)
		(layers "F.Cu" "B.Cu")
		(net 461)
	)
	(segment
		(start 141.375501 180.301)
		(end 141.875001 180.8005)
		(width 0.256)
		(layer "F.Cu")
		(net 462)
	)
	(via
		(at 141.875001 180.8005)
		(size 0.45)
		(drill 0.1)
		(layers "F.Cu" "B.Cu")
		(net 462)
	)
	(segment
		(start 140.375501 180.301)
		(end 140.875001 180.8005)
		(width 0.256)
		(layer "F.Cu")
		(net 463)
	)
	(via
		(at 140.875001 180.8005)
		(size 0.45)
		(drill 0.1)
		(layers "F.Cu" "B.Cu")
		(net 463)
	)
	(segment
		(start 139.375501 180.301)
		(end 139.875001 180.8005)
		(width 0.256)
		(layer "F.Cu")
		(net 464)
	)
	(via
		(at 139.875001 180.8005)
		(size 0.45)
		(drill 0.1)
		(layers "F.Cu" "B.Cu")
		(net 464)
	)
	(segment
		(start 138.3765 180.301)
		(end 137.877001 180.8005)
		(width 0.256)
		(layer "F.Cu")
		(net 465)
	)
	(via
		(at 137.877001 180.8005)
		(size 0.45)
		(drill 0.1)
		(layers "F.Cu" "B.Cu")
		(net 465)
	)
	(segment
		(start 136.376501 180.301)
		(end 135.877001 180.8005)
		(width 0.256)
		(layer "F.Cu")
		(net 466)
	)
	(via
		(at 135.877001 180.8005)
		(size 0.45)
		(drill 0.1)
		(layers "F.Cu" "B.Cu")
		(net 466)
	)
	(segment
		(start 135.376501 180.301)
		(end 134.877001 180.8005)
		(width 0.256)
		(layer "F.Cu")
		(net 467)
	)
	(via
		(at 134.877001 180.8005)
		(size 0.45)
		(drill 0.1)
		(layers "F.Cu" "B.Cu")
		(net 467)
	)
	(segment
		(start 134.376501 180.301)
		(end 133.877001 180.8005)
		(width 0.256)
		(layer "F.Cu")
		(net 468)
	)
	(via
		(at 133.877001 180.8005)
		(size 0.45)
		(drill 0.1)
		(layers "F.Cu" "B.Cu")
		(net 468)
	)
	(segment
		(start 133.376502 180.301)
		(end 132.877001 180.8005)
		(width 0.256)
		(layer "F.Cu")
		(net 469)
	)
	(via
		(at 132.877001 180.8005)
		(size 0.45)
		(drill 0.1)
		(layers "F.Cu" "B.Cu")
		(net 469)
	)
	(segment
		(start 129.3765 180.301)
		(end 128.877001 180.8005)
		(width 0.256)
		(layer "F.Cu")
		(net 470)
	)
	(via
		(at 128.877001 180.8005)
		(size 0.45)
		(drill 0.1)
		(layers "F.Cu" "B.Cu")
		(net 470)
	)
	(segment
		(start 128.376501 180.301)
		(end 127.877001 180.8005)
		(width 0.256)
		(layer "F.Cu")
		(net 471)
	)
	(via
		(at 127.877001 180.8005)
		(size 0.45)
		(drill 0.1)
		(layers "F.Cu" "B.Cu")
		(net 471)
	)
	(segment
		(start 126.376501 180.301)
		(end 125.877001 180.8005)
		(width 0.256)
		(layer "F.Cu")
		(net 472)
	)
	(via
		(at 125.877001 180.8005)
		(size 0.45)
		(drill 0.1)
		(layers "F.Cu" "B.Cu")
		(net 472)
	)
	(segment
		(start 149.875001 179.8005)
		(end 149.375501 179.301)
		(width 0.256)
		(layer "F.Cu")
		(net 473)
	)
	(via
		(at 149.875001 179.8005)
		(size 0.45)
		(drill 0.1)
		(layers "F.Cu" "B.Cu")
		(net 473)
	)
	(segment
		(start 148.875001 179.8005)
		(end 148.375501 179.301)
		(width 0.256)
		(layer "F.Cu")
		(net 474)
	)
	(via
		(at 148.875001 179.8005)
		(size 0.45)
		(drill 0.1)
		(layers "F.Cu" "B.Cu")
		(net 474)
	)
	(segment
		(start 144.375501 179.301)
		(end 144.875001 179.8005)
		(width 0.256)
		(layer "F.Cu")
		(net 475)
	)
	(via
		(at 144.875001 179.8005)
		(size 0.45)
		(drill 0.1)
		(layers "F.Cu" "B.Cu")
		(net 475)
	)
	(segment
		(start 142.375501 179.301)
		(end 142.875001 179.8005)
		(width 0.256)
		(layer "F.Cu")
		(net 476)
	)
	(via
		(at 142.875001 179.8005)
		(size 0.45)
		(drill 0.1)
		(layers "F.Cu" "B.Cu")
		(net 476)
	)
	(segment
		(start 141.375501 179.301)
		(end 141.875001 179.800501)
		(width 0.256)
		(layer "F.Cu")
		(net 477)
	)
	(via
		(at 141.875001 179.800501)
		(size 0.45)
		(drill 0.1)
		(layers "F.Cu" "B.Cu")
		(net 477)
	)
	(segment
		(start 139.375501 179.301)
		(end 139.875001 179.8005)
		(width 0.256)
		(layer "F.Cu")
		(net 478)
	)
	(via
		(at 139.875001 179.8005)
		(size 0.45)
		(drill 0.1)
		(layers "F.Cu" "B.Cu")
		(net 478)
	)
	(segment
		(start 138.376501 179.301)
		(end 137.877002 179.8005)
		(width 0.256)
		(layer "F.Cu")
		(net 479)
	)
	(via
		(at 137.877002 179.8005)
		(size 0.45)
		(drill 0.1)
		(layers "F.Cu" "B.Cu")
		(net 479)
	)
	(segment
		(start 137.376501 179.301)
		(end 136.877001 179.8005)
		(width 0.256)
		(layer "F.Cu")
		(net 480)
	)
	(via
		(at 136.877001 179.8005)
		(size 0.45)
		(drill 0.1)
		(layers "F.Cu" "B.Cu")
		(net 480)
	)
	(segment
		(start 136.376501 179.301)
		(end 135.877001 179.8005)
		(width 0.256)
		(layer "F.Cu")
		(net 481)
	)
	(via
		(at 135.877001 179.8005)
		(size 0.45)
		(drill 0.1)
		(layers "F.Cu" "B.Cu")
		(net 481)
	)
	(segment
		(start 134.376501 179.301)
		(end 133.877001 179.800501)
		(width 0.256)
		(layer "F.Cu")
		(net 482)
	)
	(via
		(at 133.877001 179.800501)
		(size 0.45)
		(drill 0.1)
		(layers "F.Cu" "B.Cu")
		(net 482)
	)
	(segment
		(start 133.376501 179.301)
		(end 132.877001 179.8005)
		(width 0.256)
		(layer "F.Cu")
		(net 483)
	)
	(via
		(at 132.877001 179.8005)
		(size 0.45)
		(drill 0.1)
		(layers "F.Cu" "B.Cu")
		(net 483)
	)
	(segment
		(start 132.376501 179.301)
		(end 131.877001 179.8005)
		(width 0.256)
		(layer "F.Cu")
		(net 484)
	)
	(via
		(at 131.877001 179.8005)
		(size 0.45)
		(drill 0.1)
		(layers "F.Cu" "B.Cu")
		(net 484)
	)
	(segment
		(start 131.376501 179.301)
		(end 130.877001 179.8005)
		(width 0.256)
		(layer "F.Cu")
		(net 485)
	)
	(via
		(at 130.877001 179.8005)
		(size 0.45)
		(drill 0.1)
		(layers "F.Cu" "B.Cu")
		(net 485)
	)
	(segment
		(start 129.376501 179.301)
		(end 128.877002 179.8005)
		(width 0.256)
		(layer "F.Cu")
		(net 486)
	)
	(via
		(at 128.877002 179.8005)
		(size 0.45)
		(drill 0.1)
		(layers "F.Cu" "B.Cu")
		(net 486)
	)
	(segment
		(start 128.376501 179.301)
		(end 127.877001 179.8005)
		(width 0.256)
		(layer "F.Cu")
		(net 487)
	)
	(via
		(at 127.877001 179.8005)
		(size 0.45)
		(drill 0.1)
		(layers "F.Cu" "B.Cu")
		(net 487)
	)
	(segment
		(start 127.376501 179.301)
		(end 126.877001 179.8005)
		(width 0.256)
		(layer "F.Cu")
		(net 488)
	)
	(via
		(at 126.877001 179.8005)
		(size 0.45)
		(drill 0.1)
		(layers "F.Cu" "B.Cu")
		(net 488)
	)
	(segment
		(start 126.376501 179.301)
		(end 125.877001 179.8005)
		(width 0.256)
		(layer "F.Cu")
		(net 489)
	)
	(via
		(at 125.877001 179.8005)
		(size 0.45)
		(drill 0.1)
		(layers "F.Cu" "B.Cu")
		(net 489)
	)
	(segment
		(start 150.875002 178.8005)
		(end 150.375501 178.301)
		(width 0.256)
		(layer "F.Cu")
		(net 491)
	)
	(via
		(at 150.875002 178.8005)
		(size 0.45)
		(drill 0.1)
		(layers "F.Cu" "B.Cu")
		(net 491)
	)
	(segment
		(start 147.875001 178.8005)
		(end 147.375501 178.301)
		(width 0.256)
		(layer "F.Cu")
		(net 492)
	)
	(via
		(at 147.875001 178.8005)
		(size 0.45)
		(drill 0.1)
		(layers "F.Cu" "B.Cu")
		(net 492)
	)
	(segment
		(start 146.875001 178.8005)
		(end 146.375501 178.301)
		(width 0.256)
		(layer "F.Cu")
		(net 493)
	)
	(via
		(at 146.875001 178.8005)
		(size 0.45)
		(drill 0.1)
		(layers "F.Cu" "B.Cu")
		(net 493)
	)
	(segment
		(start 137.376501 178.301)
		(end 136.877001 178.8005)
		(width 0.256)
		(layer "F.Cu")
		(net 494)
	)
	(via
		(at 136.877001 178.8005)
		(size 0.45)
		(drill 0.1)
		(layers "F.Cu" "B.Cu")
		(net 494)
	)
	(segment
		(start 136.3765 178.301)
		(end 135.877001 178.8005)
		(width 0.256)
		(layer "F.Cu")
		(net 495)
	)
	(via
		(at 135.877001 178.8005)
		(size 0.45)
		(drill 0.1)
		(layers "F.Cu" "B.Cu")
		(net 495)
	)
	(segment
		(start 135.376502 178.301)
		(end 134.877001 178.8005)
		(width 0.256)
		(layer "F.Cu")
		(net 496)
	)
	(via
		(at 134.877001 178.8005)
		(size 0.45)
		(drill 0.1)
		(layers "F.Cu" "B.Cu")
		(net 496)
	)
	(segment
		(start 134.376501 178.301)
		(end 133.877001 178.8005)
		(width 0.256)
		(layer "F.Cu")
		(net 497)
	)
	(via
		(at 133.877001 178.8005)
		(size 0.45)
		(drill 0.1)
		(layers "F.Cu" "B.Cu")
		(net 497)
	)
	(segment
		(start 132.376501 178.301)
		(end 131.877001 178.8005)
		(width 0.256)
		(layer "F.Cu")
		(net 498)
	)
	(via
		(at 131.877001 178.8005)
		(size 0.45)
		(drill 0.1)
		(layers "F.Cu" "B.Cu")
		(net 498)
	)
	(segment
		(start 131.376501 178.300999)
		(end 130.877001 178.8005)
		(width 0.256)
		(layer "F.Cu")
		(net 499)
	)
	(via
		(at 130.877001 178.8005)
		(size 0.45)
		(drill 0.1)
		(layers "F.Cu" "B.Cu")
		(net 499)
	)
	(segment
		(start 130.376501 178.301)
		(end 129.877001 178.8005)
		(width 0.256)
		(layer "F.Cu")
		(net 500)
	)
	(via
		(at 129.877001 178.8005)
		(size 0.45)
		(drill 0.1)
		(layers "F.Cu" "B.Cu")
		(net 500)
	)
	(segment
		(start 129.376501 178.301)
		(end 128.877001 178.8005)
		(width 0.256)
		(layer "F.Cu")
		(net 501)
	)
	(via
		(at 128.877001 178.8005)
		(size 0.45)
		(drill 0.1)
		(layers "F.Cu" "B.Cu")
		(net 501)
	)
	(segment
		(start 127.3765 178.301)
		(end 126.877001 178.8005)
		(width 0.256)
		(layer "F.Cu")
		(net 502)
	)
	(via
		(at 126.877001 178.8005)
		(size 0.45)
		(drill 0.1)
		(layers "F.Cu" "B.Cu")
		(net 502)
	)
	(segment
		(start 126.376502 178.301)
		(end 125.877001 178.8005)
		(width 0.256)
		(layer "F.Cu")
		(net 503)
	)
	(via
		(at 125.877001 178.8005)
		(size 0.45)
		(drill 0.1)
		(layers "F.Cu" "B.Cu")
		(net 503)
	)
	(segment
		(start 149.875001 177.8005)
		(end 149.375501 177.301)
		(width 0.256)
		(layer "F.Cu")
		(net 504)
	)
	(via
		(at 149.875001 177.8005)
		(size 0.45)
		(drill 0.1)
		(layers "F.Cu" "B.Cu")
		(net 504)
	)
	(segment
		(start 148.875002 177.8005)
		(end 148.375501 177.301)
		(width 0.256)
		(layer "F.Cu")
		(net 505)
	)
	(via
		(at 148.875002 177.8005)
		(size 0.45)
		(drill 0.1)
		(layers "F.Cu" "B.Cu")
		(net 505)
	)
	(segment
		(start 135.376501 177.301)
		(end 134.877001 177.8005)
		(width 0.256)
		(layer "F.Cu")
		(net 506)
	)
	(via
		(at 134.877001 177.8005)
		(size 0.45)
		(drill 0.1)
		(layers "F.Cu" "B.Cu")
		(net 506)
	)
	(segment
		(start 134.376501 177.301)
		(end 133.877001 177.8005)
		(width 0.256)
		(layer "F.Cu")
		(net 507)
	)
	(via
		(at 133.877001 177.8005)
		(size 0.45)
		(drill 0.1)
		(layers "F.Cu" "B.Cu")
		(net 507)
	)
	(segment
		(start 133.376501 177.301)
		(end 132.877001 177.8005)
		(width 0.256)
		(layer "F.Cu")
		(net 508)
	)
	(via
		(at 132.877001 177.8005)
		(size 0.45)
		(drill 0.1)
		(layers "F.Cu" "B.Cu")
		(net 508)
	)
	(segment
		(start 132.376501 177.301)
		(end 131.877 177.8005)
		(width 0.256)
		(layer "F.Cu")
		(net 509)
	)
	(via
		(at 131.877 177.8005)
		(size 0.45)
		(drill 0.1)
		(layers "F.Cu" "B.Cu")
		(net 509)
	)
	(segment
		(start 130.376501 177.301)
		(end 129.877001 177.8005)
		(width 0.256)
		(layer "F.Cu")
		(net 510)
	)
	(via
		(at 129.877001 177.8005)
		(size 0.45)
		(drill 0.1)
		(layers "F.Cu" "B.Cu")
		(net 510)
	)
	(segment
		(start 129.376501 177.301)
		(end 128.877001 177.8005)
		(width 0.256)
		(layer "F.Cu")
		(net 511)
	)
	(via
		(at 128.877001 177.8005)
		(size 0.45)
		(drill 0.1)
		(layers "F.Cu" "B.Cu")
		(net 511)
	)
	(segment
		(start 128.376501 177.301)
		(end 127.877001 177.8005)
		(width 0.256)
		(layer "F.Cu")
		(net 512)
	)
	(via
		(at 127.877001 177.8005)
		(size 0.45)
		(drill 0.1)
		(layers "F.Cu" "B.Cu")
		(net 512)
	)
	(segment
		(start 127.376501 177.301)
		(end 126.877002 177.8005)
		(width 0.256)
		(layer "F.Cu")
		(net 513)
	)
	(via
		(at 126.877002 177.8005)
		(size 0.45)
		(drill 0.1)
		(layers "F.Cu" "B.Cu")
		(net 513)
	)
	(segment
		(start 151.875001 176.8005)
		(end 151.375501 176.301)
		(width 0.256)
		(layer "F.Cu")
		(net 514)
	)
	(via
		(at 151.875001 176.8005)
		(size 0.45)
		(drill 0.1)
		(layers "F.Cu" "B.Cu")
		(net 514)
	)
	(segment
		(start 150.875002 176.8005)
		(end 150.375501 176.301)
		(width 0.256)
		(layer "F.Cu")
		(net 515)
	)
	(via
		(at 150.875002 176.8005)
		(size 0.45)
		(drill 0.1)
		(layers "F.Cu" "B.Cu")
		(net 515)
	)
	(segment
		(start 136.376501 176.301)
		(end 135.877001 176.8005)
		(width 0.256)
		(layer "F.Cu")
		(net 516)
	)
	(via
		(at 135.877001 176.8005)
		(size 0.45)
		(drill 0.1)
		(layers "F.Cu" "B.Cu")
		(net 516)
	)
	(segment
		(start 135.376501 176.301)
		(end 134.877001 176.8005)
		(width 0.256)
		(layer "F.Cu")
		(net 517)
	)
	(via
		(at 134.877001 176.8005)
		(size 0.45)
		(drill 0.1)
		(layers "F.Cu" "B.Cu")
		(net 517)
	)
	(segment
		(start 133.376501 176.300999)
		(end 132.877001 176.8005)
		(width 0.256)
		(layer "F.Cu")
		(net 518)
	)
	(via
		(at 132.877001 176.8005)
		(size 0.45)
		(drill 0.1)
		(layers "F.Cu" "B.Cu")
		(net 518)
	)
	(segment
		(start 132.376501 176.301)
		(end 131.877001 176.8005)
		(width 0.256)
		(layer "F.Cu")
		(net 519)
	)
	(via
		(at 131.877001 176.8005)
		(size 0.45)
		(drill 0.1)
		(layers "F.Cu" "B.Cu")
		(net 519)
	)
	(segment
		(start 131.376501 176.301)
		(end 130.877001 176.8005)
		(width 0.256)
		(layer "F.Cu")
		(net 520)
	)
	(via
		(at 130.877001 176.8005)
		(size 0.45)
		(drill 0.1)
		(layers "F.Cu" "B.Cu")
		(net 520)
	)
	(segment
		(start 130.376501 176.301)
		(end 129.877001 176.8005)
		(width 0.256)
		(layer "F.Cu")
		(net 521)
	)
	(via
		(at 129.877001 176.8005)
		(size 0.45)
		(drill 0.1)
		(layers "F.Cu" "B.Cu")
		(net 521)
	)
	(segment
		(start 128.376501 176.301)
		(end 127.877001 176.8005)
		(width 0.256)
		(layer "F.Cu")
		(net 522)
	)
	(via
		(at 127.877001 176.8005)
		(size 0.45)
		(drill 0.1)
		(layers "F.Cu" "B.Cu")
		(net 522)
	)
	(segment
		(start 127.376501 176.301)
		(end 126.877001 176.8005)
		(width 0.256)
		(layer "F.Cu")
		(net 523)
	)
	(via
		(at 126.877001 176.8005)
		(size 0.45)
		(drill 0.1)
		(layers "F.Cu" "B.Cu")
		(net 523)
	)
	(segment
		(start 126.376501 176.301)
		(end 125.877001 176.8005)
		(width 0.256)
		(layer "F.Cu")
		(net 524)
	)
	(via
		(at 125.877001 176.8005)
		(size 0.45)
		(drill 0.1)
		(layers "F.Cu" "B.Cu")
		(net 524)
	)
	(segment
		(start 149.875001 175.8005)
		(end 149.375501 175.301)
		(width 0.256)
		(layer "F.Cu")
		(net 525)
	)
	(via
		(at 149.875001 175.8005)
		(size 0.45)
		(drill 0.1)
		(layers "F.Cu" "B.Cu")
		(net 525)
	)
	(segment
		(start 148.875001 175.8005)
		(end 148.375501 175.301)
		(width 0.256)
		(layer "F.Cu")
		(net 526)
	)
	(via
		(at 148.875001 175.8005)
		(size 0.45)
		(drill 0.1)
		(layers "F.Cu" "B.Cu")
		(net 526)
	)
	(segment
		(start 136.376501 175.301)
		(end 135.877001 175.8005)
		(width 0.256)
		(layer "F.Cu")
		(net 527)
	)
	(via
		(at 135.877001 175.8005)
		(size 0.45)
		(drill 0.1)
		(layers "F.Cu" "B.Cu")
		(net 527)
	)
	(segment
		(start 135.376501 175.301)
		(end 134.877001 175.8005)
		(width 0.256)
		(layer "F.Cu")
		(net 528)
	)
	(via
		(at 134.877001 175.8005)
		(size 0.45)
		(drill 0.1)
		(layers "F.Cu" "B.Cu")
		(net 528)
	)
	(segment
		(start 134.376501 175.301)
		(end 133.877001 175.800499)
		(width 0.256)
		(layer "F.Cu")
		(net 529)
	)
	(via
		(at 133.877001 175.800499)
		(size 0.45)
		(drill 0.1)
		(layers "F.Cu" "B.Cu")
		(net 529)
	)
	(segment
		(start 133.376501 175.301001)
		(end 132.877001 175.8005)
		(width 0.256)
		(layer "F.Cu")
		(net 530)
	)
	(via
		(at 132.877001 175.8005)
		(size 0.45)
		(drill 0.1)
		(layers "F.Cu" "B.Cu")
		(net 530)
	)
	(segment
		(start 131.376501 175.301)
		(end 130.877001 175.8005)
		(width 0.256)
		(layer "F.Cu")
		(net 531)
	)
	(via
		(at 130.877001 175.8005)
		(size 0.45)
		(drill 0.1)
		(layers "F.Cu" "B.Cu")
		(net 531)
	)
	(segment
		(start 130.376501 175.301)
		(end 129.877 175.8005)
		(width 0.256)
		(layer "F.Cu")
		(net 532)
	)
	(via
		(at 129.877 175.8005)
		(size 0.45)
		(drill 0.1)
		(layers "F.Cu" "B.Cu")
		(net 532)
	)
	(segment
		(start 129.376501 175.301001)
		(end 128.877002 175.8005)
		(width 0.256)
		(layer "F.Cu")
		(net 533)
	)
	(via
		(at 128.877002 175.8005)
		(size 0.45)
		(drill 0.1)
		(layers "F.Cu" "B.Cu")
		(net 533)
	)
	(segment
		(start 128.376501 175.301)
		(end 127.877001 175.8005)
		(width 0.256)
		(layer "F.Cu")
		(net 534)
	)
	(via
		(at 127.877001 175.8005)
		(size 0.45)
		(drill 0.1)
		(layers "F.Cu" "B.Cu")
		(net 534)
	)
	(segment
		(start 126.376501 175.301)
		(end 125.877001 175.8005)
		(width 0.256)
		(layer "F.Cu")
		(net 535)
	)
	(via
		(at 125.877001 175.8005)
		(size 0.45)
		(drill 0.1)
		(layers "F.Cu" "B.Cu")
		(net 535)
	)
	(segment
		(start 151.875001 173.8025)
		(end 151.375501 174.302)
		(width 0.256)
		(layer "F.Cu")
		(net 536)
	)
	(via
		(at 151.875001 173.8025)
		(size 0.45)
		(drill 0.1)
		(layers "F.Cu" "B.Cu")
		(net 536)
	)
	(segment
		(start 150.875001 173.8025)
		(end 150.375501 174.302)
		(width 0.256)
		(layer "F.Cu")
		(net 537)
	)
	(via
		(at 150.875001 173.8025)
		(size 0.45)
		(drill 0.1)
		(layers "F.Cu" "B.Cu")
		(net 537)
	)
	(segment
		(start 136.3765 174.302)
		(end 135.877001 173.802501)
		(width 0.256)
		(layer "F.Cu")
		(net 538)
	)
	(via
		(at 135.877001 173.802501)
		(size 0.45)
		(drill 0.1)
		(layers "F.Cu" "B.Cu")
		(net 538)
	)
	(segment
		(start 134.376501 174.302)
		(end 133.877001 173.8025)
		(width 0.256)
		(layer "F.Cu")
		(net 539)
	)
	(via
		(at 133.877001 173.8025)
		(size 0.45)
		(drill 0.1)
		(layers "F.Cu" "B.Cu")
		(net 539)
	)
	(segment
		(start 133.376501 174.302)
		(end 132.877001 173.8025)
		(width 0.256)
		(layer "F.Cu")
		(net 540)
	)
	(via
		(at 132.877001 173.8025)
		(size 0.45)
		(drill 0.1)
		(layers "F.Cu" "B.Cu")
		(net 540)
	)
	(segment
		(start 132.376501 174.302)
		(end 131.877001 173.802501)
		(width 0.256)
		(layer "F.Cu")
		(net 541)
	)
	(via
		(at 131.877001 173.802501)
		(size 0.45)
		(drill 0.1)
		(layers "F.Cu" "B.Cu")
		(net 541)
	)
	(segment
		(start 131.376501 174.301999)
		(end 130.877001 173.8025)
		(width 0.256)
		(layer "F.Cu")
		(net 542)
	)
	(via
		(at 130.877001 173.8025)
		(size 0.45)
		(drill 0.1)
		(layers "F.Cu" "B.Cu")
		(net 542)
	)
	(segment
		(start 129.376501 174.302)
		(end 128.877001 173.8025)
		(width 0.256)
		(layer "F.Cu")
		(net 543)
	)
	(via
		(at 128.877001 173.8025)
		(size 0.45)
		(drill 0.1)
		(layers "F.Cu" "B.Cu")
		(net 543)
	)
	(segment
		(start 128.376501 174.302)
		(end 127.877001 173.8025)
		(width 0.256)
		(layer "F.Cu")
		(net 544)
	)
	(via
		(at 127.877001 173.8025)
		(size 0.45)
		(drill 0.1)
		(layers "F.Cu" "B.Cu")
		(net 544)
	)
	(segment
		(start 127.3765 174.302)
		(end 126.877001 173.802501)
		(width 0.256)
		(layer "F.Cu")
		(net 545)
	)
	(via
		(at 126.877001 173.802501)
		(size 0.45)
		(drill 0.1)
		(layers "F.Cu" "B.Cu")
		(net 545)
	)
	(segment
		(start 126.376502 174.302)
		(end 125.877001 173.8025)
		(width 0.256)
		(layer "F.Cu")
		(net 546)
	)
	(via
		(at 125.877001 173.8025)
		(size 0.45)
		(drill 0.1)
		(layers "F.Cu" "B.Cu")
		(net 546)
	)
	(segment
		(start 149.875001 172.8025)
		(end 149.375501 173.302001)
		(width 0.256)
		(layer "F.Cu")
		(net 547)
	)
	(via
		(at 149.875001 172.8025)
		(size 0.45)
		(drill 0.1)
		(layers "F.Cu" "B.Cu")
		(net 547)
	)
	(segment
		(start 148.875001 172.8025)
		(end 148.375501 173.302)
		(width 0.256)
		(layer "F.Cu")
		(net 548)
	)
	(via
		(at 148.875001 172.8025)
		(size 0.45)
		(drill 0.1)
		(layers "F.Cu" "B.Cu")
		(net 548)
	)
	(segment
		(start 136.376501 173.302001)
		(end 135.877001 172.8025)
		(width 0.256)
		(layer "F.Cu")
		(net 549)
	)
	(via
		(at 135.877001 172.8025)
		(size 0.45)
		(drill 0.1)
		(layers "F.Cu" "B.Cu")
		(net 549)
	)
	(segment
		(start 135.376501 173.302001)
		(end 134.877001 172.8025)
		(width 0.256)
		(layer "F.Cu")
		(net 550)
	)
	(via
		(at 134.877001 172.8025)
		(size 0.45)
		(drill 0.1)
		(layers "F.Cu" "B.Cu")
		(net 550)
	)
	(segment
		(start 134.376501 173.302)
		(end 133.877001 172.8025)
		(width 0.256)
		(layer "F.Cu")
		(net 551)
	)
	(via
		(at 133.877001 172.8025)
		(size 0.45)
		(drill 0.1)
		(layers "F.Cu" "B.Cu")
		(net 551)
	)
	(segment
		(start 132.376501 173.302)
		(end 131.877001 172.8025)
		(width 0.256)
		(layer "F.Cu")
		(net 552)
	)
	(via
		(at 131.877001 172.8025)
		(size 0.45)
		(drill 0.1)
		(layers "F.Cu" "B.Cu")
		(net 552)
	)
	(segment
		(start 131.376501 173.302001)
		(end 130.877001 172.8025)
		(width 0.256)
		(layer "F.Cu")
		(net 553)
	)
	(via
		(at 130.877001 172.8025)
		(size 0.45)
		(drill 0.1)
		(layers "F.Cu" "B.Cu")
		(net 553)
	)
	(segment
		(start 130.376501 173.302)
		(end 129.877001 172.8025)
		(width 0.256)
		(layer "F.Cu")
		(net 554)
	)
	(via
		(at 129.877001 172.8025)
		(size 0.45)
		(drill 0.1)
		(layers "F.Cu" "B.Cu")
		(net 554)
	)
	(segment
		(start 129.376501 173.302)
		(end 128.877001 172.8025)
		(width 0.256)
		(layer "F.Cu")
		(net 555)
	)
	(via
		(at 128.877001 172.8025)
		(size 0.45)
		(drill 0.1)
		(layers "F.Cu" "B.Cu")
		(net 555)
	)
	(segment
		(start 127.376501 173.302001)
		(end 126.877001 172.8025)
		(width 0.256)
		(layer "F.Cu")
		(net 556)
	)
	(via
		(at 126.877001 172.8025)
		(size 0.45)
		(drill 0.1)
		(layers "F.Cu" "B.Cu")
		(net 556)
	)
	(segment
		(start 126.376501 173.302001)
		(end 125.877001 172.8025)
		(width 0.256)
		(layer "F.Cu")
		(net 557)
	)
	(via
		(at 125.877001 172.8025)
		(size 0.45)
		(drill 0.1)
		(layers "F.Cu" "B.Cu")
		(net 557)
	)
	(segment
		(start 135.376501 172.302)
		(end 134.877001 171.8025)
		(width 0.256)
		(layer "F.Cu")
		(net 558)
	)
	(via
		(at 134.877001 171.8025)
		(size 0.45)
		(drill 0.1)
		(layers "F.Cu" "B.Cu")
		(net 558)
	)
	(segment
		(start 134.376501 172.302)
		(end 133.877001 171.802501)
		(width 0.256)
		(layer "F.Cu")
		(net 559)
	)
	(via
		(at 133.877001 171.802501)
		(size 0.45)
		(drill 0.1)
		(layers "F.Cu" "B.Cu")
		(net 559)
	)
	(segment
		(start 133.376501 172.301999)
		(end 132.877001 171.8025)
		(width 0.256)
		(layer "F.Cu")
		(net 560)
	)
	(via
		(at 132.877001 171.8025)
		(size 0.45)
		(drill 0.1)
		(layers "F.Cu" "B.Cu")
		(net 560)
	)
	(segment
		(start 132.376501 172.302)
		(end 131.877001 171.8025)
		(width 0.256)
		(layer "F.Cu")
		(net 561)
	)
	(via
		(at 131.877001 171.8025)
		(size 0.45)
		(drill 0.1)
		(layers "F.Cu" "B.Cu")
		(net 561)
	)
	(segment
		(start 130.376501 172.302)
		(end 129.877 171.8025)
		(width 0.256)
		(layer "F.Cu")
		(net 562)
	)
	(via
		(at 129.877 171.8025)
		(size 0.45)
		(drill 0.1)
		(layers "F.Cu" "B.Cu")
		(net 562)
	)
	(segment
		(start 129.376501 172.301999)
		(end 128.877002 171.8025)
		(width 0.256)
		(layer "F.Cu")
		(net 563)
	)
	(via
		(at 128.877002 171.8025)
		(size 0.45)
		(drill 0.1)
		(layers "F.Cu" "B.Cu")
		(net 563)
	)
	(segment
		(start 128.376501 172.302)
		(end 127.877001 171.8025)
		(width 0.256)
		(layer "F.Cu")
		(net 564)
	)
	(via
		(at 127.877001 171.8025)
		(size 0.45)
		(drill 0.1)
		(layers "F.Cu" "B.Cu")
		(net 564)
	)
	(segment
		(start 127.376501 172.302)
		(end 126.877001 171.8025)
		(width 0.256)
		(layer "F.Cu")
		(net 565)
	)
	(via
		(at 126.877001 171.8025)
		(size 0.45)
		(drill 0.1)
		(layers "F.Cu" "B.Cu")
		(net 565)
	)
	(segment
		(start 136.376501 171.302)
		(end 135.877001 170.8025)
		(width 0.256)
		(layer "F.Cu")
		(net 566)
	)
	(via
		(at 135.877001 170.8025)
		(size 0.45)
		(drill 0.1)
		(layers "F.Cu" "B.Cu")
		(net 566)
	)
	(segment
		(start 135.376501 171.302)
		(end 134.877001 170.8025)
		(width 0.256)
		(layer "F.Cu")
		(net 567)
	)
	(via
		(at 134.877001 170.8025)
		(size 0.45)
		(drill 0.1)
		(layers "F.Cu" "B.Cu")
		(net 567)
	)
	(segment
		(start 133.376501 171.302001)
		(end 132.877001 170.8025)
		(width 0.256)
		(layer "F.Cu")
		(net 568)
	)
	(via
		(at 132.877001 170.8025)
		(size 0.45)
		(drill 0.1)
		(layers "F.Cu" "B.Cu")
		(net 568)
	)
	(segment
		(start 132.376501 171.302)
		(end 131.877001 170.8025)
		(width 0.256)
		(layer "F.Cu")
		(net 569)
	)
	(via
		(at 131.877001 170.8025)
		(size 0.45)
		(drill 0.1)
		(layers "F.Cu" "B.Cu")
		(net 569)
	)
	(segment
		(start 131.376501 171.302)
		(end 130.877001 170.8025)
		(width 0.256)
		(layer "F.Cu")
		(net 570)
	)
	(via
		(at 130.877001 170.8025)
		(size 0.45)
		(drill 0.1)
		(layers "F.Cu" "B.Cu")
		(net 570)
	)
	(segment
		(start 78.087 156.3)
		(end 77.315 156.3)
		(width 0.15)
		(layer "F.Cu")
		(net 571)
	)
	(segment
		(start 78.087 154.302)
		(end 77.315 154.302)
		(width 0.15)
		(layer "F.Cu")
		(net 572)
	)
	(segment
		(start 130.376501 171.302)
		(end 129.877001 170.8025)
		(width 0.256)
		(layer "F.Cu")
		(net 573)
	)
	(via
		(at 129.877001 170.8025)
		(size 0.45)
		(drill 0.1)
		(layers "F.Cu" "B.Cu")
		(net 573)
	)
	(segment
		(start 128.376501 171.302)
		(end 127.877001 170.8025)
		(width 0.256)
		(layer "F.Cu")
		(net 574)
	)
	(via
		(at 127.877001 170.8025)
		(size 0.45)
		(drill 0.1)
		(layers "F.Cu" "B.Cu")
		(net 574)
	)
	(segment
		(start 131.376501 170.302)
		(end 130.877001 169.8025)
		(width 0.256)
		(layer "F.Cu")
		(net 575)
	)
	(via
		(at 130.877001 169.8025)
		(size 0.45)
		(drill 0.1)
		(layers "F.Cu" "B.Cu")
		(net 575)
	)
	(segment
		(start 130.376501 170.302)
		(end 129.877001 169.8025)
		(width 0.256)
		(layer "F.Cu")
		(net 576)
	)
	(via
		(at 129.877001 169.8025)
		(size 0.45)
		(drill 0.1)
		(layers "F.Cu" "B.Cu")
		(net 576)
	)
	(segment
		(start 129.376501 170.302)
		(end 128.877001 169.8025)
		(width 0.256)
		(layer "F.Cu")
		(net 577)
	)
	(via
		(at 128.877001 169.8025)
		(size 0.45)
		(drill 0.1)
		(layers "F.Cu" "B.Cu")
		(net 577)
	)
	(segment
		(start 128.376501 170.302)
		(end 127.877001 169.8025)
		(width 0.256)
		(layer "F.Cu")
		(net 578)
	)
	(via
		(at 127.877001 169.8025)
		(size 0.45)
		(drill 0.1)
		(layers "F.Cu" "B.Cu")
		(net 578)
	)
	(segment
		(start 132.376501 169.302)
		(end 131.877001 168.8025)
		(width 0.256)
		(layer "F.Cu")
		(net 579)
	)
	(via
		(at 131.877001 168.8025)
		(size 0.45)
		(drill 0.1)
		(layers "F.Cu" "B.Cu")
		(net 579)
	)
	(segment
		(start 131.376501 169.302001)
		(end 130.877001 168.8025)
		(width 0.256)
		(layer "F.Cu")
		(net 580)
	)
	(via
		(at 130.877001 168.8025)
		(size 0.45)
		(drill 0.1)
		(layers "F.Cu" "B.Cu")
		(net 580)
	)
	(segment
		(start 129.376501 169.302)
		(end 128.877001 168.8025)
		(width 0.256)
		(layer "F.Cu")
		(net 581)
	)
	(via
		(at 128.877001 168.8025)
		(size 0.45)
		(drill 0.1)
		(layers "F.Cu" "B.Cu")
		(net 581)
	)
	(segment
		(start 85.498 169.498)
		(end 86 170)
		(width 0.256)
		(layer "F.Cu")
		(net 582)
	)
	(segment
		(start 85.185 169.498)
		(end 84.413 169.498)
		(width 0.256)
		(layer "F.Cu")
		(net 582)
	)
	(segment
		(start 85.185 169.498)
		(end 85.498 169.498)
		(width 0.256)
		(layer "F.Cu")
		(net 582)
	)
	(via
		(at 86 170)
		(size 0.45)
		(drill 0.1)
		(layers "F.Cu" "B.Cu")
		(net 582)
	)
	(segment
		(start 70.718501 150.996)
		(end 70.718501 159.636)
		(width 0.4)
		(layer "F.Cu")
		(net 593)
	)
	(segment
		(start 78.22 159.636)
		(end 78.225 159.631)
		(width 0.4)
		(layer "F.Cu")
		(net 593)
	)
	(segment
		(start 74.898501 150.996)
		(end 70.718501 150.996)
		(width 0.4)
		(layer "F.Cu")
		(net 593)
	)
	(segment
		(start 70.718501 159.636)
		(end 74.898501 159.636)
		(width 0.4)
		(layer "F.Cu")
		(net 593)
	)
	(segment
		(start 74.626501 159.636)
		(end 78.22 159.636)
		(width 0.4)
		(layer "F.Cu")
		(net 593)
	)
	(segment
		(start 144.375501 182.301001)
		(end 144.875 182.8005)
		(width 0.256)
		(layer "F.Cu")
		(net 594)
	)
	(segment
		(start 82.039501 166.964)
		(end 82.814 166.964)
		(width 0.256)
		(layer "F.Cu")
		(net 594)
	)
	(segment
		(start 83.85 168)
		(end 84.413 168)
		(width 0.256)
		(layer "F.Cu")
		(net 594)
	)
	(segment
		(start 85.185 168)
		(end 84.413 168)
		(width 0.256)
		(layer "F.Cu")
		(net 594)
	)
	(segment
		(start 85.95 168)
		(end 86.25 167.7)
		(width 0.256)
		(layer "F.Cu")
		(net 594)
	)
	(segment
		(start 82.814 166.964)
		(end 83.85 168)
		(width 0.256)
		(layer "F.Cu")
		(net 594)
	)
	(segment
		(start 85.185 168)
		(end 85.95 168)
		(width 0.256)
		(layer "F.Cu")
		(net 594)
	)
	(via
		(at 86.25 167.7)
		(size 0.45)
		(drill 0.1)
		(layers "F.Cu" "B.Cu")
		(net 594)
	)
	(via
		(at 144.875 182.8005)
		(size 0.45)
		(drill 0.1)
		(layers "F.Cu" "B.Cu")
		(net 594)
	)
	(segment
		(start 85.235 167.9)
		(end 85.435 167.7)
		(width 0.256)
		(layer "B.Cu")
		(net 594)
	)
	(segment
		(start 85.435 167.7)
		(end 86.25 167.7)
		(width 0.256)
		(layer "B.Cu")
		(net 594)
	)
	(segment
		(start 87.3 169.15)
		(end 91.2 173.05)
		(width 0.1)
		(layer "In6.Cu")
		(net 594)
	)
	(segment
		(start 142.3 183)
		(end 142.6 183.3)
		(width 0.1)
		(layer "In6.Cu")
		(net 594)
	)
	(segment
		(start 92.520269 184.001048)
		(end 92.520268 184.001049)
		(width 0.1)
		(layer "In6.Cu")
		(net 594)
	)
	(segment
		(start 87.3 168.05)
		(end 87.3 169.15)
		(width 0.1)
		(layer "In6.Cu")
		(net 594)
	)
	(segment
		(start 123.494169 181.626001)
		(end 125.173999 181.626001)
		(width 0.1)
		(layer "In6.Cu")
		(net 594)
	)
	(segment
		(start 138.4 181.4)
		(end 139.3755 182.3755)
		(width 0.1)
		(layer "In6.Cu")
		(net 594)
	)
	(segment
		(start 139.3755 182.3755)
		(end 142.0755 182.3755)
		(width 0.1)
		(layer "In6.Cu")
		(net 594)
	)
	(segment
		(start 144.3755 183.3)
		(end 144.875 182.8005)
		(width 0.1)
		(layer "In6.Cu")
		(net 594)
	)
	(segment
		(start 92.676787 182.996006)
		(end 92.096004 183.576785)
		(width 0.1)
		(layer "In6.Cu")
		(net 594)
	)
	(segment
		(start 93.7 184.6)
		(end 112 184.6)
		(width 0.1)
		(layer "In6.Cu")
		(net 594)
	)
	(segment
		(start 120.325 181.625)
		(end 123.493168 181.625)
		(width 0.1)
		(layer "In6.Cu")
		(net 594)
	)
	(segment
		(start 118.75 183.2)
		(end 120.325 181.625)
		(width 0.1)
		(layer "In6.Cu")
		(net 594)
	)
	(segment
		(start 92.174265 182.649999)
		(end 92.174264 182.65)
		(width 0.1)
		(layer "In6.Cu")
		(net 594)
	)
	(segment
		(start 93.02279 183.92279)
		(end 93.7 184.6)
		(width 0.1)
		(layer "In6.Cu")
		(net 594)
	)
	(segment
		(start 92.520268 184.001049)
		(end 92.598526 183.92279)
		(width 0.1)
		(layer "In6.Cu")
		(net 594)
	)
	(segment
		(start 113.4 183.2)
		(end 118.75 183.2)
		(width 0.1)
		(layer "In6.Cu")
		(net 594)
	)
	(segment
		(start 86.95 167.7)
		(end 87.3 168.05)
		(width 0.1)
		(layer "In6.Cu")
		(net 594)
	)
	(segment
		(start 123.493168 181.625)
		(end 123.494169 181.626001)
		(width 0.1)
		(layer "In6.Cu")
		(net 594)
	)
	(segment
		(start 91.2 182.1)
		(end 91.75 182.65)
		(width 0.1)
		(layer "In6.Cu")
		(net 594)
	)
	(segment
		(start 112 184.6)
		(end 113.4 183.2)
		(width 0.1)
		(layer "In6.Cu")
		(net 594)
	)
	(segment
		(start 91.2 173.05)
		(end 91.2 182.1)
		(width 0.1)
		(layer "In6.Cu")
		(net 594)
	)
	(segment
		(start 125.173999 181.626001)
		(end 125.4 181.4)
		(width 0.1)
		(layer "In6.Cu")
		(net 594)
	)
	(segment
		(start 142.6 183.3)
		(end 144.3755 183.3)
		(width 0.1)
		(layer "In6.Cu")
		(net 594)
	)
	(segment
		(start 142.0755 182.3755)
		(end 142.3 182.6)
		(width 0.1)
		(layer "In6.Cu")
		(net 594)
	)
	(segment
		(start 142.3 182.6)
		(end 142.3 183)
		(width 0.1)
		(layer "In6.Cu")
		(net 594)
	)
	(segment
		(start 92.174264 182.65)
		(end 92.252523 182.571742)
		(width 0.1)
		(layer "In6.Cu")
		(net 594)
	)
	(segment
		(start 125.4 181.4)
		(end 138.4 181.4)
		(width 0.1)
		(layer "In6.Cu")
		(net 594)
	)
	(segment
		(start 92.676786 182.996007)
		(end 92.676787 182.996006)
		(width 0.1)
		(layer "In6.Cu")
		(net 594)
	)
	(segment
		(start 86.25 167.7)
		(end 86.95 167.7)
		(width 0.1)
		(layer "In6.Cu")
		(net 594)
	)
	(arc
		(start 91.75 182.65)
		(mid 91.962134 182.737869)
		(end 92.174265 182.649999)
		(width 0.1)
		(layer "In6.Cu")
		(net 594)
	)
	(arc
		(start 92.598526 183.92279)
		(mid 92.810658 183.834922)
		(end 93.02279 183.92279)
		(width 0.1)
		(layer "In6.Cu")
		(net 594)
	)
	(arc
		(start 92.096004 184.001049)
		(mid 92.308137 184.088917)
		(end 92.520269 184.001048)
		(width 0.1)
		(layer "In6.Cu")
		(net 594)
	)
	(arc
		(start 92.096004 183.576785)
		(mid 92.008136 183.788917)
		(end 92.096004 184.001049)
		(width 0.1)
		(layer "In6.Cu")
		(net 594)
	)
	(arc
		(start 92.676787 182.571742)
		(mid 92.764654 182.783874)
		(end 92.676786 182.996007)
		(width 0.1)
		(layer "In6.Cu")
		(net 594)
	)
	(arc
		(start 92.252523 182.571742)
		(mid 92.464655 182.483874)
		(end 92.676787 182.571742)
		(width 0.1)
		(layer "In6.Cu")
		(net 594)
	)
	(segment
		(start 195.366 128.15)
		(end 192.894501 128.15)
		(width 0.4)
		(layer "B.Cu")
		(net 597)
	)
	(segment
		(start 192.894501 128.15)
		(end 192.890501 128.146)
		(width 0.256)
		(layer "B.Cu")
		(net 597)
	)
	(segment
		(start 74.070501 139.166)
		(end 74.070501 133.450488)
		(width 0.15)
		(layer "F.Cu")
		(net 602)
	)
	(segment
		(start 78.4 147)
		(end 75.620501 144.220501)
		(width 0.15)
		(layer "F.Cu")
		(net 602)
	)
	(segment
		(start 89.073352 153.013149)
		(end 86.913149 153.013149)
		(width 0.15)
		(layer "F.Cu")
		(net 602)
	)
	(segment
		(start 86 152.1)
		(end 86 149.5)
		(width 0.15)
		(layer "F.Cu")
		(net 602)
	)
	(segment
		(start 74.070501 133.450488)
		(end 74.0325 133.412487)
		(width 0.15)
		(layer "F.Cu")
		(net 602)
	)
	(segment
		(start 75.620501 144.220501)
		(end 75.620501 140.716)
		(width 0.15)
		(layer "F.Cu")
		(net 602)
	)
	(segment
		(start 75.620501 140.716)
		(end 74.070501 139.166)
		(width 0.15)
		(layer "F.Cu")
		(net 602)
	)
	(segment
		(start 89.310501 153.036)
		(end 90.123352 153.036)
		(width 0.2)
		(layer "F.Cu")
		(net 602)
	)
	(segment
		(start 86.913149 153.013149)
		(end 86 152.1)
		(width 0.15)
		(layer "F.Cu")
		(net 602)
	)
	(segment
		(start 86 149.5)
		(end 83.5 147)
		(width 0.15)
		(layer "F.Cu")
		(net 602)
	)
	(segment
		(start 83.5 147)
		(end 78.4 147)
		(width 0.15)
		(layer "F.Cu")
		(net 602)
	)
	(segment
		(start 89.180501 152.906)
		(end 89.073352 153.013149)
		(width 0.15)
		(layer "F.Cu")
		(net 602)
	)
	(segment
		(start 89.180501 152.906)
		(end 89.310501 153.036)
		(width 0.2)
		(layer "F.Cu")
		(net 602)
	)
	(via
		(at 89.180501 152.906)
		(size 0.45)
		(drill 0.1)
		(layers "F.Cu" "B.Cu")
		(net 602)
	)
	(segment
		(start 85.680501 151.838149)
		(end 85.680501 152.808149)
		(width 0.2)
		(layer "B.Cu")
		(net 602)
	)
	(segment
		(start 89.180501 152.906)
		(end 89.08765 152.813149)
		(width 0.2)
		(layer "B.Cu")
		(net 602)
	)
	(segment
		(start 89.08765 152.813149)
		(end 85.685501 152.813149)
		(width 0.2)
		(layer "B.Cu")
		(net 602)
	)
	(segment
		(start 86.044851 154.044851)
		(end 85.3 153.3)
		(width 0.15)
		(layer "F.Cu")
		(net 603)
	)
	(segment
		(start 74.053487 144.153487)
		(end 74.0325 144.153487)
		(width 0.15)
		(layer "F.Cu")
		(net 603)
	)
	(segment
		(start 82.95 147.55)
		(end 77.45 147.55)
		(width 0.15)
		(layer "F.Cu")
		(net 603)
	)
	(segment
		(start 85.3 149.9)
		(end 82.95 147.55)
		(width 0.15)
		(layer "F.Cu")
		(net 603)
	)
	(segment
		(start 85.3 153.3)
		(end 85.3 149.9)
		(width 0.15)
		(layer "F.Cu")
		(net 603)
	)
	(segment
		(start 90.123352 154.036)
		(end 89.310501 154.036)
		(width 0.2)
		(layer "F.Cu")
		(net 603)
	)
	(segment
		(start 89.198858 154.044851)
		(end 86.044851 154.044851)
		(width 0.15)
		(layer "F.Cu")
		(net 603)
	)
	(segment
		(start 77.45 147.55)
		(end 74.053487 144.153487)
		(width 0.15)
		(layer "F.Cu")
		(net 603)
	)
	(segment
		(start 89.310501 154.036)
		(end 89.250254 154.096247)
		(width 0.2)
		(layer "F.Cu")
		(net 603)
	)
	(segment
		(start 89.250254 154.096247)
		(end 89.198858 154.044851)
		(width 0.15)
		(layer "F.Cu")
		(net 603)
	)
	(via
		(at 89.250254 154.096247)
		(size 0.45)
		(drill 0.1)
		(layers "F.Cu" "B.Cu")
		(net 603)
	)
	(segment
		(start 85.685501 154.313149)
		(end 85.685501 155.273149)
		(width 0.2)
		(layer "B.Cu")
		(net 603)
	)
	(segment
		(start 89.250254 154.096247)
		(end 89.190007 154.036)
		(width 0.2)
		(layer "B.Cu")
		(net 603)
	)
	(segment
		(start 85.96265 154.036)
		(end 85.685501 154.313149)
		(width 0.2)
		(layer "B.Cu")
		(net 603)
	)
	(segment
		(start 89.190007 154.036)
		(end 85.96265 154.036)
		(width 0.2)
		(layer "B.Cu")
		(net 603)
	)
	(segment
		(start 147.775501 187.294378)
		(end 147.775501 187.656133)
		(width 0.1)
		(layer "F.Cu")
		(net 604)
	)
	(segment
		(start 146.775501 186.428181)
		(end 146.775501 186.496212)
		(width 0.1)
		(layer "F.Cu")
		(net 604)
	)
	(segment
		(start 147.684981 188.993425)
		(end 147.684981 187.874727)
		(width 0.22)
		(layer "F.Cu")
		(net 604)
	)
	(segment
		(start 129.835501 205.825262)
		(end 129.835501 208.020797)
		(width 0.22)
		(layer "F.Cu")
		(net 604)
	)
	(segment
		(start 141.51744 191.889359)
		(end 131.429293 201.977506)
		(width 0.22)
		(layer "F.Cu")
		(net 604)
	)
	(segment
		(start 147.26045 186.901)
		(end 147.385583 186.901)
		(width 0.1)
		(layer "F.Cu")
		(net 604)
	)
	(segment
		(start 146.860856 186.702278)
		(end 146.917539 186.758961)
		(width 0.1)
		(layer "F.Cu")
		(net 604)
	)
	(segment
		(start 129.525501 208.769204)
		(end 129.525501 210.806)
		(width 0.22)
		(layer "F.Cu")
		(net 604)
	)
	(segment
		(start 146.375501 186.301)
		(end 146.648319 186.301)
		(width 0.1)
		(layer "F.Cu")
		(net 604)
	)
	(segment
		(start 144.846299 190.510501)
		(end 146.167905 190.510501)
		(width 0.22)
		(layer "F.Cu")
		(net 604)
	)
	(segment
		(start 147.651218 187.011031)
		(end 147.663025 187.022838)
		(width 0.1)
		(layer "F.Cu")
		(net 604)
	)
	(arc
		(start 147.663025 187.022838)
		(mid 147.746269 187.147422)
		(end 147.775501 187.294378)
		(width 0.1)
		(layer "F.Cu")
		(net 604)
	)
	(arc
		(start 147.684981 187.874727)
		(mid 147.751965 187.774457)
		(end 147.775501 187.656133)
		(width 0.1)
		(layer "F.Cu")
		(net 604)
	)
	(arc
		(start 147.385583 186.901)
		(mid 147.529344 186.929597)
		(end 147.651218 187.011031)
		(width 0.1)
		(layer "F.Cu")
		(net 604)
	)
	(arc
		(start 129.835501 208.020797)
		(mid 129.795217 208.223314)
		(end 129.680501 208.395001)
		(width 0.22)
		(layer "F.Cu")
		(net 604)
	)
	(arc
		(start 129.680501 208.395001)
		(mid 129.565784 208.566686)
		(end 129.525501 208.769204)
		(width 0.22)
		(layer "F.Cu")
		(net 604)
	)
	(arc
		(start 146.73825 186.33825)
		(mid 146.765819 186.37951)
		(end 146.775501 186.428181)
		(width 0.1)
		(layer "F.Cu")
		(net 604)
	)
	(arc
		(start 131.429293 201.977506)
		(mid 130.249714 203.742871)
		(end 129.835501 205.825262)
		(width 0.22)
		(layer "F.Cu")
		(net 604)
	)
	(arc
		(start 146.648319 186.301)
		(mid 146.696989 186.31068)
		(end 146.73825 186.33825)
		(width 0.1)
		(layer "F.Cu")
		(net 604)
	)
	(arc
		(start 147.24064 190.06616)
		(mid 146.748465 190.39502)
		(end 146.167905 190.510501)
		(width 0.22)
		(layer "F.Cu")
		(net 604)
	)
	(arc
		(start 146.917539 186.758961)
		(mid 147.074868 186.864085)
		(end 147.26045 186.901)
		(width 0.1)
		(layer "F.Cu")
		(net 604)
	)
	(arc
		(start 147.684981 188.993425)
		(mid 147.5695 189.573985)
		(end 147.24064 190.06616)
		(width 0.22)
		(layer "F.Cu")
		(net 604)
	)
	(arc
		(start 144.846299 190.510501)
		(mid 143.044733 190.868854)
		(end 141.51744 191.889359)
		(width 0.22)
		(layer "F.Cu")
		(net 604)
	)
	(arc
		(start 146.775501 186.496212)
		(mid 146.797684 186.607734)
		(end 146.860856 186.702278)
		(width 0.1)
		(layer "F.Cu")
		(net 604)
	)
	(segment
		(start 147.260452 186.701)
		(end 147.384566 186.701)
		(width 0.1)
		(layer "F.Cu")
		(net 605)
	)
	(segment
		(start 148.064981 188.07356)
		(end 148.064981 187.874005)
		(width 0.22)
		(layer "F.Cu")
		(net 605)
	)
	(segment
		(start 131.800923 202.14328)
		(end 141.744407 192.199796)
		(width 0.22)
		(layer "F.Cu")
		(net 605)
	)
	(segment
		(start 148.064981 188.99343)
		(end 148.064981 188.59644)
		(width 0.22)
		(layer "F.Cu")
		(net 605)
	)
	(segment
		(start 147.793312 186.870309)
		(end 147.805634 186.882631)
		(width 0.1)
		(layer "F.Cu")
		(net 605)
	)
	(segment
		(start 146.975501 186.42647)
		(end 146.975501 186.454289)
		(width 0.1)
		(layer "F.Cu")
		(net 605)
	)
	(segment
		(start 148.094271 188.525729)
		(end 148.170711 188.449289)
		(width 0.22)
		(layer "F.Cu")
		(net 605)
	)
	(segment
		(start 144.905324 190.890501)
		(end 146.16791 190.890501)
		(width 0.22)
		(layer "F.Cu")
		(net 605)
	)
	(segment
		(start 147.375501 186.301)
		(end 147.100971 186.301)
		(width 0.1)
		(layer "F.Cu")
		(net 605)
	)
	(segment
		(start 147.975482 187.292683)
		(end 147.975482 187.657967)
		(width 0.1)
		(layer "F.Cu")
		(net 605)
	)
	(segment
		(start 148.2 188.378579)
		(end 148.2 188.291421)
		(width 0.22)
		(layer "F.Cu")
		(net 605)
	)
	(segment
		(start 148.17071 188.22071)
		(end 148.09427 188.14427)
		(width 0.22)
		(layer "F.Cu")
		(net 605)
	)
	(segment
		(start 130.525501 210.806)
		(end 130.525501 208.770204)
		(width 0.22)
		(layer "F.Cu")
		(net 605)
	)
	(segment
		(start 130.215501 208.021797)
		(end 130.215501 205.970828)
		(width 0.22)
		(layer "F.Cu")
		(net 605)
	)
	(segment
		(start 147.031921 186.590499)
		(end 147.058961 186.617539)
		(width 0.1)
		(layer "F.Cu")
		(net 605)
	)
	(arc
		(start 147.058961 186.617539)
		(mid 147.151406 186.679309)
		(end 147.260452 186.701)
		(width 0.1)
		(layer "F.Cu")
		(net 605)
	)
	(arc
		(start 147.975482 187.657967)
		(mid 147.998736 187.774874)
		(end 148.064981 187.874005)
		(width 0.1)
		(layer "F.Cu")
		(net 605)
	)
	(arc
		(start 146.16791 190.890501)
		(mid 146.893887 190.746095)
		(end 147.509342 190.334862)
		(width 0.22)
		(layer "F.Cu")
		(net 605)
	)
	(arc
		(start 147.509342 190.334862)
		(mid 147.920575 189.719407)
		(end 148.064981 188.99343)
		(width 0.22)
		(layer "F.Cu")
		(net 605)
	)
	(arc
		(start 148.064981 188.07356)
		(mid 148.072593 188.111828)
		(end 148.09427 188.14427)
		(width 0.22)
		(layer "F.Cu")
		(net 605)
	)
	(arc
		(start 130.525501 208.770204)
		(mid 130.485217 208.567686)
		(end 130.370501 208.396001)
		(width 0.22)
		(layer "F.Cu")
		(net 605)
	)
	(arc
		(start 147.100971 186.301)
		(mid 147.052955 186.31055)
		(end 147.01225 186.337749)
		(width 0.1)
		(layer "F.Cu")
		(net 605)
	)
	(arc
		(start 146.975501 186.454289)
		(mid 146.990164 186.528005)
		(end 147.031921 186.590499)
		(width 0.1)
		(layer "F.Cu")
		(net 605)
	)
	(arc
		(start 141.744407 192.199796)
		(mid 143.194648 191.230776)
		(end 144.905324 190.890501)
		(width 0.22)
		(layer "F.Cu")
		(net 605)
	)
	(arc
		(start 148.094271 188.525729)
		(mid 148.072593 188.558171)
		(end 148.064981 188.59644)
		(width 0.22)
		(layer "F.Cu")
		(net 605)
	)
	(arc
		(start 147.01225 186.337749)
		(mid 146.985051 186.378454)
		(end 146.975501 186.42647)
		(width 0.1)
		(layer "F.Cu")
		(net 605)
	)
	(arc
		(start 130.215501 205.970828)
		(mid 130.627539 203.899374)
		(end 131.800923 202.14328)
		(width 0.22)
		(layer "F.Cu")
		(net 605)
	)
	(arc
		(start 147.805634 186.882631)
		(mid 147.93134 187.070765)
		(end 147.975482 187.292683)
		(width 0.1)
		(layer "F.Cu")
		(net 605)
	)
	(arc
		(start 148.2 188.378579)
		(mid 148.192388 188.416847)
		(end 148.170711 188.449289)
		(width 0.22)
		(layer "F.Cu")
		(net 605)
	)
	(arc
		(start 130.370501 208.396001)
		(mid 130.255784 208.224314)
		(end 130.215501 208.021797)
		(width 0.22)
		(layer "F.Cu")
		(net 605)
	)
	(arc
		(start 148.2 188.291421)
		(mid 148.192388 188.253152)
		(end 148.17071 188.22071)
		(width 0.22)
		(layer "F.Cu")
		(net 605)
	)
	(arc
		(start 147.384566 186.701)
		(mid 147.605778 186.745002)
		(end 147.793312 186.870309)
		(width 0.1)
		(layer "F.Cu")
		(net 605)
	)
	(segment
		(start 152.679165 186.769585)
		(end 152.316993 186.407413)
		(width 0.22)
		(layer "F.Cu")
		(net 606)
	)
	(segment
		(start 153.085001 187.99861)
		(end 153.085001 187.749359)
		(width 0.22)
		(layer "F.Cu")
		(net 606)
	)
	(segment
		(start 134.525501 210.806)
		(end 134.525501 208.769204)
		(width 0.22)
		(layer "F.Cu")
		(net 606)
	)
	(segment
		(start 134.835501 208.020797)
		(end 134.835501 204.725262)
		(width 0.22)
		(layer "F.Cu")
		(net 606)
	)
	(segment
		(start 149.801421 186)
		(end 149.948579 186)
		(width 0.1)
		(layer "F.Cu")
		(net 606)
	)
	(segment
		(start 148.886593 185.728015)
		(end 148.917539 185.758961)
		(width 0.1)
		(layer "F.Cu")
		(net 606)
	)
	(segment
		(start 144.912627 193.38)
		(end 147.698372 193.38)
		(width 0.22)
		(layer "F.Cu")
		(net 606)
	)
	(segment
		(start 136.429293 200.877506)
		(end 143.229713 194.077086)
		(width 0.22)
		(layer "F.Cu")
		(net 606)
	)
	(segment
		(start 150.130421 185.901)
		(end 151.69419 185.901)
		(width 0.1)
		(layer "F.Cu")
		(net 606)
	)
	(segment
		(start 149.26045 185.901)
		(end 149.619579 185.901)
		(width 0.1)
		(layer "F.Cu")
		(net 606)
	)
	(segment
		(start 149.112586 192.794213)
		(end 152.502918 189.403881)
		(width 0.22)
		(layer "F.Cu")
		(net 606)
	)
	(segment
		(start 148.775501 185.428181)
		(end 148.775501 185.459815)
		(width 0.1)
		(layer "F.Cu")
		(net 606)
	)
	(segment
		(start 150.01929 185.97071)
		(end 150.059711 185.930289)
		(width 0.1)
		(layer "F.Cu")
		(net 606)
	)
	(segment
		(start 152.103704 186.070626)
		(end 152.229781 186.196703)
		(width 0.1)
		(layer "F.Cu")
		(net 606)
	)
	(segment
		(start 148.375501 185.301)
		(end 148.648319 185.301)
		(width 0.1)
		(layer "F.Cu")
		(net 606)
	)
	(segment
		(start 149.69029 185.93029)
		(end 149.730711 185.970711)
		(width 0.1)
		(layer "F.Cu")
		(net 606)
	)
	(arc
		(start 134.835501 204.725262)
		(mid 135.249714 202.642871)
		(end 136.429293 200.877506)
		(width 0.22)
		(layer "F.Cu")
		(net 606)
	)
	(arc
		(start 134.525501 208.769204)
		(mid 134.565784 208.566686)
		(end 134.680501 208.395001)
		(width 0.22)
		(layer "F.Cu")
		(net 606)
	)
	(arc
		(start 148.775501 185.459815)
		(mid 148.804373 185.604964)
		(end 148.886593 185.728015)
		(width 0.1)
		(layer "F.Cu")
		(net 606)
	)
	(arc
		(start 150.059711 185.930289)
		(mid 150.092153 185.908612)
		(end 150.130421 185.901)
		(width 0.1)
		(layer "F.Cu")
		(net 606)
	)
	(arc
		(start 144.912627 193.38)
		(mid 144.00184 193.561167)
		(end 143.229713 194.077086)
		(width 0.22)
		(layer "F.Cu")
		(net 606)
	)
	(arc
		(start 151.69419 185.901)
		(mid 151.915817 185.945084)
		(end 152.103704 186.070626)
		(width 0.1)
		(layer "F.Cu")
		(net 606)
	)
	(arc
		(start 148.917539 185.758961)
		(mid 149.074868 185.864085)
		(end 149.26045 185.901)
		(width 0.1)
		(layer "F.Cu")
		(net 606)
	)
	(arc
		(start 147.698372 193.38)
		(mid 148.463739 193.227759)
		(end 149.112586 192.794213)
		(width 0.22)
		(layer "F.Cu")
		(net 606)
	)
	(arc
		(start 152.502918 189.403881)
		(mid 152.933722 188.759137)
		(end 153.085001 187.99861)
		(width 0.22)
		(layer "F.Cu")
		(net 606)
	)
	(arc
		(start 152.229781 186.196703)
		(mid 152.294328 186.293305)
		(end 152.316993 186.407413)
		(width 0.1)
		(layer "F.Cu")
		(net 606)
	)
	(arc
		(start 148.73825 185.33825)
		(mid 148.765819 185.37951)
		(end 148.775501 185.428181)
		(width 0.1)
		(layer "F.Cu")
		(net 606)
	)
	(arc
		(start 153.085001 187.749359)
		(mid 152.979527 187.219109)
		(end 152.679165 186.769585)
		(width 0.22)
		(layer "F.Cu")
		(net 606)
	)
	(arc
		(start 149.730711 185.970711)
		(mid 149.763153 185.992388)
		(end 149.801421 186)
		(width 0.1)
		(layer "F.Cu")
		(net 606)
	)
	(arc
		(start 149.69029 185.93029)
		(mid 149.657848 185.908612)
		(end 149.619579 185.901)
		(width 0.1)
		(layer "F.Cu")
		(net 606)
	)
	(arc
		(start 149.948579 186)
		(mid 149.986848 185.992388)
		(end 150.01929 185.97071)
		(width 0.1)
		(layer "F.Cu")
		(net 606)
	)
	(arc
		(start 134.680501 208.395001)
		(mid 134.795217 208.223314)
		(end 134.835501 208.020797)
		(width 0.22)
		(layer "F.Cu")
		(net 606)
	)
	(arc
		(start 148.648319 185.301)
		(mid 148.696989 185.31068)
		(end 148.73825 185.33825)
		(width 0.1)
		(layer "F.Cu")
		(net 606)
	)
	(segment
		(start 152.237435 185.921513)
		(end 152.364642 186.04872)
		(width 0.1)
		(layer "F.Cu")
		(net 607)
	)
	(segment
		(start 144.91263 193.76)
		(end 147.698375 193.76)
		(width 0.22)
		(layer "F.Cu")
		(net 607)
	)
	(segment
		(start 149.031921 185.590499)
		(end 149.058961 185.617539)
		(width 0.1)
		(layer "F.Cu")
		(net 607)
	)
	(segment
		(start 136.809293 201.03491)
		(end 143.498417 194.345786)
		(width 0.22)
		(layer "F.Cu")
		(net 607)
	)
	(segment
		(start 135.215501 208.021797)
		(end 135.215501 204.882666)
		(width 0.22)
		(layer "F.Cu")
		(net 607)
	)
	(segment
		(start 149.375501 185.301)
		(end 149.100971 185.301)
		(width 0.1)
		(layer "F.Cu")
		(net 607)
	)
	(segment
		(start 149.381289 193.062914)
		(end 152.771617 189.672586)
		(width 0.22)
		(layer "F.Cu")
		(net 607)
	)
	(segment
		(start 148.975501 185.42647)
		(end 148.975501 185.454289)
		(width 0.1)
		(layer "F.Cu")
		(net 607)
	)
	(segment
		(start 153.003516 186.556532)
		(end 152.588369 186.141385)
		(width 0.22)
		(layer "F.Cu")
		(net 607)
	)
	(segment
		(start 149.260452 185.701)
		(end 151.70507 185.701)
		(width 0.1)
		(layer "F.Cu")
		(net 607)
	)
	(segment
		(start 153.465001 187.99861)
		(end 153.465001 187.670654)
		(width 0.22)
		(layer "F.Cu")
		(net 607)
	)
	(segment
		(start 135.525501 210.806)
		(end 135.525501 208.770204)
		(width 0.22)
		(layer "F.Cu")
		(net 607)
	)
	(arc
		(start 153.465001 187.670654)
		(mid 153.345064 187.067695)
		(end 153.003516 186.556532)
		(width 0.22)
		(layer "F.Cu")
		(net 607)
	)
	(arc
		(start 152.364642 186.04872)
		(mid 152.467283 186.117302)
		(end 152.588369 186.141385)
		(width 0.1)
		(layer "F.Cu")
		(net 607)
	)
	(arc
		(start 149.100971 185.301)
		(mid 149.052955 185.31055)
		(end 149.01225 185.337749)
		(width 0.1)
		(layer "F.Cu")
		(net 607)
	)
	(arc
		(start 135.525501 208.770204)
		(mid 135.485217 208.567686)
		(end 135.370501 208.396001)
		(width 0.22)
		(layer "F.Cu")
		(net 607)
	)
	(arc
		(start 148.975501 185.454289)
		(mid 148.990164 185.528005)
		(end 149.031921 185.590499)
		(width 0.1)
		(layer "F.Cu")
		(net 607)
	)
	(arc
		(start 147.698375 193.76)
		(mid 148.609162 193.578833)
		(end 149.381289 193.062914)
		(width 0.22)
		(layer "F.Cu")
		(net 607)
	)
	(arc
		(start 149.01225 185.337749)
		(mid 148.985051 185.378454)
		(end 148.975501 185.42647)
		(width 0.1)
		(layer "F.Cu")
		(net 607)
	)
	(arc
		(start 152.771617 189.672586)
		(mid 153.284796 188.904559)
		(end 153.465001 187.99861)
		(width 0.22)
		(layer "F.Cu")
		(net 607)
	)
	(arc
		(start 135.215501 204.882666)
		(mid 135.629714 202.800275)
		(end 136.809293 201.03491)
		(width 0.22)
		(layer "F.Cu")
		(net 607)
	)
	(arc
		(start 144.91263 193.76)
		(mid 144.147263 193.912241)
		(end 143.498417 194.345786)
		(width 0.22)
		(layer "F.Cu")
		(net 607)
	)
	(arc
		(start 135.370501 208.396001)
		(mid 135.255784 208.224314)
		(end 135.215501 208.021797)
		(width 0.22)
		(layer "F.Cu")
		(net 607)
	)
	(arc
		(start 149.058961 185.617539)
		(mid 149.151406 185.679309)
		(end 149.260452 185.701)
		(width 0.1)
		(layer "F.Cu")
		(net 607)
	)
	(arc
		(start 151.70507 185.701)
		(mid 151.993184 185.758309)
		(end 152.237435 185.921513)
		(width 0.1)
		(layer "F.Cu")
		(net 607)
	)
	(segment
		(start 138.525501 208.769204)
		(end 138.525501 210.806)
		(width 0.22)
		(layer "F.Cu")
		(net 608)
	)
	(segment
		(start 149.72029 183.93029)
		(end 149.730711 183.940711)
		(width 0.1)
		(layer "F.Cu")
		(net 608)
	)
	(segment
		(start 158.99065 189.184852)
		(end 158.622991 188.817193)
		(width 0.22)
		(layer "F.Cu")
		(net 608)
	)
	(segment
		(start 148.775501 183.428181)
		(end 148.775501 183.496212)
		(width 0.1)
		(layer "F.Cu")
		(net 608)
	)
	(segment
		(start 159.935001 192.532731)
		(end 159.935001 191.464716)
		(width 0.22)
		(layer "F.Cu")
		(net 608)
	)
	(segment
		(start 157.105093 188.240501)
		(end 157.230728 188.240501)
		(width 0.22)
		(layer "F.Cu")
		(net 608)
	)
	(segment
		(start 140.429293 200.777505)
		(end 143.002506 198.204293)
		(width 0.22)
		(layer "F.Cu")
		(net 608)
	)
	(segment
		(start 152.303674 184.319786)
		(end 152.303672 184.325439)
		(width 0.1)
		(layer "F.Cu")
		(net 608)
	)
	(segment
		(start 152.342453 184.419066)
		(end 155.498355 187.574968)
		(width 0.22)
		(layer "F.Cu")
		(net 608)
	)
	(segment
		(start 148.860856 183.702278)
		(end 148.917539 183.758961)
		(width 0.1)
		(layer "F.Cu")
		(net 608)
	)
	(segment
		(start 155.857231 196.610501)
		(end 146.850262 196.610501)
		(width 0.22)
		(layer "F.Cu")
		(net 608)
	)
	(segment
		(start 149.801421 183.97)
		(end 149.920579 183.97)
		(width 0.1)
		(layer "F.Cu")
		(net 608)
	)
	(segment
		(start 149.26045 183.901)
		(end 149.649579 183.901)
		(width 0.1)
		(layer "F.Cu")
		(net 608)
	)
	(segment
		(start 150.072421 183.901)
		(end 151.672735 183.901)
		(width 0.1)
		(layer "F.Cu")
		(net 608)
	)
	(segment
		(start 149.99129 183.94071)
		(end 150.001711 183.930289)
		(width 0.1)
		(layer "F.Cu")
		(net 608)
	)
	(segment
		(start 148.375501 183.301)
		(end 148.667778 183.301)
		(width 0.1)
		(layer "F.Cu")
		(net 608)
	)
	(segment
		(start 148.724492 183.324492)
		(end 148.73825 183.33825)
		(width 0.1)
		(layer "F.Cu")
		(net 608)
	)
	(segment
		(start 152.118875 184.085797)
		(end 152.268915 184.235837)
		(width 0.1)
		(layer "F.Cu")
		(net 608)
	)
	(segment
		(start 138.835501 204.625262)
		(end 138.835501 208.020797)
		(width 0.22)
		(layer "F.Cu")
		(net 608)
	)
	(arc
		(start 149.72029 183.93029)
		(mid 149.687848 183.908612)
		(end 149.649579 183.901)
		(width 0.1)
		(layer "F.Cu")
		(net 608)
	)
	(arc
		(start 158.622991 188.817193)
		(mid 157.984215 188.390377)
		(end 157.230728 188.240501)
		(width 0.22)
		(layer "F.Cu")
		(net 608)
	)
	(arc
		(start 148.917539 183.758961)
		(mid 149.074868 183.864085)
		(end 149.26045 183.901)
		(width 0.1)
		(layer "F.Cu")
		(net 608)
	)
	(arc
		(start 149.801421 183.97)
		(mid 149.763153 183.962388)
		(end 149.730711 183.940711)
		(width 0.1)
		(layer "F.Cu")
		(net 608)
	)
	(arc
		(start 148.775501 183.496212)
		(mid 148.797684 183.607734)
		(end 148.860856 183.702278)
		(width 0.1)
		(layer "F.Cu")
		(net 608)
	)
	(arc
		(start 158.99065 189.184852)
		(mid 159.689572 190.230862)
		(end 159.935001 191.464716)
		(width 0.22)
		(layer "F.Cu")
		(net 608)
	)
	(arc
		(start 152.268915 184.235837)
		(mid 152.294647 184.274353)
		(end 152.303674 184.319786)
		(width 0.1)
		(layer "F.Cu")
		(net 608)
	)
	(arc
		(start 146.850262 196.610501)
		(mid 144.767871 197.024714)
		(end 143.002506 198.204293)
		(width 0.22)
		(layer "F.Cu")
		(net 608)
	)
	(arc
		(start 148.667778 183.301)
		(mid 148.698471 183.307106)
		(end 148.724492 183.324492)
		(width 0.1)
		(layer "F.Cu")
		(net 608)
	)
	(arc
		(start 149.920579 183.97)
		(mid 149.958848 183.962388)
		(end 149.99129 183.94071)
		(width 0.1)
		(layer "F.Cu")
		(net 608)
	)
	(arc
		(start 148.73825 183.33825)
		(mid 148.765819 183.37951)
		(end 148.775501 183.428181)
		(width 0.1)
		(layer "F.Cu")
		(net 608)
	)
	(arc
		(start 152.303672 184.325439)
		(mid 152.31375 184.376109)
		(end 152.342453 184.419066)
		(width 0.1)
		(layer "F.Cu")
		(net 608)
	)
	(arc
		(start 151.672735 183.901)
		(mid 151.914184 183.949027)
		(end 152.118875 184.085797)
		(width 0.1)
		(layer "F.Cu")
		(net 608)
	)
	(arc
		(start 158.74065 195.41615)
		(mid 157.417726 196.300099)
		(end 155.857231 196.610501)
		(width 0.22)
		(layer "F.Cu")
		(net 608)
	)
	(arc
		(start 155.498355 187.574968)
		(mid 156.235532 188.067534)
		(end 157.105093 188.240501)
		(width 0.22)
		(layer "F.Cu")
		(net 608)
	)
	(arc
		(start 138.835501 208.020797)
		(mid 138.795217 208.223314)
		(end 138.680501 208.395001)
		(width 0.22)
		(layer "F.Cu")
		(net 608)
	)
	(arc
		(start 140.429293 200.777505)
		(mid 139.249714 202.542871)
		(end 138.835501 204.625262)
		(width 0.22)
		(layer "F.Cu")
		(net 608)
	)
	(arc
		(start 138.680501 208.395001)
		(mid 138.565784 208.566686)
		(end 138.525501 208.769204)
		(width 0.22)
		(layer "F.Cu")
		(net 608)
	)
	(arc
		(start 159.935001 192.532731)
		(mid 159.624599 194.093226)
		(end 158.74065 195.41615)
		(width 0.22)
		(layer "F.Cu")
		(net 608)
	)
	(arc
		(start 150.072421 183.901)
		(mid 150.034153 183.908612)
		(end 150.001711 183.930289)
		(width 0.1)
		(layer "F.Cu")
		(net 608)
	)
	(segment
		(start 143.159909 198.584293)
		(end 140.809293 200.93491)
		(width 0.22)
		(layer "F.Cu")
		(net 609)
	)
	(segment
		(start 139.525501 208.770204)
		(end 139.525501 210.806)
		(width 0.22)
		(layer "F.Cu")
		(net 609)
	)
	(segment
		(start 148.975501 183.42647)
		(end 148.975501 183.454289)
		(width 0.1)
		(layer "F.Cu")
		(net 609)
	)
	(segment
		(start 139.215501 204.782666)
		(end 139.215501 208.021797)
		(width 0.22)
		(layer "F.Cu")
		(net 609)
	)
	(segment
		(start 152.623592 184.162801)
		(end 155.693453 187.232662)
		(width 0.22)
		(layer "F.Cu")
		(net 609)
	)
	(segment
		(start 160.315001 191.464712)
		(end 160.315001 192.532736)
		(width 0.22)
		(layer "F.Cu")
		(net 609)
	)
	(segment
		(start 149.375501 183.301)
		(end 149.100971 183.301)
		(width 0.1)
		(layer "F.Cu")
		(net 609)
	)
	(segment
		(start 157.209186 187.860501)
		(end 157.262497 187.860501)
		(width 0.22)
		(layer "F.Cu")
		(net 609)
	)
	(segment
		(start 152.247255 183.931333)
		(end 152.377246 184.061324)
		(width 0.1)
		(layer "F.Cu")
		(net 609)
	)
	(segment
		(start 149.277641 183.701)
		(end 151.691182 183.701)
		(width 0.1)
		(layer "F.Cu")
		(net 609)
	)
	(segment
		(start 152.623592 184.162801)
		(end 152.622226 184.162801)
		(width 0.1)
		(layer "F.Cu")
		(net 609)
	)
	(segment
		(start 155.857236 196.990501)
		(end 147.007666 196.990501)
		(width 0.22)
		(layer "F.Cu")
		(net 609)
	)
	(segment
		(start 158.869235 188.526033)
		(end 159.259352 188.91615)
		(width 0.22)
		(layer "F.Cu")
		(net 609)
	)
	(segment
		(start 149.031921 183.590499)
		(end 149.046802 183.60538)
		(width 0.1)
		(layer "F.Cu")
		(net 609)
	)
	(arc
		(start 151.691182 183.701)
		(mid 151.992127 183.760862)
		(end 152.247255 183.931333)
		(width 0.1)
		(layer "F.Cu")
		(net 609)
	)
	(arc
		(start 140.809293 200.93491)
		(mid 139.629714 202.700275)
		(end 139.215501 204.782666)
		(width 0.22)
		(layer "F.Cu")
		(net 609)
	)
	(arc
		(start 159.259352 188.91615)
		(mid 160.040646 190.08544)
		(end 160.315001 191.464712)
		(width 0.22)
		(layer "F.Cu")
		(net 609)
	)
	(arc
		(start 159.009352 195.684852)
		(mid 157.563148 196.651173)
		(end 155.857236 196.990501)
		(width 0.22)
		(layer "F.Cu")
		(net 609)
	)
	(arc
		(start 152.377246 184.061324)
		(mid 152.489644 184.136427)
		(end 152.622226 184.162801)
		(width 0.1)
		(layer "F.Cu")
		(net 609)
	)
	(arc
		(start 147.007666 196.990501)
		(mid 144.925275 197.404714)
		(end 143.159909 198.584293)
		(width 0.22)
		(layer "F.Cu")
		(net 609)
	)
	(arc
		(start 139.215501 208.021797)
		(mid 139.255784 208.224314)
		(end 139.370501 208.396001)
		(width 0.22)
		(layer "F.Cu")
		(net 609)
	)
	(arc
		(start 139.370501 208.396001)
		(mid 139.485217 208.567686)
		(end 139.525501 208.770204)
		(width 0.22)
		(layer "F.Cu")
		(net 609)
	)
	(arc
		(start 149.01225 183.337749)
		(mid 148.985051 183.378454)
		(end 148.975501 183.42647)
		(width 0.1)
		(layer "F.Cu")
		(net 609)
	)
	(arc
		(start 149.046802 183.60538)
		(mid 149.15271 183.676149)
		(end 149.277641 183.701)
		(width 0.1)
		(layer "F.Cu")
		(net 609)
	)
	(arc
		(start 157.262497 187.860501)
		(mid 158.132057 188.033467)
		(end 158.869235 188.526033)
		(width 0.22)
		(layer "F.Cu")
		(net 609)
	)
	(arc
		(start 155.693453 187.232662)
		(mid 156.388877 187.69733)
		(end 157.209186 187.860501)
		(width 0.22)
		(layer "F.Cu")
		(net 609)
	)
	(arc
		(start 149.100971 183.301)
		(mid 149.052955 183.31055)
		(end 149.01225 183.337749)
		(width 0.1)
		(layer "F.Cu")
		(net 609)
	)
	(arc
		(start 148.975501 183.454289)
		(mid 148.990164 183.528005)
		(end 149.031921 183.590499)
		(width 0.1)
		(layer "F.Cu")
		(net 609)
	)
	(arc
		(start 160.315001 192.532736)
		(mid 159.975673 194.238648)
		(end 159.009352 195.684852)
		(width 0.22)
		(layer "F.Cu")
		(net 609)
	)
	(segment
		(start 149.73029 181.93029)
		(end 149.750711 181.950711)
		(width 0.1)
		(layer "F.Cu")
		(net 610)
	)
	(segment
		(start 148.860856 181.702278)
		(end 148.917539 181.758961)
		(width 0.1)
		(layer "F.Cu")
		(net 610)
	)
	(segment
		(start 156.042335 198.860501)
		(end 148.700262 198.860501)
		(width 0.22)
		(layer "F.Cu")
		(net 610)
	)
	(segment
		(start 144.852505 200.454293)
		(end 144.429293 200.877506)
		(width 0.22)
		(layer "F.Cu")
		(net 610)
	)
	(segment
		(start 148.775501 181.428181)
		(end 148.775501 181.496212)
		(width 0.1)
		(layer "F.Cu")
		(net 610)
	)
	(segment
		(start 149.96929 181.95071)
		(end 149.989711 181.930289)
		(width 0.1)
		(layer "F.Cu")
		(net 610)
	)
	(segment
		(start 161.935001 192.967835)
		(end 161.935001 190.136468)
		(width 0.22)
		(layer "F.Cu")
		(net 610)
	)
	(segment
		(start 142.525501 208.769204)
		(end 142.525501 210.806)
		(width 0.22)
		(layer "F.Cu")
		(net 610)
	)
	(segment
		(start 152.114594 182.081516)
		(end 152.248772 182.215694)
		(width 0.1)
		(layer "F.Cu")
		(net 610)
	)
	(segment
		(start 150.060421 181.901)
		(end 151.678789 181.901)
		(width 0.1)
		(layer "F.Cu")
		(net 610)
	)
	(segment
		(start 149.821421 181.98)
		(end 149.898579 181.98)
		(width 0.1)
		(layer "F.Cu")
		(net 610)
	)
	(segment
		(start 152.341447 182.439431)
		(end 153.812321 183.910305)
		(width 0.22)
		(layer "F.Cu")
		(net 610)
	)
	(segment
		(start 142.835501 204.725262)
		(end 142.835501 208.020797)
		(width 0.22)
		(layer "F.Cu")
		(net 610)
	)
	(segment
		(start 148.375501 181.301)
		(end 148.648319 181.301)
		(width 0.1)
		(layer "F.Cu")
		(net 610)
	)
	(segment
		(start 160.51565 186.709852)
		(end 160.476494 186.670696)
		(width 0.22)
		(layer "F.Cu")
		(net 610)
	)
	(segment
		(start 159.890091 197.266707)
		(end 160.341208 196.815591)
		(width 0.22)
		(layer "F.Cu")
		(net 610)
	)
	(segment
		(start 149.26045 181.901)
		(end 149.659579 181.901)
		(width 0.1)
		(layer "F.Cu")
		(net 610)
	)
	(arc
		(start 148.700262 198.860501)
		(mid 146.617871 199.274714)
		(end 144.852505 200.454293)
		(width 0.22)
		(layer "F.Cu")
		(net 610)
	)
	(arc
		(start 149.898579 181.98)
		(mid 149.936848 181.972388)
		(end 149.96929 181.95071)
		(width 0.1)
		(layer "F.Cu")
		(net 610)
	)
	(arc
		(start 152.29511 182.327563)
		(mid 152.307152 182.388105)
		(end 152.341447 182.439431)
		(width 0.1)
		(layer "F.Cu")
		(net 610)
	)
	(arc
		(start 151.678789 181.901)
		(mid 151.914645 181.947914)
		(end 152.114594 182.081516)
		(width 0.1)
		(layer "F.Cu")
		(net 610)
	)
	(arc
		(start 148.917539 181.758961)
		(mid 149.074868 181.864085)
		(end 149.26045 181.901)
		(width 0.1)
		(layer "F.Cu")
		(net 610)
	)
	(arc
		(start 159.890091 197.266707)
		(mid 158.124725 198.446287)
		(end 156.042335 198.860501)
		(width 0.22)
		(layer "F.Cu")
		(net 610)
	)
	(arc
		(start 160.51565 186.709852)
		(mid 161.566123 188.281996)
		(end 161.935001 190.136468)
		(width 0.22)
		(layer "F.Cu")
		(net 610)
	)
	(arc
		(start 148.73825 181.33825)
		(mid 148.765819 181.37951)
		(end 148.775501 181.428181)
		(width 0.1)
		(layer "F.Cu")
		(net 610)
	)
	(arc
		(start 144.429293 200.877506)
		(mid 143.249714 202.642871)
		(end 142.835501 204.725262)
		(width 0.22)
		(layer "F.Cu")
		(net 610)
	)
	(arc
		(start 161.935001 192.967835)
		(mid 161.520787 195.050225)
		(end 160.341208 196.815591)
		(width 0.22)
		(layer "F.Cu")
		(net 610)
	)
	(arc
		(start 149.73029 181.93029)
		(mid 149.697848 181.908612)
		(end 149.659579 181.901)
		(width 0.1)
		(layer "F.Cu")
		(net 610)
	)
	(arc
		(start 152.248772 182.215694)
		(mid 152.283067 182.26702)
		(end 152.29511 182.327563)
		(width 0.1)
		(layer "F.Cu")
		(net 610)
	)
	(arc
		(start 149.750711 181.950711)
		(mid 149.783153 181.972388)
		(end 149.821421 181.98)
		(width 0.1)
		(layer "F.Cu")
		(net 610)
	)
	(arc
		(start 142.680501 208.395001)
		(mid 142.565784 208.566686)
		(end 142.525501 208.769204)
		(width 0.22)
		(layer "F.Cu")
		(net 610)
	)
	(arc
		(start 142.835501 208.020797)
		(mid 142.795217 208.223314)
		(end 142.680501 208.395001)
		(width 0.22)
		(layer "F.Cu")
		(net 610)
	)
	(arc
		(start 148.648319 181.301)
		(mid 148.696989 181.31068)
		(end 148.73825 181.33825)
		(width 0.1)
		(layer "F.Cu")
		(net 610)
	)
	(arc
		(start 153.812321 183.910305)
		(mid 155.341095 184.931799)
		(end 157.144408 185.290501)
		(width 0.22)
		(layer "F.Cu")
		(net 610)
	)
	(arc
		(start 150.060421 181.901)
		(mid 150.022153 181.908612)
		(end 149.989711 181.930289)
		(width 0.1)
		(layer "F.Cu")
		(net 610)
	)
	(arc
		(start 160.476494 186.670696)
		(mid 158.94772 185.649201)
		(end 157.144408 185.290501)
		(width 0.22)
		(layer "F.Cu")
		(net 610)
	)
	(arc
		(start 148.775501 181.496212)
		(mid 148.797684 181.607734)
		(end 148.860856 181.702278)
		(width 0.1)
		(layer "F.Cu")
		(net 610)
	)
	(segment
		(start 148.975501 181.42647)
		(end 148.975501 181.454289)
		(width 0.1)
		(layer "F.Cu")
		(net 611)
	)
	(segment
		(start 143.525501 208.770204)
		(end 143.525501 210.806)
		(width 0.22)
		(layer "F.Cu")
		(net 611)
	)
	(segment
		(start 152.607475 182.168055)
		(end 153.969784 183.530364)
		(width 0.22)
		(layer "F.Cu")
		(net 611)
	)
	(segment
		(start 160.721207 196.972995)
		(end 160.047495 197.646708)
		(width 0.22)
		(layer "F.Cu")
		(net 611)
	)
	(segment
		(start 152.231981 181.916059)
		(end 152.39671 182.080788)
		(width 0.1)
		(layer "F.Cu")
		(net 611)
	)
	(segment
		(start 149.375501 181.301)
		(end 149.100971 181.301)
		(width 0.1)
		(layer "F.Cu")
		(net 611)
	)
	(segment
		(start 156.199739 199.240501)
		(end 148.766795 199.240501)
		(width 0.22)
		(layer "F.Cu")
		(net 611)
	)
	(segment
		(start 145.074153 200.770049)
		(end 144.829852 201.014351)
		(width 0.22)
		(layer "F.Cu")
		(net 611)
	)
	(segment
		(start 162.315001 190.136463)
		(end 162.315001 193.125239)
		(width 0.22)
		(layer "F.Cu")
		(net 611)
	)
	(segment
		(start 149.031921 181.590499)
		(end 149.058961 181.617539)
		(width 0.1)
		(layer "F.Cu")
		(net 611)
	)
	(segment
		(start 149.260452 181.701)
		(end 151.712784 181.701)
		(width 0.1)
		(layer "F.Cu")
		(net 611)
	)
	(segment
		(start 160.633898 186.290696)
		(end 160.784352 186.44115)
		(width 0.22)
		(layer "F.Cu")
		(net 611)
	)
	(segment
		(start 143.215501 204.911749)
		(end 143.215501 208.021797)
		(width 0.22)
		(layer "F.Cu")
		(net 611)
	)
	(arc
		(start 143.370501 208.396001)
		(mid 143.485217 208.567686)
		(end 143.525501 208.770204)
		(width 0.22)
		(layer "F.Cu")
		(net 611)
	)
	(arc
		(start 160.784352 186.44115)
		(mid 161.917198 188.136574)
		(end 162.315001 190.136463)
		(width 0.22)
		(layer "F.Cu")
		(net 611)
	)
	(arc
		(start 157.301812 184.910501)
		(mid 159.105124 185.269201)
		(end 160.633898 186.290696)
		(width 0.22)
		(layer "F.Cu")
		(net 611)
	)
	(arc
		(start 149.01225 181.337749)
		(mid 148.985051 181.378454)
		(end 148.975501 181.42647)
		(width 0.1)
		(layer "F.Cu")
		(net 611)
	)
	(arc
		(start 160.047495 197.646708)
		(mid 158.282129 198.826287)
		(end 156.199739 199.240501)
		(width 0.22)
		(layer "F.Cu")
		(net 611)
	)
	(arc
		(start 162.315001 193.125239)
		(mid 161.900787 195.207629)
		(end 160.721207 196.972995)
		(width 0.22)
		(layer "F.Cu")
		(net 611)
	)
	(arc
		(start 143.215501 208.021797)
		(mid 143.255784 208.224314)
		(end 143.370501 208.396001)
		(width 0.22)
		(layer "F.Cu")
		(net 611)
	)
	(arc
		(start 153.969784 183.530364)
		(mid 155.498498 184.551817)
		(end 157.301812 184.910501)
		(width 0.22)
		(layer "F.Cu")
		(net 611)
	)
	(arc
		(start 152.39671 182.080788)
		(mid 152.493407 182.14539)
		(end 152.607475 182.168055)
		(width 0.1)
		(layer "F.Cu")
		(net 611)
	)
	(arc
		(start 148.975501 181.454289)
		(mid 148.990164 181.528005)
		(end 149.031921 181.590499)
		(width 0.1)
		(layer "F.Cu")
		(net 611)
	)
	(arc
		(start 151.712784 181.701)
		(mid 151.993771 181.756892)
		(end 152.231981 181.916059)
		(width 0.1)
		(layer "F.Cu")
		(net 611)
	)
	(arc
		(start 149.058961 181.617539)
		(mid 149.151406 181.679309)
		(end 149.260452 181.701)
		(width 0.1)
		(layer "F.Cu")
		(net 611)
	)
	(arc
		(start 144.829852 201.014351)
		(mid 143.635057 202.802493)
		(end 143.215501 204.911749)
		(width 0.22)
		(layer "F.Cu")
		(net 611)
	)
	(arc
		(start 149.100971 181.301)
		(mid 149.052955 181.31055)
		(end 149.01225 181.337749)
		(width 0.1)
		(layer "F.Cu")
		(net 611)
	)
	(arc
		(start 148.766795 199.240501)
		(mid 146.76835 199.638018)
		(end 145.074153 200.770049)
		(width 0.22)
		(layer "F.Cu")
		(net 611)
	)
	(segment
		(start 127.376501 186.301)
		(end 126.877002 186.8005)
		(width 0.256)
		(layer "F.Cu")
		(net 612)
	)
	(via
		(at 126.877002 186.8005)
		(size 0.45)
		(drill 0.1)
		(layers "F.Cu" "B.Cu")
		(net 612)
	)
	(segment
		(start 124.75 187.365)
		(end 126.312502 187.365)
		(width 0.182)
		(layer "B.Cu")
		(net 612)
	)
	(segment
		(start 124.2 186.2)
		(end 123.7 186.7)
		(width 0.182)
		(layer "B.Cu")
		(net 612)
	)
	(segment
		(start 126.312502 187.365)
		(end 126.877002 186.8005)
		(width 0.182)
		(layer "B.Cu")
		(net 612)
	)
	(segment
		(start 124.235 187.365)
		(end 124.75 187.365)
		(width 0.182)
		(layer "B.Cu")
		(net 612)
	)
	(segment
		(start 123.7 187.365)
		(end 124.235 187.365)
		(width 0.182)
		(layer "B.Cu")
		(net 612)
	)
	(segment
		(start 123.7 186.7)
		(end 123.7 187.365)
		(width 0.182)
		(layer "B.Cu")
		(net 612)
	)
	(segment
		(start 94.100501 129.393921)
		(end 93.738501 129.031921)
		(width 0.15)
		(layer "F.Cu")
		(net 613)
	)
	(segment
		(start 94.100501 130.199)
		(end 94.100501 129.393921)
		(width 0.15)
		(layer "F.Cu")
		(net 613)
	)
	(segment
		(start 145.375501 179.301)
		(end 145.875001 179.8005)
		(width 0.256)
		(layer "F.Cu")
		(net 613)
	)
	(segment
		(start 94.100501 131.100501)
		(end 94.100501 130.3)
		(width 0.15)
		(layer "F.Cu")
		(net 613)
	)
	(segment
		(start 93.738501 129.031921)
		(end 93.738501 127.206921)
		(width 0.15)
		(layer "F.Cu")
		(net 613)
	)
	(segment
		(start 95.1 132.1)
		(end 94.100501 131.100501)
		(width 0.15)
		(layer "F.Cu")
		(net 613)
	)
	(via
		(at 145.875001 179.8005)
		(size 0.45)
		(drill 0.1)
		(layers "F.Cu" "B.Cu")
		(net 613)
	)
	(via
		(at 95.1 132.1)
		(size 0.45)
		(drill 0.1)
		(layers "F.Cu" "B.Cu")
		(net 613)
	)
	(segment
		(start 142.500001 180.199999)
		(end 142.725002 180.425)
		(width 0.1)
		(layer "In4.Cu")
		(net 613)
	)
	(segment
		(start 101.04042 160.1)
		(end 101.21992 159.9205)
		(width 0.1)
		(layer "In4.Cu")
		(net 613)
	)
	(segment
		(start 142.725002 180.425)
		(end 145.625 180.425)
		(width 0.1)
		(layer "In4.Cu")
		(net 613)
	)
	(segment
		(start 127.89717 179.25)
		(end 142.1 179.25)
		(width 0.1)
		(layer "In4.Cu")
		(net 613)
	)
	(segment
		(start 87.1 160.1)
		(end 101.04042 160.1)
		(width 0.1)
		(layer "In4.Cu")
		(net 613)
	)
	(segment
		(start 127.174499 181.225501)
		(end 127.35 181.05)
		(width 0.1)
		(layer "In4.Cu")
		(net 613)
	)
	(segment
		(start 113.9 171.750499)
		(end 113.9 179.65)
		(width 0.1)
		(layer "In4.Cu")
		(net 613)
	)
	(segment
		(start 95.1 140.8)
		(end 83.2 152.7)
		(width 0.1)
		(layer "In4.Cu")
		(net 613)
	)
	(segment
		(start 126.4 182)
		(end 126.4 181.7)
		(width 0.1)
		(layer "In4.Cu")
		(net 613)
	)
	(segment
		(start 145.875001 180.174999)
		(end 145.875001 179.8005)
		(width 0.1)
		(layer "In4.Cu")
		(net 613)
	)
	(segment
		(start 122.4 181.55)
		(end 123.15 182.3)
		(width 0.1)
		(layer "In4.Cu")
		(net 613)
	)
	(segment
		(start 115.8 181.55)
		(end 122.4 181.55)
		(width 0.1)
		(layer "In4.Cu")
		(net 613)
	)
	(segment
		(start 95.1 132.1)
		(end 95.1 140.8)
		(width 0.1)
		(layer "In4.Cu")
		(net 613)
	)
	(segment
		(start 127.35 179.79717)
		(end 127.89717 179.25)
		(width 0.1)
		(layer "In4.Cu")
		(net 613)
	)
	(segment
		(start 145.625 180.425)
		(end 145.875001 180.174999)
		(width 0.1)
		(layer "In4.Cu")
		(net 613)
	)
	(segment
		(start 142.500001 179.650001)
		(end 142.500001 180.199999)
		(width 0.1)
		(layer "In4.Cu")
		(net 613)
	)
	(segment
		(start 127.35 181.05)
		(end 127.35 179.79717)
		(width 0.1)
		(layer "In4.Cu")
		(net 613)
	)
	(segment
		(start 126.874499 181.225501)
		(end 127.174499 181.225501)
		(width 0.1)
		(layer "In4.Cu")
		(net 613)
	)
	(segment
		(start 83.2 156.2)
		(end 87.1 160.1)
		(width 0.1)
		(layer "In4.Cu")
		(net 613)
	)
	(segment
		(start 126.4 181.7)
		(end 126.874499 181.225501)
		(width 0.1)
		(layer "In4.Cu")
		(net 613)
	)
	(segment
		(start 126.1 182.3)
		(end 126.4 182)
		(width 0.1)
		(layer "In4.Cu")
		(net 613)
	)
	(segment
		(start 142.1 179.25)
		(end 142.500001 179.650001)
		(width 0.1)
		(layer "In4.Cu")
		(net 613)
	)
	(segment
		(start 101.21992 159.9205)
		(end 102.070001 159.9205)
		(width 0.1)
		(layer "In4.Cu")
		(net 613)
	)
	(segment
		(start 102.070001 159.9205)
		(end 113.9 171.750499)
		(width 0.1)
		(layer "In4.Cu")
		(net 613)
	)
	(segment
		(start 83.2 152.7)
		(end 83.2 156.2)
		(width 0.1)
		(layer "In4.Cu")
		(net 613)
	)
	(segment
		(start 113.9 179.65)
		(end 115.8 181.55)
		(width 0.1)
		(layer "In4.Cu")
		(net 613)
	)
	(segment
		(start 123.15 182.3)
		(end 126.1 182.3)
		(width 0.1)
		(layer "In4.Cu")
		(net 613)
	)
	(segment
		(start 93.5 131.4)
		(end 92.200501 131.4)
		(width 0.15)
		(layer "F.Cu")
		(net 614)
	)
	(segment
		(start 92.200501 131.4)
		(end 91.100501 130.3)
		(width 0.15)
		(layer "F.Cu")
		(net 614)
	)
	(segment
		(start 94.2 132.1)
		(end 93.5 131.4)
		(width 0.15)
		(layer "F.Cu")
		(net 614)
	)
	(segment
		(start 145.375501 181.301)
		(end 145.875001 181.8005)
		(width 0.256)
		(layer "F.Cu")
		(net 614)
	)
	(segment
		(start 90.748501 128.961921)
		(end 90.748501 127.216921)
		(width 0.15)
		(layer "F.Cu")
		(net 614)
	)
	(segment
		(start 91.100501 130.199)
		(end 91.100501 129.313921)
		(width 0.15)
		(layer "F.Cu")
		(net 614)
	)
	(segment
		(start 91.100501 129.313921)
		(end 90.748501 128.961921)
		(width 0.15)
		(layer "F.Cu")
		(net 614)
	)
	(via
		(at 94.2 132.1)
		(size 0.45)
		(drill 0.1)
		(layers "F.Cu" "B.Cu")
		(net 614)
	)
	(via
		(at 145.875001 181.8005)
		(size 0.45)
		(drill 0.1)
		(layers "F.Cu" "B.Cu")
		(net 614)
	)
	(segment
		(start 145.38775 182.61225)
		(end 145.875001 182.124999)
		(width 0.1)
		(layer "In4.Cu")
		(net 614)
	)
	(segment
		(start 126.7745 182.2255)
		(end 138.3755 182.2255)
		(width 0.1)
		(layer "In4.Cu")
		(net 614)
	)
	(segment
		(start 145.1 183.3)
		(end 145.38775 183.01225)
		(width 0.1)
		(layer "In4.Cu")
		(net 614)
	)
	(segment
		(start 94.2 140.9)
		(end 86 149.1)
		(width 0.1)
		(layer "In4.Cu")
		(net 614)
	)
	(segment
		(start 126.4 183.05)
		(end 126.4 182.6)
		(width 0.1)
		(layer "In4.Cu")
		(net 614)
	)
	(segment
		(start 145.38775 183.01225)
		(end 145.38775 182.61225)
		(width 0.1)
		(layer "In4.Cu")
		(net 614)
	)
	(segment
		(start 138.3755 182.2255)
		(end 139.45 183.3)
		(width 0.1)
		(layer "In4.Cu")
		(net 614)
	)
	(segment
		(start 122.95 183.3)
		(end 126.15 183.3)
		(width 0.1)
		(layer "In4.Cu")
		(net 614)
	)
	(segment
		(start 113 179.7)
		(end 115.8 182.5)
		(width 0.1)
		(layer "In4.Cu")
		(net 614)
	)
	(segment
		(start 83 149.1)
		(end 82.6 149.5)
		(width 0.1)
		(layer "In4.Cu")
		(net 614)
	)
	(segment
		(start 126.4 182.6)
		(end 126.7745 182.2255)
		(width 0.1)
		(layer "In4.Cu")
		(net 614)
	)
	(segment
		(start 122.15 182.5)
		(end 122.95 183.3)
		(width 0.1)
		(layer "In4.Cu")
		(net 614)
	)
	(segment
		(start 139.45 183.3)
		(end 145.1 183.3)
		(width 0.1)
		(layer "In4.Cu")
		(net 614)
	)
	(segment
		(start 115.8 182.5)
		(end 122.15 182.5)
		(width 0.1)
		(layer "In4.Cu")
		(net 614)
	)
	(segment
		(start 145.875001 182.124999)
		(end 145.875001 181.8005)
		(width 0.1)
		(layer "In4.Cu")
		(net 614)
	)
	(segment
		(start 101.2 160.7)
		(end 113 172.5)
		(width 0.1)
		(layer "In4.Cu")
		(net 614)
	)
	(segment
		(start 86 149.1)
		(end 83 149.1)
		(width 0.1)
		(layer "In4.Cu")
		(net 614)
	)
	(segment
		(start 94.2 132.1)
		(end 94.2 140.9)
		(width 0.1)
		(layer "In4.Cu")
		(net 614)
	)
	(segment
		(start 86.8 160.7)
		(end 101.2 160.7)
		(width 0.1)
		(layer "In4.Cu")
		(net 614)
	)
	(segment
		(start 82.6 156.5)
		(end 86.8 160.7)
		(width 0.1)
		(layer "In4.Cu")
		(net 614)
	)
	(segment
		(start 126.15 183.3)
		(end 126.4 183.05)
		(width 0.1)
		(layer "In4.Cu")
		(net 614)
	)
	(segment
		(start 113 172.5)
		(end 113 179.7)
		(width 0.1)
		(layer "In4.Cu")
		(net 614)
	)
	(segment
		(start 82.6 149.5)
		(end 82.6 156.5)
		(width 0.1)
		(layer "In4.Cu")
		(net 614)
	)
	(segment
		(start 83.000501 123.876)
		(end 83.000501 124.606)
		(width 0.15)
		(layer "F.Cu")
		(net 615)
	)
	(segment
		(start 131.376501 184.301)
		(end 130.877001 184.8005)
		(width 0.256)
		(layer "F.Cu")
		(net 615)
	)
	(via
		(at 130.877001 184.8005)
		(size 0.45)
		(drill 0.1)
		(layers "F.Cu" "B.Cu")
		(net 615)
	)
	(via
		(at 83.000501 124.606)
		(size 0.45)
		(drill 0.1)
		(layers "F.Cu" "B.Cu")
		(net 615)
	)
	(segment
		(start 132.4 186.518998)
		(end 132.181002 186.3)
		(width 0.1)
		(layer "In4.Cu")
		(net 615)
	)
	(segment
		(start 124.2 189.1)
		(end 131.4 189.1)
		(width 0.1)
		(layer "In4.Cu")
		(net 615)
	)
	(segment
		(start 108.5 184.5)
		(end 112.2 188.2)
		(width 0.1)
		(layer "In4.Cu")
		(net 615)
	)
	(segment
		(start 130.6 186.3)
		(end 130.4 186.1)
		(width 0.1)
		(layer "In4.Cu")
		(net 615)
	)
	(segment
		(start 130.4 185.277501)
		(end 130.877001 184.8005)
		(width 0.1)
		(layer "In4.Cu")
		(net 615)
	)
	(segment
		(start 130.4 186.1)
		(end 130.4 185.277501)
		(width 0.1)
		(layer "In4.Cu")
		(net 615)
	)
	(segment
		(start 131.4 189.1)
		(end 132.4 188.1)
		(width 0.1)
		(layer "In4.Cu")
		(net 615)
	)
	(segment
		(start 119.55 188.2)
		(end 120.7 189.35)
		(width 0.1)
		(layer "In4.Cu")
		(net 615)
	)
	(segment
		(start 123.95 189.35)
		(end 124.2 189.1)
		(width 0.1)
		(layer "In4.Cu")
		(net 615)
	)
	(segment
		(start 112.2 188.2)
		(end 119.55 188.2)
		(width 0.1)
		(layer "In4.Cu")
		(net 615)
	)
	(segment
		(start 132.181002 186.3)
		(end 130.6 186.3)
		(width 0.1)
		(layer "In4.Cu")
		(net 615)
	)
	(segment
		(start 83.000501 124.606)
		(end 89.5 131.1055)
		(width 0.1)
		(layer "In4.Cu")
		(net 615)
	)
	(segment
		(start 84.02 146.98)
		(end 80.76 146.98)
		(width 0.1)
		(layer "In4.Cu")
		(net 615)
	)
	(segment
		(start 89.5 131.1055)
		(end 89.5 141.5)
		(width 0.1)
		(layer "In4.Cu")
		(net 615)
	)
	(segment
		(start 120.7 189.35)
		(end 123.95 189.35)
		(width 0.1)
		(layer "In4.Cu")
		(net 615)
	)
	(segment
		(start 85.4 164)
		(end 99.7 164)
		(width 0.1)
		(layer "In4.Cu")
		(net 615)
	)
	(segment
		(start 79.2 157.8)
		(end 85.4 164)
		(width 0.1)
		(layer "In4.Cu")
		(net 615)
	)
	(segment
		(start 89.5 141.5)
		(end 84.02 146.98)
		(width 0.1)
		(layer "In4.Cu")
		(net 615)
	)
	(segment
		(start 79.2 148.54)
		(end 79.2 157.8)
		(width 0.1)
		(layer "In4.Cu")
		(net 615)
	)
	(segment
		(start 99.7 164)
		(end 108.5 172.8)
		(width 0.1)
		(layer "In4.Cu")
		(net 615)
	)
	(segment
		(start 132.4 188.1)
		(end 132.4 186.518998)
		(width 0.1)
		(layer "In4.Cu")
		(net 615)
	)
	(segment
		(start 80.76 146.98)
		(end 79.2 148.54)
		(width 0.1)
		(layer "In4.Cu")
		(net 615)
	)
	(segment
		(start 108.5 172.8)
		(end 108.5 184.5)
		(width 0.1)
		(layer "In4.Cu")
		(net 615)
	)
	(segment
		(start 131.376501 186.301)
		(end 130.877001 186.8005)
		(width 0.256)
		(layer "F.Cu")
		(net 617)
	)
	(segment
		(start 88.400501 123.876)
		(end 88.400501 124.606)
		(width 0.15)
		(layer "F.Cu")
		(net 617)
	)
	(via
		(at 88.400501 124.606)
		(size 0.45)
		(drill 0.1)
		(layers "F.Cu" "B.Cu")
		(net 617)
	)
	(via
		(at 130.877001 186.8005)
		(size 0.45)
		(drill 0.1)
		(layers "F.Cu" "B.Cu")
		(net 617)
	)
	(segment
		(start 80.2 157.000499)
		(end 85.499501 162.3)
		(width 0.1)
		(layer "In4.Cu")
		(net 617)
	)
	(segment
		(start 84.8 147.8)
		(end 81.6 147.8)
		(width 0.1)
		(layer "In4.Cu")
		(net 617)
	)
	(segment
		(start 85.499501 162.3)
		(end 100.579832 162.3)
		(width 0.1)
		(layer "In4.Cu")
		(net 617)
	)
	(segment
		(start 110.25 183)
		(end 113.225 185.975)
		(width 0.1)
		(layer "In4.Cu")
		(net 617)
	)
	(segment
		(start 91 129.905499)
		(end 91 141.6)
		(width 0.1)
		(layer "In4.Cu")
		(net 617)
	)
	(segment
		(start 130.377501 187.3)
		(end 130.877001 186.8005)
		(width 0.1)
		(layer "In4.Cu")
		(net 617)
	)
	(segment
		(start 91.4 129.505499)
		(end 91 129.905499)
		(width 0.1)
		(layer "In4.Cu")
		(net 617)
	)
	(segment
		(start 81.6 147.8)
		(end 80.2 149.2)
		(width 0.1)
		(layer "In4.Cu")
		(net 617)
	)
	(segment
		(start 110.25 172.45)
		(end 110.25 183)
		(width 0.1)
		(layer "In4.Cu")
		(net 617)
	)
	(segment
		(start 88.400501 124.606)
		(end 88.400501 125.600501)
		(width 0.1)
		(layer "In4.Cu")
		(net 617)
	)
	(segment
		(start 100.875501 162.595669)
		(end 100.875501 163.075501)
		(width 0.1)
		(layer "In4.Cu")
		(net 617)
	)
	(segment
		(start 113.225 185.975)
		(end 120.725 185.975)
		(width 0.1)
		(layer "In4.Cu")
		(net 617)
	)
	(segment
		(start 91 141.6)
		(end 84.8 147.8)
		(width 0.1)
		(layer "In4.Cu")
		(net 617)
	)
	(segment
		(start 100.579832 162.3)
		(end 100.875501 162.595669)
		(width 0.1)
		(layer "In4.Cu")
		(net 617)
	)
	(segment
		(start 91.4 128.6)
		(end 91.4 129.505499)
		(width 0.1)
		(layer "In4.Cu")
		(net 617)
	)
	(segment
		(start 88.400501 125.600501)
		(end 91.4 128.6)
		(width 0.1)
		(layer "In4.Cu")
		(net 617)
	)
	(segment
		(start 80.2 149.2)
		(end 80.2 157.000499)
		(width 0.1)
		(layer "In4.Cu")
		(net 617)
	)
	(segment
		(start 120.725 185.975)
		(end 122.05 187.3)
		(width 0.1)
		(layer "In4.Cu")
		(net 617)
	)
	(segment
		(start 100.875501 163.075501)
		(end 110.25 172.45)
		(width 0.1)
		(layer "In4.Cu")
		(net 617)
	)
	(segment
		(start 122.05 187.3)
		(end 130.377501 187.3)
		(width 0.1)
		(layer "In4.Cu")
		(net 617)
	)
	(segment
		(start 85.700501 123.876)
		(end 85.700501 124.606)
		(width 0.15)
		(layer "F.Cu")
		(net 619)
	)
	(segment
		(start 132.376501 186.301)
		(end 131.877 186.8005)
		(width 0.256)
		(layer "F.Cu")
		(net 619)
	)
	(via
		(at 131.877 186.8005)
		(size 0.45)
		(drill 0.1)
		(layers "F.Cu" "B.Cu")
		(net 619)
	)
	(via
		(at 85.700501 124.606)
		(size 0.45)
		(drill 0.1)
		(layers "F.Cu" "B.Cu")
		(net 619)
	)
	(segment
		(start 90.2 129.8)
		(end 90.2 141.65)
		(width 0.1)
		(layer "In4.Cu")
		(net 619)
	)
	(segment
		(start 85.700501 125.300501)
		(end 90.2 129.8)
		(width 0.1)
		(layer "In4.Cu")
		(net 619)
	)
	(segment
		(start 79.7 148.8)
		(end 79.7 157.4)
		(width 0.1)
		(layer "In4.Cu")
		(net 619)
	)
	(segment
		(start 90.2 141.65)
		(end 84.41 147.44)
		(width 0.1)
		(layer "In4.Cu")
		(net 619)
	)
	(segment
		(start 79.7 157.4)
		(end 85.8 163.5)
		(width 0.1)
		(layer "In4.Cu")
		(net 619)
	)
	(segment
		(start 131.13875 188.3)
		(end 131.33875 188.1)
		(width 0.1)
		(layer "In4.Cu")
		(net 619)
	)
	(segment
		(start 85.8 163.5)
		(end 100.375 163.5)
		(width 0.1)
		(layer "In4.Cu")
		(net 619)
	)
	(segment
		(start 120.95 188.3)
		(end 131.13875 188.3)
		(width 0.1)
		(layer "In4.Cu")
		(net 619)
	)
	(segment
		(start 84.41 147.44)
		(end 81.06 147.44)
		(width 0.1)
		(layer "In4.Cu")
		(net 619)
	)
	(segment
		(start 131.33875 188.1)
		(end 131.33875 187.33875)
		(width 0.1)
		(layer "In4.Cu")
		(net 619)
	)
	(segment
		(start 109.4 183.95)
		(end 112.35 186.9)
		(width 0.1)
		(layer "In4.Cu")
		(net 619)
	)
	(segment
		(start 112.35 186.9)
		(end 119.55 186.9)
		(width 0.1)
		(layer "In4.Cu")
		(net 619)
	)
	(segment
		(start 109.4 172.525)
		(end 109.4 183.95)
		(width 0.1)
		(layer "In4.Cu")
		(net 619)
	)
	(segment
		(start 85.700501 124.606)
		(end 85.700501 125.300501)
		(width 0.1)
		(layer "In4.Cu")
		(net 619)
	)
	(segment
		(start 119.55 186.9)
		(end 120.95 188.3)
		(width 0.1)
		(layer "In4.Cu")
		(net 619)
	)
	(segment
		(start 100.375 163.5)
		(end 109.4 172.525)
		(width 0.1)
		(layer "In4.Cu")
		(net 619)
	)
	(segment
		(start 81.06 147.44)
		(end 79.7 148.8)
		(width 0.1)
		(layer "In4.Cu")
		(net 619)
	)
	(segment
		(start 131.33875 187.33875)
		(end 131.877 186.8005)
		(width 0.1)
		(layer "In4.Cu")
		(net 619)
	)
	(segment
		(start 91.100501 123.876)
		(end 91.100501 124.606)
		(width 0.15)
		(layer "F.Cu")
		(net 621)
	)
	(segment
		(start 130.376501 185.301)
		(end 129.877001 185.8005)
		(width 0.256)
		(layer "F.Cu")
		(net 621)
	)
	(via
		(at 129.877001 185.8005)
		(size 0.45)
		(drill 0.1)
		(layers "F.Cu" "B.Cu")
		(net 621)
	)
	(via
		(at 91.100501 124.606)
		(size 0.45)
		(drill 0.1)
		(layers "F.Cu" "B.Cu")
		(net 621)
	)
	(segment
		(start 129.466501 186.3)
		(end 129.877001 185.8895)
		(width 0.1)
		(layer "In4.Cu")
		(net 621)
	)
	(segment
		(start 122.6 186.3)
		(end 129.466501 186.3)
		(width 0.1)
		(layer "In4.Cu")
		(net 621)
	)
	(segment
		(start 92.2 131.5)
		(end 91.8 131.9)
		(width 0.1)
		(layer "In4.Cu")
		(net 621)
	)
	(segment
		(start 121.525 185.225)
		(end 122.6 186.3)
		(width 0.1)
		(layer "In4.Cu")
		(net 621)
	)
	(segment
		(start 129.877001 185.8895)
		(end 129.877001 185.8005)
		(width 0.1)
		(layer "In4.Cu")
		(net 621)
	)
	(segment
		(start 111.15 182.35)
		(end 114.025 185.225)
		(width 0.1)
		(layer "In4.Cu")
		(net 621)
	)
	(segment
		(start 92.2 125.705499)
		(end 92.2 131.5)
		(width 0.1)
		(layer "In4.Cu")
		(net 621)
	)
	(segment
		(start 91.8 141.6)
		(end 85.2 148.2)
		(width 0.1)
		(layer "In4.Cu")
		(net 621)
	)
	(segment
		(start 114.025 185.225)
		(end 121.525 185.225)
		(width 0.1)
		(layer "In4.Cu")
		(net 621)
	)
	(segment
		(start 102.000501 163.100501)
		(end 111.15 172.25)
		(width 0.1)
		(layer "In4.Cu")
		(net 621)
	)
	(segment
		(start 111.15 172.25)
		(end 111.15 182.35)
		(width 0.1)
		(layer "In4.Cu")
		(net 621)
	)
	(segment
		(start 102.000501 162.560314)
		(end 102.000501 163.100501)
		(width 0.1)
		(layer "In4.Cu")
		(net 621)
	)
	(segment
		(start 101.240187 161.8)
		(end 102.000501 162.560314)
		(width 0.1)
		(layer "In4.Cu")
		(net 621)
	)
	(segment
		(start 86 161.8)
		(end 101.240187 161.8)
		(width 0.1)
		(layer "In4.Cu")
		(net 621)
	)
	(segment
		(start 81.5 148.8)
		(end 81.5 157.3)
		(width 0.1)
		(layer "In4.Cu")
		(net 621)
	)
	(segment
		(start 81.5 157.3)
		(end 86 161.8)
		(width 0.1)
		(layer "In4.Cu")
		(net 621)
	)
	(segment
		(start 85.2 148.2)
		(end 82.1 148.2)
		(width 0.1)
		(layer "In4.Cu")
		(net 621)
	)
	(segment
		(start 82.1 148.2)
		(end 81.5 148.8)
		(width 0.1)
		(layer "In4.Cu")
		(net 621)
	)
	(segment
		(start 91.8 131.9)
		(end 91.8 141.6)
		(width 0.1)
		(layer "In4.Cu")
		(net 621)
	)
	(segment
		(start 91.100501 124.606)
		(end 92.2 125.705499)
		(width 0.1)
		(layer "In4.Cu")
		(net 621)
	)
	(segment
		(start 130.376501 183.301)
		(end 129.877001 183.8005)
		(width 0.256)
		(layer "F.Cu")
		(net 622)
	)
	(segment
		(start 93.800501 123.876)
		(end 93.800501 124.606)
		(width 0.15)
		(layer "F.Cu")
		(net 622)
	)
	(via
		(at 129.877001 183.8005)
		(size 0.45)
		(drill 0.1)
		(layers "F.Cu" "B.Cu")
		(net 622)
	)
	(via
		(at 93.800501 124.606)
		(size 0.45)
		(drill 0.1)
		(layers "F.Cu" "B.Cu")
		(net 622)
	)
	(segment
		(start 112.05 180.35)
		(end 115.025 183.325)
		(width 0.1)
		(layer "In4.Cu")
		(net 622)
	)
	(segment
		(start 115.025 183.325)
		(end 120.975 183.325)
		(width 0.1)
		(layer "In4.Cu")
		(net 622)
	)
	(segment
		(start 101.2 161.2)
		(end 112.05 172.05)
		(width 0.1)
		(layer "In4.Cu")
		(net 622)
	)
	(segment
		(start 85.6 148.7)
		(end 82.5 148.7)
		(width 0.1)
		(layer "In4.Cu")
		(net 622)
	)
	(segment
		(start 129.877001 184.122999)
		(end 129.877001 183.8005)
		(width 0.1)
		(layer "In4.Cu")
		(net 622)
	)
	(segment
		(start 93.800501 124.606)
		(end 94.415501 125.221)
		(width 0.1)
		(layer "In4.Cu")
		(net 622)
	)
	(segment
		(start 120.975 183.325)
		(end 122.95 185.3)
		(width 0.1)
		(layer "In4.Cu")
		(net 622)
	)
	(segment
		(start 129.7 184.3)
		(end 129.877001 184.122999)
		(width 0.1)
		(layer "In4.Cu")
		(net 622)
	)
	(segment
		(start 129.4 185)
		(end 129.4 184.5)
		(width 0.1)
		(layer "In4.Cu")
		(net 622)
	)
	(segment
		(start 112.05 172.05)
		(end 112.05 180.35)
		(width 0.1)
		(layer "In4.Cu")
		(net 622)
	)
	(segment
		(start 86.4 161.2)
		(end 101.2 161.2)
		(width 0.1)
		(layer "In4.Cu")
		(net 622)
	)
	(segment
		(start 129.6 184.3)
		(end 129.7 184.3)
		(width 0.1)
		(layer "In4.Cu")
		(net 622)
	)
	(segment
		(start 82 149.2)
		(end 82 156.8)
		(width 0.1)
		(layer "In4.Cu")
		(net 622)
	)
	(segment
		(start 82.5 148.7)
		(end 82 149.2)
		(width 0.1)
		(layer "In4.Cu")
		(net 622)
	)
	(segment
		(start 122.95 185.3)
		(end 129.1 185.3)
		(width 0.1)
		(layer "In4.Cu")
		(net 622)
	)
	(segment
		(start 129.4 184.5)
		(end 129.6 184.3)
		(width 0.1)
		(layer "In4.Cu")
		(net 622)
	)
	(segment
		(start 92.5 132.3)
		(end 92.5 141.8)
		(width 0.1)
		(layer "In4.Cu")
		(net 622)
	)
	(segment
		(start 129.1 185.3)
		(end 129.4 185)
		(width 0.1)
		(layer "In4.Cu")
		(net 622)
	)
	(segment
		(start 92.5 141.8)
		(end 85.6 148.7)
		(width 0.1)
		(layer "In4.Cu")
		(net 622)
	)
	(segment
		(start 94.415501 130.384499)
		(end 92.5 132.3)
		(width 0.1)
		(layer "In4.Cu")
		(net 622)
	)
	(segment
		(start 82 156.8)
		(end 86.4 161.2)
		(width 0.1)
		(layer "In4.Cu")
		(net 622)
	)
	(segment
		(start 94.415501 125.221)
		(end 94.415501 130.384499)
		(width 0.1)
		(layer "In4.Cu")
		(net 622)
	)
	(segment
		(start 120.650501 175.926)
		(end 121.150501 176.426)
		(width 0.256)
		(layer "F.Cu")
		(net 623)
	)
	(segment
		(start 128.376501 165.302)
		(end 127.877001 164.8025)
		(width 0.256)
		(layer "F.Cu")
		(net 623)
	)
	(via
		(at 127.877001 164.8025)
		(size 0.45)
		(drill 0.1)
		(layers "F.Cu" "B.Cu")
		(net 623)
	)
	(via
		(at 121.150501 176.426)
		(size 0.45)
		(drill 0.1)
		(layers "F.Cu" "B.Cu")
		(net 623)
	)
	(segment
		(start 121.200501 176.476)
		(end 121.150501 176.426)
		(width 0.256)
		(layer "B.Cu")
		(net 623)
	)
	(segment
		(start 121.865501 176.476)
		(end 121.200501 176.476)
		(width 0.256)
		(layer "B.Cu")
		(net 623)
	)
	(segment
		(start 123.250501 174.326)
		(end 121.150501 176.426)
		(width 0.1)
		(layer "In6.Cu")
		(net 623)
	)
	(segment
		(start 127.539501 165.2255)
		(end 125.453001 165.2255)
		(width 0.1)
		(layer "In6.Cu")
		(net 623)
	)
	(segment
		(start 127.877501 164.8005)
		(end 127.877501 164.8875)
		(width 0.1)
		(layer "In6.Cu")
		(net 623)
	)
	(segment
		(start 123.250501 167.428)
		(end 123.250501 174.326)
		(width 0.1)
		(layer "In6.Cu")
		(net 623)
	)
	(segment
		(start 125.453001 165.2255)
		(end 123.250501 167.428)
		(width 0.1)
		(layer "In6.Cu")
		(net 623)
	)
	(segment
		(start 127.877501 164.8875)
		(end 127.539501 165.2255)
		(width 0.1)
		(layer "In6.Cu")
		(net 623)
	)
	(segment
		(start 126.376501 165.301999)
		(end 125.877001 164.8025)
		(width 0.256)
		(layer "F.Cu")
		(net 624)
	)
	(segment
		(start 120.650501 174.926)
		(end 121.150501 175.426)
		(width 0.256)
		(layer "F.Cu")
		(net 624)
	)
	(via
		(at 125.877001 164.8025)
		(size 0.45)
		(drill 0.1)
		(layers "F.Cu" "B.Cu")
		(net 624)
	)
	(via
		(at 121.150501 175.426)
		(size 0.45)
		(drill 0.1)
		(layers "F.Cu" "B.Cu")
		(net 624)
	)
	(segment
		(start 121.865501 175.426)
		(end 121.150501 175.426)
		(width 0.256)
		(layer "B.Cu")
		(net 624)
	)
	(segment
		(start 125.2995 164.8005)
		(end 125.875001 164.8005)
		(width 0.1)
		(layer "In6.Cu")
		(net 624)
	)
	(segment
		(start 121.150501 175.426)
		(end 122.950501 173.626)
		(width 0.1)
		(layer "In6.Cu")
		(net 624)
	)
	(segment
		(start 125.875001 164.8005)
		(end 125.877001 164.8025)
		(width 0.1)
		(layer "In6.Cu")
		(net 624)
	)
	(segment
		(start 122.950501 167.149499)
		(end 125.2995 164.8005)
		(width 0.1)
		(layer "In6.Cu")
		(net 624)
	)
	(segment
		(start 122.950501 173.626)
		(end 122.950501 167.149499)
		(width 0.1)
		(layer "In6.Cu")
		(net 624)
	)
	(segment
		(start 129.376501 185.300999)
		(end 128.877001 185.8005)
		(width 0.256)
		(layer "F.Cu")
		(net 625)
	)
	(segment
		(start 122.649501 183.8045)
		(end 123.635 183.8045)
		(width 0.256)
		(layer "F.Cu")
		(net 625)
	)
	(segment
		(start 123.635 183.8045)
		(end 123.6495 183.790001)
		(width 0.256)
		(layer "F.Cu")
		(net 625)
	)
	(via
		(at 128.877001 185.8005)
		(size 0.45)
		(drill 0.1)
		(layers "F.Cu" "B.Cu")
		(net 625)
	)
	(via
		(at 123.6495 183.790001)
		(size 0.45)
		(drill 0.1)
		(layers "F.Cu" "B.Cu")
		(net 625)
	)
	(segment
		(start 123.635001 183.100001)
		(end 123.635001 183.7755)
		(width 0.256)
		(layer "B.Cu")
		(net 625)
	)
	(segment
		(start 123.635001 183.7755)
		(end 123.6495 183.790001)
		(width 0.256)
		(layer "B.Cu")
		(net 625)
	)
	(segment
		(start 128.330001 185.2535)
		(end 128.330001 184.612861)
		(width 0.1)
		(layer "In6.Cu")
		(net 625)
	)
	(segment
		(start 124.209499 184.35)
		(end 123.6495 183.790001)
		(width 0.1)
		(layer "In6.Cu")
		(net 625)
	)
	(segment
		(start 128.330001 184.612861)
		(end 128.06714 184.35)
		(width 0.1)
		(layer "In6.Cu")
		(net 625)
	)
	(segment
		(start 128.06714 184.35)
		(end 124.209499 184.35)
		(width 0.1)
		(layer "In6.Cu")
		(net 625)
	)
	(segment
		(start 128.877001 185.8005)
		(end 128.330001 185.2535)
		(width 0.1)
		(layer "In6.Cu")
		(net 625)
	)
	(segment
		(start 128.376501 186.301)
		(end 127.877001 186.8005)
		(width 0.256)
		(layer "F.Cu")
		(net 626)
	)
	(segment
		(start 114.375 187.085)
		(end 114.375 187.7)
		(width 0.256)
		(layer "F.Cu")
		(net 626)
	)
	(via
		(at 114.375 187.7)
		(size 0.45)
		(drill 0.1)
		(layers "F.Cu" "B.Cu")
		(net 626)
	)
	(via
		(at 127.877001 186.8005)
		(size 0.45)
		(drill 0.1)
		(layers "F.Cu" "B.Cu")
		(net 626)
	)
	(segment
		(start 129.35 186.55)
		(end 129.6 186.3)
		(width 0.107)
		(layer "In9.Cu")
		(net 626)
	)
	(segment
		(start 116.325 190.325)
		(end 116.325 190.075)
		(width 0.107)
		(layer "In9.Cu")
		(net 626)
	)
	(segment
		(start 129.6 186.3)
		(end 130.1 186.3)
		(width 0.107)
		(layer "In9.Cu")
		(net 626)
	)
	(segment
		(start 128.376501 187.3)
		(end 128.999001 187.3)
		(width 0.107)
		(layer "In9.Cu")
		(net 626)
	)
	(segment
		(start 115.65 190.55)
		(end 115.6 190.55)
		(width 0.107)
		(layer "In9.Cu")
		(net 626)
	)
	(segment
		(start 129.35 186.949001)
		(end 129.35 186.55)
		(width 0.107)
		(layer "In9.Cu")
		(net 626)
	)
	(segment
		(start 121.2 190.55)
		(end 116.55 190.55)
		(width 0.107)
		(layer "In9.Cu")
		(net 626)
	)
	(segment
		(start 114.8 190.55)
		(end 114.7 190.55)
		(width 0.107)
		(layer "In9.Cu")
		(net 626)
	)
	(segment
		(start 127.877001 186.8005)
		(end 128.376501 187.3)
		(width 0.107)
		(layer "In9.Cu")
		(net 626)
	)
	(segment
		(start 114.6 189.6)
		(end 114.9 189.6)
		(width 0.107)
		(layer "In9.Cu")
		(net 626)
	)
	(segment
		(start 130.35 188.85)
		(end 129.5965 189.6035)
		(width 0.107)
		(layer "In9.Cu")
		(net 626)
	)
	(segment
		(start 122.1465 189.6035)
		(end 121.2 190.55)
		(width 0.107)
		(layer "In9.Cu")
		(net 626)
	)
	(segment
		(start 130.1 186.3)
		(end 130.35 186.55)
		(width 0.107)
		(layer "In9.Cu")
		(net 626)
	)
	(segment
		(start 130.35 186.55)
		(end 130.35 188.85)
		(width 0.107)
		(layer "In9.Cu")
		(net 626)
	)
	(segment
		(start 114.805678 190.55)
		(end 114.8 190.55)
		(width 0.107)
		(layer "In9.Cu")
		(net 626)
	)
	(segment
		(start 128.999001 187.3)
		(end 129.35 186.949001)
		(width 0.107)
		(layer "In9.Cu")
		(net 626)
	)
	(segment
		(start 115.205678 190.155678)
		(end 115.2 190.155678)
		(width 0.107)
		(layer "In9.Cu")
		(net 626)
	)
	(segment
		(start 114.7 190.55)
		(end 114.375 190.225)
		(width 0.107)
		(layer "In9.Cu")
		(net 626)
	)
	(segment
		(start 115.875 190.075)
		(end 115.875 190.325)
		(width 0.107)
		(layer "In9.Cu")
		(net 626)
	)
	(segment
		(start 114.9 189.15)
		(end 114.6 189.15)
		(width 0.107)
		(layer "In9.Cu")
		(net 626)
	)
	(segment
		(start 129.5965 189.6035)
		(end 122.1465 189.6035)
		(width 0.107)
		(layer "In9.Cu")
		(net 626)
	)
	(segment
		(start 114.375 190.225)
		(end 114.375 189.825)
		(width 0.107)
		(layer "In9.Cu")
		(net 626)
	)
	(segment
		(start 114.6 188.65)
		(end 114.95 188.65)
		(width 0.107)
		(layer "In9.Cu")
		(net 626)
	)
	(segment
		(start 114.375 188.925)
		(end 114.375 188.875)
		(width 0.107)
		(layer "In9.Cu")
		(net 626)
	)
	(segment
		(start 114.375 187.975)
		(end 114.375 187.7)
		(width 0.107)
		(layer "In9.Cu")
		(net 626)
	)
	(segment
		(start 114.95 188.2)
		(end 114.6 188.2)
		(width 0.107)
		(layer "In9.Cu")
		(net 626)
	)
	(arc
		(start 115.875 190.325)
		(mid 115.809099 190.484099)
		(end 115.65 190.55)
		(width 0.107)
		(layer "In9.Cu")
		(net 626)
	)
	(arc
		(start 115.002839 190.352839)
		(mid 114.945092 190.492253)
		(end 114.805678 190.55)
		(width 0.107)
		(layer "In9.Cu")
		(net 626)
	)
	(arc
		(start 114.9 189.6)
		(mid 115.059099 189.534099)
		(end 115.125 189.375)
		(width 0.107)
		(layer "In9.Cu")
		(net 626)
	)
	(arc
		(start 116.1 189.85)
		(mid 115.940901 189.915901)
		(end 115.875 190.075)
		(width 0.107)
		(layer "In9.Cu")
		(net 626)
	)
	(arc
		(start 115.6 190.55)
		(mid 115.460586 190.492253)
		(end 115.402839 190.352839)
		(width 0.107)
		(layer "In9.Cu")
		(net 626)
	)
	(arc
		(start 114.6 188.2)
		(mid 114.440901 188.134099)
		(end 114.375 187.975)
		(width 0.107)
		(layer "In9.Cu")
		(net 626)
	)
	(arc
		(start 115.175 188.425)
		(mid 115.109099 188.265901)
		(end 114.95 188.2)
		(width 0.107)
		(layer "In9.Cu")
		(net 626)
	)
	(arc
		(start 114.375 189.825)
		(mid 114.440901 189.665901)
		(end 114.6 189.6)
		(width 0.107)
		(layer "In9.Cu")
		(net 626)
	)
	(arc
		(start 116.55 190.55)
		(mid 116.390901 190.484099)
		(end 116.325 190.325)
		(width 0.107)
		(layer "In9.Cu")
		(net 626)
	)
	(arc
		(start 114.95 188.65)
		(mid 115.109099 188.584099)
		(end 115.175 188.425)
		(width 0.107)
		(layer "In9.Cu")
		(net 626)
	)
	(arc
		(start 114.6 189.15)
		(mid 114.440901 189.084099)
		(end 114.375 188.925)
		(width 0.107)
		(layer "In9.Cu")
		(net 626)
	)
	(arc
		(start 116.325 190.075)
		(mid 116.259099 189.915901)
		(end 116.1 189.85)
		(width 0.107)
		(layer "In9.Cu")
		(net 626)
	)
	(arc
		(start 115.402839 190.352839)
		(mid 115.345092 190.213425)
		(end 115.205678 190.155678)
		(width 0.107)
		(layer "In9.Cu")
		(net 626)
	)
	(arc
		(start 115.2 190.155678)
		(mid 115.060586 190.213425)
		(end 115.002839 190.352839)
		(width 0.107)
		(layer "In9.Cu")
		(net 626)
	)
	(arc
		(start 114.375 188.875)
		(mid 114.440901 188.715901)
		(end 114.6 188.65)
		(width 0.107)
		(layer "In9.Cu")
		(net 626)
	)
	(arc
		(start 115.125 189.375)
		(mid 115.059099 189.215901)
		(end 114.9 189.15)
		(width 0.107)
		(layer "In9.Cu")
		(net 626)
	)
	(segment
		(start 121.774499 187.085)
		(end 121.774499 187.7)
		(width 0.256)
		(layer "F.Cu")
		(net 627)
	)
	(segment
		(start 127.3765 187.301)
		(end 126.877001 187.8005)
		(width 0.256)
		(layer "F.Cu")
		(net 627)
	)
	(via
		(at 126.877001 187.8005)
		(size 0.45)
		(drill 0.1)
		(layers "F.Cu" "B.Cu")
		(net 627)
	)
	(via
		(at 121.774499 187.7)
		(size 0.45)
		(drill 0.1)
		(layers "F.Cu" "B.Cu")
		(net 627)
	)
	(segment
		(start 122.225 186.65)
		(end 122.225 186.180159)
		(width 0.1)
		(layer "In9.Cu")
		(net 627)
	)
	(segment
		(start 119.425 186.65)
		(end 119.425 186.180159)
		(width 0.1)
		(layer "In9.Cu")
		(net 627)
	)
	(segment
		(start 117.75 186.75)
		(end 117.85 186.65)
		(width 0.1)
		(layer "In9.Cu")
		(net 627)
	)
	(segment
		(start 121.525 187.119841)
		(end 121.525 186.65)
		(width 0.1)
		(layer "In9.Cu")
		(net 627)
	)
	(segment
		(start 118.725 187.119841)
		(end 118.725 186.65)
		(width 0.1)
		(layer "In9.Cu")
		(net 627)
	)
	(segment
		(start 122.225 187.119841)
		(end 122.225 186.65)
		(width 0.1)
		(layer "In9.Cu")
		(net 627)
	)
	(segment
		(start 119.075 186.180159)
		(end 119.075 186.65)
		(width 0.1)
		(layer "In9.Cu")
		(net 627)
	)
	(segment
		(start 119.775 186.65)
		(end 119.775 187.119841)
		(width 0.1)
		(layer "In9.Cu")
		(net 627)
	)
	(segment
		(start 121.875 186.180159)
		(end 121.875 186.65)
		(width 0.1)
		(layer "In9.Cu")
		(net 627)
	)
	(segment
		(start 118.375 186.475)
		(end 118.375 187.119841)
		(width 0.1)
		(layer "In9.Cu")
		(net 627)
	)
	(segment
		(start 121.525 186.65)
		(end 121.525 186.180159)
		(width 0.1)
		(layer "In9.Cu")
		(net 627)
	)
	(segment
		(start 121.175 186.180159)
		(end 121.175 186.65)
		(width 0.1)
		(layer "In9.Cu")
		(net 627)
	)
	(segment
		(start 117.85 187.7)
		(end 117.75 187.6)
		(width 0.1)
		(layer "In9.Cu")
		(net 627)
	)
	(segment
		(start 121.175 186.65)
		(end 121.175 187.119841)
		(width 0.1)
		(layer "In9.Cu")
		(net 627)
	)
	(segment
		(start 126.477501 188.2)
		(end 126.877001 187.8005)
		(width 0.1)
		(layer "In9.Cu")
		(net 627)
	)
	(segment
		(start 121.875 186.65)
		(end 121.875 187.119841)
		(width 0.1)
		(layer "In9.Cu")
		(net 627)
	)
	(segment
		(start 120.125 186.65)
		(end 120.125 186.180159)
		(width 0.1)
		(layer "In9.Cu")
		(net 627)
	)
	(segment
		(start 120.475 186.180159)
		(end 120.475 186.65)
		(width 0.1)
		(layer "In9.Cu")
		(net 627)
	)
	(segment
		(start 123 186.65)
		(end 124.55 188.2)
		(width 0.1)
		(layer "In9.Cu")
		(net 627)
	)
	(segment
		(start 120.475 186.65)
		(end 120.475 187.119841)
		(width 0.1)
		(layer "In9.Cu")
		(net 627)
	)
	(segment
		(start 119.425 187.119841)
		(end 119.425 186.65)
		(width 0.1)
		(layer "In9.Cu")
		(net 627)
	)
	(segment
		(start 120.825 187.119841)
		(end 120.825 186.65)
		(width 0.1)
		(layer "In9.Cu")
		(net 627)
	)
	(segment
		(start 118.375 186.180159)
		(end 118.375 186.475)
		(width 0.1)
		(layer "In9.Cu")
		(net 627)
	)
	(segment
		(start 119.775 186.180159)
		(end 119.775 186.65)
		(width 0.1)
		(layer "In9.Cu")
		(net 627)
	)
	(segment
		(start 119.075 186.65)
		(end 119.075 187.119841)
		(width 0.1)
		(layer "In9.Cu")
		(net 627)
	)
	(segment
		(start 124.55 188.2)
		(end 126.477501 188.2)
		(width 0.1)
		(layer "In9.Cu")
		(net 627)
	)
	(segment
		(start 121.774499 187.7)
		(end 117.85 187.7)
		(width 0.1)
		(layer "In9.Cu")
		(net 627)
	)
	(segment
		(start 118.025 186.475)
		(end 118.025 186.180159)
		(width 0.1)
		(layer "In9.Cu")
		(net 627)
	)
	(segment
		(start 117.75 187.6)
		(end 117.75 186.75)
		(width 0.1)
		(layer "In9.Cu")
		(net 627)
	)
	(segment
		(start 122.575 186.180159)
		(end 122.575 186.475)
		(width 0.1)
		(layer "In9.Cu")
		(net 627)
	)
	(segment
		(start 120.125 187.119841)
		(end 120.125 186.65)
		(width 0.1)
		(layer "In9.Cu")
		(net 627)
	)
	(segment
		(start 120.825 186.65)
		(end 120.825 186.180159)
		(width 0.1)
		(layer "In9.Cu")
		(net 627)
	)
	(segment
		(start 122.75 186.65)
		(end 123 186.65)
		(width 0.1)
		(layer "In9.Cu")
		(net 627)
	)
	(segment
		(start 118.725 186.65)
		(end 118.725 186.180159)
		(width 0.1)
		(layer "In9.Cu")
		(net 627)
	)
	(arc
		(start 121.35 187.294841)
		(mid 121.473744 187.243585)
		(end 121.525 187.119841)
		(width 0.1)
		(layer "In9.Cu")
		(net 627)
	)
	(arc
		(start 122.575 186.475)
		(mid 122.626256 186.598744)
		(end 122.75 186.65)
		(width 0.1)
		(layer "In9.Cu")
		(net 627)
	)
	(arc
		(start 121 186.005159)
		(mid 121.123744 186.056415)
		(end 121.175 186.180159)
		(width 0.1)
		(layer "In9.Cu")
		(net 627)
	)
	(arc
		(start 118.375 187.119841)
		(mid 118.426256 187.243585)
		(end 118.55 187.294841)
		(width 0.1)
		(layer "In9.Cu")
		(net 627)
	)
	(arc
		(start 119.425 186.180159)
		(mid 119.476256 186.056415)
		(end 119.6 186.005159)
		(width 0.1)
		(layer "In9.Cu")
		(net 627)
	)
	(arc
		(start 120.3 186.005159)
		(mid 120.423744 186.056415)
		(end 120.475 186.180159)
		(width 0.1)
		(layer "In9.Cu")
		(net 627)
	)
	(arc
		(start 119.25 187.294841)
		(mid 119.373744 187.243585)
		(end 119.425 187.119841)
		(width 0.1)
		(layer "In9.Cu")
		(net 627)
	)
	(arc
		(start 118.025 186.180159)
		(mid 118.076256 186.056415)
		(end 118.2 186.005159)
		(width 0.1)
		(layer "In9.Cu")
		(net 627)
	)
	(arc
		(start 117.85 186.65)
		(mid 117.973744 186.598744)
		(end 118.025 186.475)
		(width 0.1)
		(layer "In9.Cu")
		(net 627)
	)
	(arc
		(start 121.875 187.119841)
		(mid 121.926256 187.243585)
		(end 122.05 187.294841)
		(width 0.1)
		(layer "In9.Cu")
		(net 627)
	)
	(arc
		(start 121.7 186.005159)
		(mid 121.823744 186.056415)
		(end 121.875 186.180159)
		(width 0.1)
		(layer "In9.Cu")
		(net 627)
	)
	(arc
		(start 119.95 187.294841)
		(mid 120.073744 187.243585)
		(end 120.125 187.119841)
		(width 0.1)
		(layer "In9.Cu")
		(net 627)
	)
	(arc
		(start 120.475 187.119841)
		(mid 120.526256 187.243585)
		(end 120.65 187.294841)
		(width 0.1)
		(layer "In9.Cu")
		(net 627)
	)
	(arc
		(start 119.775 187.119841)
		(mid 119.826256 187.243585)
		(end 119.95 187.294841)
		(width 0.1)
		(layer "In9.Cu")
		(net 627)
	)
	(arc
		(start 118.2 186.005159)
		(mid 118.323744 186.056415)
		(end 118.375 186.180159)
		(width 0.1)
		(layer "In9.Cu")
		(net 627)
	)
	(arc
		(start 122.4 186.005159)
		(mid 122.523744 186.056415)
		(end 122.575 186.180159)
		(width 0.1)
		(layer "In9.Cu")
		(net 627)
	)
	(arc
		(start 122.05 187.294841)
		(mid 122.173744 187.243585)
		(end 122.225 187.119841)
		(width 0.1)
		(layer "In9.Cu")
		(net 627)
	)
	(arc
		(start 119.6 186.005159)
		(mid 119.723744 186.056415)
		(end 119.775 186.180159)
		(width 0.1)
		(layer "In9.Cu")
		(net 627)
	)
	(arc
		(start 118.55 187.294841)
		(mid 118.673744 187.243585)
		(end 118.725 187.119841)
		(width 0.1)
		(layer "In9.Cu")
		(net 627)
	)
	(arc
		(start 120.65 187.294841)
		(mid 120.773744 187.243585)
		(end 120.825 187.119841)
		(width 0.1)
		(layer "In9.Cu")
		(net 627)
	)
	(arc
		(start 120.125 186.180159)
		(mid 120.176256 186.056415)
		(end 120.3 186.005159)
		(width 0.1)
		(layer "In9.Cu")
		(net 627)
	)
	(arc
		(start 119.075 187.119841)
		(mid 119.126256 187.243585)
		(end 119.25 187.294841)
		(width 0.1)
		(layer "In9.Cu")
		(net 627)
	)
	(arc
		(start 120.825 186.180159)
		(mid 120.876256 186.056415)
		(end 121 186.005159)
		(width 0.1)
		(layer "In9.Cu")
		(net 627)
	)
	(arc
		(start 122.225 186.180159)
		(mid 122.276256 186.056415)
		(end 122.4 186.005159)
		(width 0.1)
		(layer "In9.Cu")
		(net 627)
	)
	(arc
		(start 121.175 187.119841)
		(mid 121.226256 187.243585)
		(end 121.35 187.294841)
		(width 0.1)
		(layer "In9.Cu")
		(net 627)
	)
	(arc
		(start 118.725 186.180159)
		(mid 118.776256 186.056415)
		(end 118.9 186.005159)
		(width 0.1)
		(layer "In9.Cu")
		(net 627)
	)
	(arc
		(start 118.9 186.005159)
		(mid 119.023744 186.056415)
		(end 119.075 186.180159)
		(width 0.1)
		(layer "In9.Cu")
		(net 627)
	)
	(arc
		(start 121.525 186.180159)
		(mid 121.576256 186.056415)
		(end 121.7 186.005159)
		(width 0.1)
		(layer "In9.Cu")
		(net 627)
	)
	(segment
		(start 130.376501 186.301)
		(end 129.877001 186.8005)
		(width 0.256)
		(layer "F.Cu")
		(net 628)
	)
	(segment
		(start 122.85 187.085)
		(end 122.85 187.7)
		(width 0.256)
		(layer "F.Cu")
		(net 628)
	)
	(via
		(at 129.877001 186.8005)
		(size 0.45)
		(drill 0.1)
		(layers "F.Cu" "B.Cu")
		(net 628)
	)
	(via
		(at 122.85 187.7)
		(size 0.45)
		(drill 0.1)
		(layers "F.Cu" "B.Cu")
		(net 628)
	)
	(segment
		(start 117 187.4)
		(end 117 187.45)
		(width 0.1)
		(layer "In9.Cu")
		(net 628)
	)
	(segment
		(start 117 186.15)
		(end 117 186.3)
		(width 0.1)
		(layer "In9.Cu")
		(net 628)
	)
	(segment
		(start 115.9 188.55)
		(end 116.05 188.7)
		(width 0.1)
		(layer "In9.Cu")
		(net 628)
	)
	(segment
		(start 123.4 188.25)
		(end 123.9 188.75)
		(width 0.1)
		(layer "In9.Cu")
		(net 628)
	)
	(segment
		(start 122.45 188.7)
		(end 122.9 188.25)
		(width 0.1)
		(layer "In9.Cu")
		(net 628)
	)
	(segment
		(start 129.15 188.75)
		(end 129.35 188.55)
		(width 0.1)
		(layer "In9.Cu")
		(net 628)
	)
	(segment
		(start 115.396995 187.125)
		(end 116.725 187.125)
		(width 0.1)
		(layer "In9.Cu")
		(net 628)
	)
	(segment
		(start 129.877001 187.111749)
		(end 129.877001 186.8005)
		(width 0.1)
		(layer "In9.Cu")
		(net 628)
	)
	(segment
		(start 117 187.45)
		(end 117 187.9)
		(width 0.1)
		(layer "In9.Cu")
		(net 628)
	)
	(segment
		(start 116.725 186.575)
		(end 115.396995 186.575)
		(width 0.1)
		(layer "In9.Cu")
		(net 628)
	)
	(segment
		(start 122.9 188.25)
		(end 123.4 188.25)
		(width 0.1)
		(layer "In9.Cu")
		(net 628)
	)
	(segment
		(start 123.9 188.75)
		(end 129.15 188.75)
		(width 0.1)
		(layer "In9.Cu")
		(net 628)
	)
	(segment
		(start 129.35 188.55)
		(end 129.35 187.63875)
		(width 0.1)
		(layer "In9.Cu")
		(net 628)
	)
	(segment
		(start 115.9 188.25)
		(end 115.9 188.55)
		(width 0.1)
		(layer "In9.Cu")
		(net 628)
	)
	(segment
		(start 116.05 188.7)
		(end 122.45 188.7)
		(width 0.1)
		(layer "In9.Cu")
		(net 628)
	)
	(segment
		(start 117.4 187.9)
		(end 117.4 186.15)
		(width 0.1)
		(layer "In9.Cu")
		(net 628)
	)
	(segment
		(start 122.85 187.7)
		(end 122.45 188.1)
		(width 0.1)
		(layer "In9.Cu")
		(net 628)
	)
	(segment
		(start 116.8 188.1)
		(end 116.75 188.1)
		(width 0.1)
		(layer "In9.Cu")
		(net 628)
	)
	(segment
		(start 116.05 188.1)
		(end 115.9 188.25)
		(width 0.1)
		(layer "In9.Cu")
		(net 628)
	)
	(segment
		(start 129.35 187.63875)
		(end 129.877001 187.111749)
		(width 0.1)
		(layer "In9.Cu")
		(net 628)
	)
	(segment
		(start 122.45 188.1)
		(end 117.6 188.1)
		(width 0.1)
		(layer "In9.Cu")
		(net 628)
	)
	(segment
		(start 116.75 188.1)
		(end 116.05 188.1)
		(width 0.1)
		(layer "In9.Cu")
		(net 628)
	)
	(arc
		(start 117.2 185.95)
		(mid 117.058579 186.008579)
		(end 117 186.15)
		(width 0.1)
		(layer "In9.Cu")
		(net 628)
	)
	(arc
		(start 117 187.9)
		(mid 116.941421 188.041421)
		(end 116.8 188.1)
		(width 0.1)
		(layer "In9.Cu")
		(net 628)
	)
	(arc
		(start 116.725 187.125)
		(mid 116.919454 187.205546)
		(end 117 187.4)
		(width 0.1)
		(layer "In9.Cu")
		(net 628)
	)
	(arc
		(start 115.396995 186.575)
		(mid 115.202541 186.655546)
		(end 115.121995 186.85)
		(width 0.1)
		(layer "In9.Cu")
		(net 628)
	)
	(arc
		(start 117 186.3)
		(mid 116.919454 186.494454)
		(end 116.725 186.575)
		(width 0.1)
		(layer "In9.Cu")
		(net 628)
	)
	(arc
		(start 117.6 188.1)
		(mid 117.458579 188.041421)
		(end 117.4 187.9)
		(width 0.1)
		(layer "In9.Cu")
		(net 628)
	)
	(arc
		(start 115.121995 186.85)
		(mid 115.202541 187.044454)
		(end 115.396995 187.125)
		(width 0.1)
		(layer "In9.Cu")
		(net 628)
	)
	(arc
		(start 117.4 186.15)
		(mid 117.341421 186.008579)
		(end 117.2 185.95)
		(width 0.1)
		(layer "In9.Cu")
		(net 628)
	)
	(segment
		(start 130.376501 187.301)
		(end 129.877001 187.8005)
		(width 0.256)
		(layer "F.Cu")
		(net 629)
	)
	(segment
		(start 115.45 187.085)
		(end 115.45 187.7)
		(width 0.256)
		(layer "F.Cu")
		(net 629)
	)
	(via
		(at 129.877001 187.8005)
		(size 0.45)
		(drill 0.1)
		(layers "F.Cu" "B.Cu")
		(net 629)
	)
	(via
		(at 115.45 187.7)
		(size 0.45)
		(drill 0.1)
		(layers "F.Cu" "B.Cu")
		(net 629)
	)
	(segment
		(start 117.975 189.6)
		(end 117.975 189.156231)
		(width 0.1)
		(layer "In9.Cu")
		(net 629)
	)
	(segment
		(start 118.325 189.6)
		(end 118.325 190.043769)
		(width 0.1)
		(layer "In9.Cu")
		(net 629)
	)
	(segment
		(start 120.775 189.425)
		(end 120.775 189.156231)
		(width 0.1)
		(layer "In9.Cu")
		(net 629)
	)
	(segment
		(start 120.075 190.043769)
		(end 120.075 189.6)
		(width 0.1)
		(layer "In9.Cu")
		(net 629)
	)
	(segment
		(start 129.877001 187.8005)
		(end 129.877001 188.622999)
		(width 0.1)
		(layer "In9.Cu")
		(net 629)
	)
	(segment
		(start 121.2 189.6)
		(end 120.95 189.6)
		(width 0.1)
		(layer "In9.Cu")
		(net 629)
	)
	(segment
		(start 119.025 189.156231)
		(end 119.025 189.6)
		(width 0.1)
		(layer "In9.Cu")
		(net 629)
	)
	(segment
		(start 119.375 189.6)
		(end 119.375 189.156231)
		(width 0.1)
		(layer "In9.Cu")
		(net 629)
	)
	(segment
		(start 119.725 189.156231)
		(end 119.725 189.6)
		(width 0.1)
		(layer "In9.Cu")
		(net 629)
	)
	(segment
		(start 116.225 189.156231)
		(end 116.225 189.425)
		(width 0.1)
		(layer "In9.Cu")
		(net 629)
	)
	(segment
		(start 116.05 189.6)
		(end 115.7 189.6)
		(width 0.1)
		(layer "In9.Cu")
		(net 629)
	)
	(segment
		(start 120.425 189.156231)
		(end 120.425 189.425)
		(width 0.1)
		(layer "In9.Cu")
		(net 629)
	)
	(segment
		(start 117.625 189.156231)
		(end 117.625 189.6)
		(width 0.1)
		(layer "In9.Cu")
		(net 629)
	)
	(segment
		(start 117.975 190.043769)
		(end 117.975 189.6)
		(width 0.1)
		(layer "In9.Cu")
		(net 629)
	)
	(segment
		(start 115.7 189.6)
		(end 115.45 189.35)
		(width 0.1)
		(layer "In9.Cu")
		(net 629)
	)
	(segment
		(start 119.375 190.043769)
		(end 119.375 189.6)
		(width 0.1)
		(layer "In9.Cu")
		(net 629)
	)
	(segment
		(start 117.275 189.6)
		(end 117.275 189.156231)
		(width 0.1)
		(layer "In9.Cu")
		(net 629)
	)
	(segment
		(start 118.675 190.043769)
		(end 118.675 189.6)
		(width 0.1)
		(layer "In9.Cu")
		(net 629)
	)
	(segment
		(start 116.925 189.6)
		(end 116.925 190.043769)
		(width 0.1)
		(layer "In9.Cu")
		(net 629)
	)
	(segment
		(start 116.575 190.043769)
		(end 116.575 189.6)
		(width 0.1)
		(layer "In9.Cu")
		(net 629)
	)
	(segment
		(start 119.025 189.6)
		(end 119.025 190.043769)
		(width 0.1)
		(layer "In9.Cu")
		(net 629)
	)
	(segment
		(start 129.877001 188.622999)
		(end 129.35 189.15)
		(width 0.1)
		(layer "In9.Cu")
		(net 629)
	)
	(segment
		(start 118.675 189.6)
		(end 118.675 189.156231)
		(width 0.1)
		(layer "In9.Cu")
		(net 629)
	)
	(segment
		(start 117.625 189.6)
		(end 117.625 190.043769)
		(width 0.1)
		(layer "In9.Cu")
		(net 629)
	)
	(segment
		(start 120.075 189.6)
		(end 120.075 189.156231)
		(width 0.1)
		(layer "In9.Cu")
		(net 629)
	)
	(segment
		(start 116.575 189.6)
		(end 116.575 189.156231)
		(width 0.1)
		(layer "In9.Cu")
		(net 629)
	)
	(segment
		(start 129.35 189.15)
		(end 121.65 189.15)
		(width 0.1)
		(layer "In9.Cu")
		(net 629)
	)
	(segment
		(start 121.65 189.15)
		(end 121.2 189.6)
		(width 0.1)
		(layer "In9.Cu")
		(net 629)
	)
	(segment
		(start 117.275 190.043769)
		(end 117.275 189.6)
		(width 0.1)
		(layer "In9.Cu")
		(net 629)
	)
	(segment
		(start 120.425 189.425)
		(end 120.425 190.043769)
		(width 0.1)
		(layer "In9.Cu")
		(net 629)
	)
	(segment
		(start 118.325 189.156231)
		(end 118.325 189.6)
		(width 0.1)
		(layer "In9.Cu")
		(net 629)
	)
	(segment
		(start 119.725 189.6)
		(end 119.725 190.043769)
		(width 0.1)
		(layer "In9.Cu")
		(net 629)
	)
	(segment
		(start 115.45 189.35)
		(end 115.45 187.7)
		(width 0.1)
		(layer "In9.Cu")
		(net 629)
	)
	(segment
		(start 116.925 189.156231)
		(end 116.925 189.6)
		(width 0.1)
		(layer "In9.Cu")
		(net 629)
	)
	(arc
		(start 118.85 190.218769)
		(mid 118.726256 190.167513)
		(end 118.675 190.043769)
		(width 0.1)
		(layer "In9.Cu")
		(net 629)
	)
	(arc
		(start 119.2 188.981231)
		(mid 119.076256 189.032487)
		(end 119.025 189.156231)
		(width 0.1)
		(layer "In9.Cu")
		(net 629)
	)
	(arc
		(start 116.925 190.043769)
		(mid 116.873744 190.167513)
		(end 116.75 190.218769)
		(width 0.1)
		(layer "In9.Cu")
		(net 629)
	)
	(arc
		(start 120.075 189.156231)
		(mid 120.023744 189.032487)
		(end 119.9 188.981231)
		(width 0.1)
		(layer "In9.Cu")
		(net 629)
	)
	(arc
		(start 118.15 190.218769)
		(mid 118.026256 190.167513)
		(end 117.975 190.043769)
		(width 0.1)
		(layer "In9.Cu")
		(net 629)
	)
	(arc
		(start 118.675 189.156231)
		(mid 118.623744 189.032487)
		(end 118.5 188.981231)
		(width 0.1)
		(layer "In9.Cu")
		(net 629)
	)
	(arc
		(start 120.95 189.6)
		(mid 120.826256 189.548744)
		(end 120.775 189.425)
		(width 0.1)
		(layer "In9.Cu")
		(net 629)
	)
	(arc
		(start 116.4 188.981231)
		(mid 116.276256 189.032487)
		(end 116.225 189.156231)
		(width 0.1)
		(layer "In9.Cu")
		(net 629)
	)
	(arc
		(start 116.575 189.156231)
		(mid 116.523744 189.032487)
		(end 116.4 188.981231)
		(width 0.1)
		(layer "In9.Cu")
		(net 629)
	)
	(arc
		(start 117.8 188.981231)
		(mid 117.676256 189.032487)
		(end 117.625 189.156231)
		(width 0.1)
		(layer "In9.Cu")
		(net 629)
	)
	(arc
		(start 120.775 189.156231)
		(mid 120.723744 189.032487)
		(end 120.6 188.981231)
		(width 0.1)
		(layer "In9.Cu")
		(net 629)
	)
	(arc
		(start 116.75 190.218769)
		(mid 116.626256 190.167513)
		(end 116.575 190.043769)
		(width 0.1)
		(layer "In9.Cu")
		(net 629)
	)
	(arc
		(start 118.325 190.043769)
		(mid 118.273744 190.167513)
		(end 118.15 190.218769)
		(width 0.1)
		(layer "In9.Cu")
		(net 629)
	)
	(arc
		(start 120.25 190.218769)
		(mid 120.126256 190.167513)
		(end 120.075 190.043769)
		(width 0.1)
		(layer "In9.Cu")
		(net 629)
	)
	(arc
		(start 119.025 190.043769)
		(mid 118.973744 190.167513)
		(end 118.85 190.218769)
		(width 0.1)
		(layer "In9.Cu")
		(net 629)
	)
	(arc
		(start 119.725 190.043769)
		(mid 119.673744 190.167513)
		(end 119.55 190.218769)
		(width 0.1)
		(layer "In9.Cu")
		(net 629)
	)
	(arc
		(start 116.225 189.425)
		(mid 116.173744 189.548744)
		(end 116.05 189.6)
		(width 0.1)
		(layer "In9.Cu")
		(net 629)
	)
	(arc
		(start 117.625 190.043769)
		(mid 117.573744 190.167513)
		(end 117.45 190.218769)
		(width 0.1)
		(layer "In9.Cu")
		(net 629)
	)
	(arc
		(start 119.55 190.218769)
		(mid 119.426256 190.167513)
		(end 119.375 190.043769)
		(width 0.1)
		(layer "In9.Cu")
		(net 629)
	)
	(arc
		(start 117.45 190.218769)
		(mid 117.326256 190.167513)
		(end 117.275 190.043769)
		(width 0.1)
		(layer "In9.Cu")
		(net 629)
	)
	(arc
		(start 118.5 188.981231)
		(mid 118.376256 189.032487)
		(end 118.325 189.156231)
		(width 0.1)
		(layer "In9.Cu")
		(net 629)
	)
	(arc
		(start 117.975 189.156231)
		(mid 117.923744 189.032487)
		(end 117.8 188.981231)
		(width 0.1)
		(layer "In9.Cu")
		(net 629)
	)
	(arc
		(start 119.375 189.156231)
		(mid 119.323744 189.032487)
		(end 119.2 188.981231)
		(width 0.1)
		(layer "In9.Cu")
		(net 629)
	)
	(arc
		(start 117.275 189.156231)
		(mid 117.223744 189.032487)
		(end 117.1 188.981231)
		(width 0.1)
		(layer "In9.Cu")
		(net 629)
	)
	(arc
		(start 117.1 188.981231)
		(mid 116.976256 189.032487)
		(end 116.925 189.156231)
		(width 0.1)
		(layer "In9.Cu")
		(net 629)
	)
	(arc
		(start 120.6 188.981231)
		(mid 120.476256 189.032487)
		(end 120.425 189.156231)
		(width 0.1)
		(layer "In9.Cu")
		(net 629)
	)
	(arc
		(start 120.425 190.043769)
		(mid 120.373744 190.167513)
		(end 120.25 190.218769)
		(width 0.1)
		(layer "In9.Cu")
		(net 629)
	)
	(arc
		(start 119.9 188.981231)
		(mid 119.776256 189.032487)
		(end 119.725 189.156231)
		(width 0.1)
		(layer "In9.Cu")
		(net 629)
	)
	(segment
		(start 114.6505 181.296499)
		(end 113.665001 181.296499)
		(width 0.256)
		(layer "F.Cu")
		(net 630)
	)
	(segment
		(start 113.665001 181.296499)
		(end 113.650501 181.310999)
		(width 0.256)
		(layer "F.Cu")
		(net 630)
	)
	(segment
		(start 144.375501 185.301)
		(end 144.875001 185.8005)
		(width 0.256)
		(layer "F.Cu")
		(net 630)
	)
	(via
		(at 113.650501 181.310999)
		(size 0.45)
		(drill 0.1)
		(layers "F.Cu" "B.Cu")
		(net 630)
	)
	(via
		(at 144.875001 185.8005)
		(size 0.45)
		(drill 0.1)
		(layers "F.Cu" "B.Cu")
		(net 630)
	)
	(segment
		(start 113.711501 181.249999)
		(end 113.650501 181.310999)
		(width 0.256)
		(layer "B.Cu")
		(net 630)
	)
	(segment
		(start 114.315501 181.25)
		(end 113.711501 181.249999)
		(width 0.256)
		(layer "B.Cu")
		(net 630)
	)
	(segment
		(start 145.35 181.6)
		(end 145.05 181.3)
		(width 0.1)
		(layer "In6.Cu")
		(net 630)
	)
	(segment
		(start 140.15 180.35)
		(end 139.55 180.35)
		(width 0.1)
		(layer "In6.Cu")
		(net 630)
	)
	(segment
		(start 122.45 179.9)
		(end 115.45 179.9)
		(width 0.1)
		(layer "In6.Cu")
		(net 630)
	)
	(segment
		(start 123.05 179.3)
		(end 122.45 179.9)
		(width 0.1)
		(layer "In6.Cu")
		(net 630)
	)
	(segment
		(start 145.05 181.3)
		(end 140.65 181.3)
		(width 0.1)
		(layer "In6.Cu")
		(net 630)
	)
	(segment
		(start 140.4 180.6)
		(end 140.15 180.35)
		(width 0.1)
		(layer "In6.Cu")
		(net 630)
	)
	(segment
		(start 140.65 181.3)
		(end 140.4 181.05)
		(width 0.1)
		(layer "In6.Cu")
		(net 630)
	)
	(segment
		(start 138.5 179.3)
		(end 123.05 179.3)
		(width 0.1)
		(layer "In6.Cu")
		(net 630)
	)
	(segment
		(start 140.4 181.05)
		(end 140.4 180.6)
		(width 0.1)
		(layer "In6.Cu")
		(net 630)
	)
	(segment
		(start 115.45 179.9)
		(end 114.039001 181.310999)
		(width 0.1)
		(layer "In6.Cu")
		(net 630)
	)
	(segment
		(start 145.35 185.325501)
		(end 145.35 181.6)
		(width 0.1)
		(layer "In6.Cu")
		(net 630)
	)
	(segment
		(start 144.875001 185.8005)
		(end 145.35 185.325501)
		(width 0.1)
		(layer "In6.Cu")
		(net 630)
	)
	(segment
		(start 114.039001 181.310999)
		(end 113.650501 181.310999)
		(width 0.1)
		(layer "In6.Cu")
		(net 630)
	)
	(segment
		(start 139.55 180.35)
		(end 138.5 179.3)
		(width 0.1)
		(layer "In6.Cu")
		(net 630)
	)
	(segment
		(start 158.415501 181.672)
		(end 159.351501 181.672)
		(width 0.201)
		(layer "F.Cu")
		(net 631)
	)
	(segment
		(start 147.375501 174.302)
		(end 147.875001 173.8025)
		(width 0.256)
		(layer "F.Cu")
		(net 631)
	)
	(via
		(at 158.415501 181.672)
		(size 0.45)
		(drill 0.1)
		(layers "F.Cu" "B.Cu")
		(net 631)
	)
	(via
		(at 147.875001 173.8025)
		(size 0.45)
		(drill 0.1)
		(layers "F.Cu" "B.Cu")
		(net 631)
	)
	(segment
		(start 159.215501 181.676)
		(end 158.419501 181.676)
		(width 0.256)
		(layer "B.Cu")
		(net 631)
	)
	(segment
		(start 158.419501 181.676)
		(end 158.415501 181.672)
		(width 0.256)
		(layer "B.Cu")
		(net 631)
	)
	(segment
		(start 143.350501 178.950501)
		(end 143.6 179.2)
		(width 0.1)
		(layer "In4.Cu")
		(net 631)
	)
	(segment
		(start 147.928832 171.326)
		(end 144.750501 171.326)
		(width 0.1)
		(layer "In4.Cu")
		(net 631)
	)
	(segment
		(start 144.350501 174.351)
		(end 143.350501 175.351)
		(width 0.1)
		(layer "In4.Cu")
		(net 631)
	)
	(segment
		(start 143.6 179.2)
		(end 155.943501 179.2)
		(width 0.1)
		(layer "In4.Cu")
		(net 631)
	)
	(segment
		(start 144.350501 171.726)
		(end 144.350501 174.351)
		(width 0.1)
		(layer "In4.Cu")
		(net 631)
	)
	(segment
		(start 148.250001 173.4275)
		(end 148.250001 171.647169)
		(width 0.1)
		(layer "In4.Cu")
		(net 631)
	)
	(segment
		(start 155.943501 179.2)
		(end 158.415501 181.672)
		(width 0.1)
		(layer "In4.Cu")
		(net 631)
	)
	(segment
		(start 148.250001 171.647169)
		(end 147.928832 171.326)
		(width 0.1)
		(layer "In4.Cu")
		(net 631)
	)
	(segment
		(start 143.350501 175.351)
		(end 143.350501 178.950501)
		(width 0.1)
		(layer "In4.Cu")
		(net 631)
	)
	(segment
		(start 144.750501 171.326)
		(end 144.350501 171.726)
		(width 0.1)
		(layer "In4.Cu")
		(net 631)
	)
	(segment
		(start 147.875001 173.8025)
		(end 148.250001 173.4275)
		(width 0.1)
		(layer "In4.Cu")
		(net 631)
	)
	(segment
		(start 158.415501 180.675)
		(end 159.351501 180.675)
		(width 0.201)
		(layer "F.Cu")
		(net 632)
	)
	(segment
		(start 150.375501 172.302)
		(end 150.875002 171.8025)
		(width 0.256)
		(layer "F.Cu")
		(net 632)
	)
	(via
		(at 150.875002 171.8025)
		(size 0.45)
		(drill 0.1)
		(layers "F.Cu" "B.Cu")
		(net 632)
	)
	(via
		(at 158.415501 180.675)
		(size 0.45)
		(drill 0.1)
		(layers "F.Cu" "B.Cu")
		(net 632)
	)
	(segment
		(start 158.416502 180.676001)
		(end 158.415501 180.675)
		(width 0.256)
		(layer "B.Cu")
		(net 632)
	)
	(segment
		(start 159.2155 180.676001)
		(end 158.416502 180.676001)
		(width 0.256)
		(layer "B.Cu")
		(net 632)
	)
	(segment
		(start 143.6 180.2)
		(end 145.192659 180.2)
		(width 0.1)
		(layer "In4.Cu")
		(net 632)
	)
	(segment
		(start 157.475501 182.251)
		(end 158.600501 182.251)
		(width 0.1)
		(layer "In4.Cu")
		(net 632)
	)
	(segment
		(start 144.375501 171.126)
		(end 144.200501 171.301)
		(width 0.1)
		(layer "In4.Cu")
		(net 632)
	)
	(segment
		(start 158.925501 181.185)
		(end 158.415501 180.675)
		(width 0.1)
		(layer "In4.Cu")
		(net 632)
	)
	(segment
		(start 158.600501 182.251)
		(end 158.925501 181.926)
		(width 0.1)
		(layer "In4.Cu")
		(net 632)
	)
	(segment
		(start 142.672085 179.3)
		(end 143.2 179.3)
		(width 0.1)
		(layer "In4.Cu")
		(net 632)
	)
	(segment
		(start 145.192659 180.2)
		(end 145.4 179.992659)
		(width 0.1)
		(layer "In4.Cu")
		(net 632)
	)
	(segment
		(start 143.422085 179.522085)
		(end 143.422085 180.022085)
		(width 0.1)
		(layer "In4.Cu")
		(net 632)
	)
	(segment
		(start 146.225501 179.425501)
		(end 146.4 179.6)
		(width 0.1)
		(layer "In4.Cu")
		(net 632)
	)
	(segment
		(start 145.4 179.992659)
		(end 145.4 179.672585)
		(width 0.1)
		(layer "In4.Cu")
		(net 632)
	)
	(segment
		(start 143.350501 171.626)
		(end 143.350501 174.151)
		(width 0.1)
		(layer "In4.Cu")
		(net 632)
	)
	(segment
		(start 147.975501 170.301)
		(end 144.725501 170.301)
		(width 0.1)
		(layer "In4.Cu")
		(net 632)
	)
	(segment
		(start 143.422085 180.022085)
		(end 143.6 180.2)
		(width 0.1)
		(layer "In4.Cu")
		(net 632)
	)
	(segment
		(start 158.925501 181.926)
		(end 158.925501 181.185)
		(width 0.1)
		(layer "In4.Cu")
		(net 632)
	)
	(segment
		(start 148.7 172.2)
		(end 148.500001 172.000001)
		(width 0.1)
		(layer "In4.Cu")
		(net 632)
	)
	(segment
		(start 142.325501 175.176)
		(end 142.325501 178.953416)
		(width 0.1)
		(layer "In4.Cu")
		(net 632)
	)
	(segment
		(start 148.500001 172.000001)
		(end 148.500001 170.825499)
		(width 0.1)
		(layer "In4.Cu")
		(net 632)
	)
	(segment
		(start 146.4 179.855831)
		(end 146.895169 180.351)
		(width 0.1)
		(layer "In4.Cu")
		(net 632)
	)
	(segment
		(start 143.350501 174.151)
		(end 142.325501 175.176)
		(width 0.1)
		(layer "In4.Cu")
		(net 632)
	)
	(segment
		(start 144.200501 171.301)
		(end 143.675501 171.301)
		(width 0.1)
		(layer "In4.Cu")
		(net 632)
	)
	(segment
		(start 146.895169 180.351)
		(end 155.575501 180.351)
		(width 0.1)
		(layer "In4.Cu")
		(net 632)
	)
	(segment
		(start 145.4 179.672585)
		(end 145.647084 179.425501)
		(width 0.1)
		(layer "In4.Cu")
		(net 632)
	)
	(segment
		(start 144.725501 170.301)
		(end 144.375501 170.651)
		(width 0.1)
		(layer "In4.Cu")
		(net 632)
	)
	(segment
		(start 143.675501 171.301)
		(end 143.350501 171.626)
		(width 0.1)
		(layer "In4.Cu")
		(net 632)
	)
	(segment
		(start 142.325501 178.953416)
		(end 142.672085 179.3)
		(width 0.1)
		(layer "In4.Cu")
		(net 632)
	)
	(segment
		(start 144.375501 170.651)
		(end 144.375501 171.126)
		(width 0.1)
		(layer "In4.Cu")
		(net 632)
	)
	(segment
		(start 150.875002 171.8025)
		(end 150.477502 172.2)
		(width 0.1)
		(layer "In4.Cu")
		(net 632)
	)
	(segment
		(start 146.4 179.6)
		(end 146.4 179.855831)
		(width 0.1)
		(layer "In4.Cu")
		(net 632)
	)
	(segment
		(start 150.477502 172.2)
		(end 148.7 172.2)
		(width 0.1)
		(layer "In4.Cu")
		(net 632)
	)
	(segment
		(start 155.575501 180.351)
		(end 157.475501 182.251)
		(width 0.1)
		(layer "In4.Cu")
		(net 632)
	)
	(segment
		(start 148.500001 170.825499)
		(end 147.975501 170.301)
		(width 0.1)
		(layer "In4.Cu")
		(net 632)
	)
	(segment
		(start 145.647084 179.425501)
		(end 146.225501 179.425501)
		(width 0.1)
		(layer "In4.Cu")
		(net 632)
	)
	(segment
		(start 143.2 179.3)
		(end 143.422085 179.522085)
		(width 0.1)
		(layer "In4.Cu")
		(net 632)
	)
	(segment
		(start 147.375501 172.301999)
		(end 147.875001 171.8025)
		(width 0.256)
		(layer "F.Cu")
		(net 633)
	)
	(segment
		(start 158.415501 179.675)
		(end 159.351501 179.675)
		(width 0.201)
		(layer "F.Cu")
		(net 633)
	)
	(via
		(at 151.875001 178.8005)
		(size 0.45)
		(drill 0.1)
		(layers "F.Cu" "B.Cu")
		(net 633)
	)
	(via
		(at 147.875001 171.8025)
		(size 0.45)
		(drill 0.1)
		(layers "F.Cu" "B.Cu")
		(net 633)
	)
	(via
		(at 158.415501 179.675)
		(size 0.45)
		(drill 0.1)
		(layers "F.Cu" "B.Cu")
		(net 633)
	)
	(segment
		(start 158.416501 179.676)
		(end 158.415501 179.675)
		(width 0.256)
		(layer "B.Cu")
		(net 633)
	)
	(segment
		(start 159.215501 179.676)
		(end 158.416501 179.676)
		(width 0.256)
		(layer "B.Cu")
		(net 633)
	)
	(segment
		(start 144.35 175.426501)
		(end 145.350501 174.426)
		(width 0.1)
		(layer "In4.Cu")
		(net 633)
	)
	(segment
		(start 157.416501 178.676)
		(end 151.600501 178.676)
		(width 0.1)
		(layer "In4.Cu")
		(net 633)
	)
	(segment
		(start 145.350501 174.426)
		(end 145.350501 172.526)
		(width 0.1)
		(layer "In4.Cu")
		(net 633)
	)
	(segment
		(start 151.200501 178.276)
		(end 144.626 178.276)
		(width 0.1)
		(layer "In4.Cu")
		(net 633)
	)
	(segment
		(start 158.415501 179.675)
		(end 157.416501 178.676)
		(width 0.1)
		(layer "In4.Cu")
		(net 633)
	)
	(segment
		(start 144.35 178)
		(end 144.35 175.426501)
		(width 0.1)
		(layer "In4.Cu")
		(net 633)
	)
	(segment
		(start 144.626 178.276)
		(end 144.35 178)
		(width 0.1)
		(layer "In4.Cu")
		(net 633)
	)
	(segment
		(start 151.600501 178.676)
		(end 151.200501 178.276)
		(width 0.1)
		(layer "In4.Cu")
		(net 633)
	)
	(segment
		(start 145.692001 172.1845)
		(end 147.493001 172.1845)
		(width 0.1)
		(layer "In4.Cu")
		(net 633)
	)
	(segment
		(start 145.350501 172.526)
		(end 145.692001 172.1845)
		(width 0.1)
		(layer "In4.Cu")
		(net 633)
	)
	(segment
		(start 147.493001 172.1845)
		(end 147.875001 171.8025)
		(width 0.1)
		(layer "In4.Cu")
		(net 633)
	)
	(segment
		(start 201.091 146.847999)
		(end 201.0895 146.849499)
		(width 0.4)
		(layer "F.Cu")
		(net 634)
	)
	(segment
		(start 201.128 142.749999)
		(end 201.1265 142.751499)
		(width 0.4)
		(layer "F.Cu")
		(net 634)
	)
	(segment
		(start 202.113 146.847999)
		(end 201.091 146.847999)
		(width 0.4)
		(layer "F.Cu")
		(net 634)
	)
	(segment
		(start 146.375501 174.302)
		(end 146.875001 173.8025)
		(width 0.256)
		(layer "F.Cu")
		(net 634)
	)
	(segment
		(start 202.15 142.749999)
		(end 201.128 142.749999)
		(width 0.4)
		(layer "F.Cu")
		(net 634)
	)
	(via
		(at 146.875001 173.8025)
		(size 0.45)
		(drill 0.1)
		(layers "F.Cu" "B.Cu")
		(net 634)
	)
	(via
		(at 152.675001 175.800501)
		(size 0.45)
		(drill 0.1)
		(layers "F.Cu" "B.Cu")
		(net 634)
	)
	(via
		(at 201.1265 142.751499)
		(size 0.45)
		(drill 0.1)
		(layers "F.Cu" "B.Cu")
		(net 634)
	)
	(via
		(at 175.1 164.3)
		(size 0.45)
		(drill 0.1)
		(layers "F.Cu" "B.Cu")
		(net 634)
	)
	(via
		(at 201.0895 146.849499)
		(size 0.45)
		(drill 0.1)
		(layers "F.Cu" "B.Cu")
		(net 634)
	)
	(segment
		(start 201.0895 146.849499)
		(end 201.0895 142.788499)
		(width 0.182)
		(layer "B.Cu")
		(net 634)
	)
	(segment
		(start 153.275 175.3)
		(end 152.774499 175.800501)
		(width 0.201)
		(layer "B.Cu")
		(net 634)
	)
	(segment
		(start 153.290001 175.3)
		(end 153.275 175.3)
		(width 0.201)
		(layer "B.Cu")
		(net 634)
	)
	(segment
		(start 201.0895 142.788499)
		(end 201.1265 142.751499)
		(width 0.182)
		(layer "B.Cu")
		(net 634)
	)
	(segment
		(start 152.774499 175.800501)
		(end 152.675001 175.800501)
		(width 0.201)
		(layer "B.Cu")
		(net 634)
	)
	(segment
		(start 175.5 164.3)
		(end 175.1 164.3)
		(width 0.1)
		(layer "In4.Cu")
		(net 634)
	)
	(segment
		(start 179.05 160.75)
		(end 179.95 159.85)
		(width 0.1)
		(layer "In4.Cu")
		(net 634)
	)
	(segment
		(start 179.95 149.2)
		(end 186.398501 142.751499)
		(width 0.1)
		(layer "In4.Cu")
		(net 634)
	)
	(segment
		(start 179.95 159.85)
		(end 179.95 149.2)
		(width 0.1)
		(layer "In4.Cu")
		(net 634)
	)
	(segment
		(start 179.05 160.75)
		(end 175.5 164.3)
		(width 0.1)
		(layer "In4.Cu")
		(net 634)
	)
	(segment
		(start 186.398501 142.751499)
		(end 201.1265 142.751499)
		(width 0.1)
		(layer "In4.Cu")
		(net 634)
	)
	(segment
		(start 152.575001 173.300501)
		(end 147.377 173.300501)
		(width 0.1)
		(layer "In9.Cu")
		(net 634)
	)
	(segment
		(start 152.675001 173.400501)
		(end 152.675001 173.300501)
		(width 0.1)
		(layer "In9.Cu")
		(net 634)
	)
	(segment
		(start 152.675001 175.800501)
		(end 152.675001 173.400501)
		(width 0.1)
		(layer "In9.Cu")
		(net 634)
	)
	(segment
		(start 155.276001 173.300501)
		(end 164.251502 164.325)
		(width 0.1)
		(layer "In9.Cu")
		(net 634)
	)
	(segment
		(start 175.075 164.325)
		(end 175.1 164.3)
		(width 0.1)
		(layer "In9.Cu")
		(net 634)
	)
	(segment
		(start 147.377 173.300501)
		(end 146.875001 173.8025)
		(width 0.1)
		(layer "In9.Cu")
		(net 634)
	)
	(segment
		(start 152.675001 173.400501)
		(end 152.575001 173.300501)
		(width 0.1)
		(layer "In9.Cu")
		(net 634)
	)
	(segment
		(start 164.251502 164.325)
		(end 175.075 164.325)
		(width 0.1)
		(layer "In9.Cu")
		(net 634)
	)
	(segment
		(start 152.675001 173.300501)
		(end 152.575001 173.300501)
		(width 0.1)
		(layer "In9.Cu")
		(net 634)
	)
	(segment
		(start 152.775001 173.300501)
		(end 152.675001 173.300501)
		(width 0.1)
		(layer "In9.Cu")
		(net 634)
	)
	(segment
		(start 152.675001 173.400501)
		(end 152.775001 173.300501)
		(width 0.1)
		(layer "In9.Cu")
		(net 634)
	)
	(segment
		(start 152.775001 173.300501)
		(end 155.276001 173.300501)
		(width 0.1)
		(layer "In9.Cu")
		(net 634)
	)
	(segment
		(start 145.375501 174.302)
		(end 145.875001 173.8025)
		(width 0.256)
		(layer "F.Cu")
		(net 635)
	)
	(via
		(at 145.875001 173.8025)
		(size 0.45)
		(drill 0.1)
		(layers "F.Cu" "B.Cu")
		(net 635)
	)
	(segment
		(start 146.376001 173.3025)
		(end 146.375001 173.3025)
		(width 0.4)
		(layer "B.Cu")
		(net 635)
	)
	(segment
		(start 146.375001 173.3025)
		(end 145.875001 173.8025)
		(width 0.4)
		(layer "B.Cu")
		(net 635)
	)
	(segment
		(start 131.376501 164.302001)
		(end 130.877001 163.8025)
		(width 0.256)
		(layer "F.Cu")
		(net 636)
	)
	(via
		(at 130.877001 163.8025)
		(size 0.45)
		(drill 0.1)
		(layers "F.Cu" "B.Cu")
		(net 636)
	)
	(segment
		(start 130.877001 163.8025)
		(end 131.379501 163.3)
		(width 0.15)
		(layer "B.Cu")
		(net 636)
	)
	(segment
		(start 131.379501 163.3)
		(end 132.072594 163.3)
		(width 0.15)
		(layer "B.Cu")
		(net 636)
	)
	(segment
		(start 146.025 144.225)
		(end 146.025 142.885)
		(width 0.15)
		(layer "B.Cu")
		(net 636)
	)
	(segment
		(start 146.425 144.625)
		(end 146.025 144.225)
		(width 0.15)
		(layer "B.Cu")
		(net 636)
	)
	(segment
		(start 144.94 146.94)
		(end 146.425 145.455)
		(width 0.15)
		(layer "B.Cu")
		(net 636)
	)
	(segment
		(start 144.55 147.871999)
		(end 144.94 147.481999)
		(width 0.15)
		(layer "B.Cu")
		(net 636)
	)
	(segment
		(start 132.4 162.972594)
		(end 132.4 157.3)
		(width 0.15)
		(layer "B.Cu")
		(net 636)
	)
	(segment
		(start 141.828001 147.871999)
		(end 144.55 147.871999)
		(width 0.15)
		(layer "B.Cu")
		(net 636)
	)
	(segment
		(start 132.072594 163.3)
		(end 132.4 162.972594)
		(width 0.15)
		(layer "B.Cu")
		(net 636)
	)
	(segment
		(start 132.4 157.3)
		(end 141.828001 147.871999)
		(width 0.15)
		(layer "B.Cu")
		(net 636)
	)
	(segment
		(start 146.425 145.455)
		(end 146.425 144.625)
		(width 0.15)
		(layer "B.Cu")
		(net 636)
	)
	(segment
		(start 144.94 147.481999)
		(end 144.94 146.94)
		(width 0.15)
		(layer "B.Cu")
		(net 636)
	)
	(segment
		(start 131.376501 165.301999)
		(end 130.877001 164.8025)
		(width 0.256)
		(layer "F.Cu")
		(net 637)
	)
	(via
		(at 130.877001 164.8025)
		(size 0.45)
		(drill 0.1)
		(layers "F.Cu" "B.Cu")
		(net 637)
	)
	(segment
		(start 148.55 142.885)
		(end 148.55 143.55)
		(width 0.15)
		(layer "B.Cu")
		(net 637)
	)
	(segment
		(start 142.53 148.47)
		(end 145.19 148.47)
		(width 0.15)
		(layer "B.Cu")
		(net 637)
	)
	(segment
		(start 133.4 159.3)
		(end 133.4 157.6)
		(width 0.15)
		(layer "B.Cu")
		(net 637)
	)
	(segment
		(start 131.25 164.3)
		(end 135.1 164.3)
		(width 0.15)
		(layer "B.Cu")
		(net 637)
	)
	(segment
		(start 135.35 161.25)
		(end 133.4 159.3)
		(width 0.15)
		(layer "B.Cu")
		(net 637)
	)
	(segment
		(start 147.43 145.54)
		(end 147.43 144.67)
		(width 0.15)
		(layer "B.Cu")
		(net 637)
	)
	(segment
		(start 145.19 148.47)
		(end 145.89 147.77)
		(width 0.15)
		(layer "B.Cu")
		(net 637)
	)
	(segment
		(start 130.877001 164.8025)
		(end 130.877001 164.672999)
		(width 0.15)
		(layer "B.Cu")
		(net 637)
	)
	(segment
		(start 145.89 147.08)
		(end 147.43 145.54)
		(width 0.15)
		(layer "B.Cu")
		(net 637)
	)
	(segment
		(start 130.877001 164.672999)
		(end 131.25 164.3)
		(width 0.15)
		(layer "B.Cu")
		(net 637)
	)
	(segment
		(start 145.89 147.77)
		(end 145.89 147.08)
		(width 0.15)
		(layer "B.Cu")
		(net 637)
	)
	(segment
		(start 135.35 164.05)
		(end 135.35 161.25)
		(width 0.15)
		(layer "B.Cu")
		(net 637)
	)
	(segment
		(start 135.1 164.3)
		(end 135.35 164.05)
		(width 0.15)
		(layer "B.Cu")
		(net 637)
	)
	(segment
		(start 147.43 144.67)
		(end 148.55 143.55)
		(width 0.15)
		(layer "B.Cu")
		(net 637)
	)
	(segment
		(start 133.4 157.6)
		(end 142.53 148.47)
		(width 0.15)
		(layer "B.Cu")
		(net 637)
	)
	(segment
		(start 102.496501 176.135)
		(end 103.405 176.135)
		(width 0.15)
		(layer "F.Cu")
		(net 638)
	)
	(segment
		(start 103.83 175.71)
		(end 104.38 175.71)
		(width 0.15)
		(layer "F.Cu")
		(net 638)
	)
	(segment
		(start 103.405 176.135)
		(end 103.83 175.71)
		(width 0.15)
		(layer "F.Cu")
		(net 638)
	)
	(segment
		(start 107.26 176.045)
		(end 107.635 176.045)
		(width 0.15)
		(layer "F.Cu")
		(net 639)
	)
	(segment
		(start 127.3765 182.301)
		(end 126.877001 182.800499)
		(width 0.256)
		(layer "F.Cu")
		(net 639)
	)
	(segment
		(start 107.635 176.045)
		(end 107.955166 175.724834)
		(width 0.15)
		(layer "F.Cu")
		(net 639)
	)
	(via
		(at 126.877001 182.800499)
		(size 0.45)
		(drill 0.1)
		(layers "F.Cu" "B.Cu")
		(net 639)
	)
	(via
		(at 107.955166 175.724834)
		(size 0.45)
		(drill 0.1)
		(layers "F.Cu" "B.Cu")
		(net 639)
	)
	(segment
		(start 107.955166 175.724834)
		(end 107.955166 177.085166)
		(width 0.15)
		(layer "B.Cu")
		(net 639)
	)
	(segment
		(start 107.955166 177.085166)
		(end 110 179.13)
		(width 0.15)
		(layer "B.Cu")
		(net 639)
	)
	(segment
		(start 107.574 176.106)
		(end 107.955166 175.724834)
		(width 0.1)
		(layer "In9.Cu")
		(net 639)
	)
	(segment
		(start 101.85 182.55)
		(end 101.85 181.9)
		(width 0.1)
		(layer "In9.Cu")
		(net 639)
	)
	(segment
		(start 126.877001 182.800499)
		(end 126.3775 183.3)
		(width 0.1)
		(layer "In9.Cu")
		(net 639)
	)
	(segment
		(start 102.2 182.9)
		(end 101.85 182.55)
		(width 0.1)
		(layer "In9.Cu")
		(net 639)
	)
	(segment
		(start 124.7 181.630916)
		(end 122.569084 179.5)
		(width 0.1)
		(layer "In9.Cu")
		(net 639)
	)
	(segment
		(start 107.6 181.7)
		(end 107.225 182.075)
		(width 0.1)
		(layer "In9.Cu")
		(net 639)
	)
	(segment
		(start 107.225 182.375)
		(end 106.7 182.9)
		(width 0.1)
		(layer "In9.Cu")
		(net 639)
	)
	(segment
		(start 122.569084 179.5)
		(end 110.1 179.5)
		(width 0.1)
		(layer "In9.Cu")
		(net 639)
	)
	(segment
		(start 110.1 179.5)
		(end 108.7 180.9)
		(width 0.1)
		(layer "In9.Cu")
		(net 639)
	)
	(segment
		(start 102.425 178.825)
		(end 105.144 176.106)
		(width 0.1)
		(layer "In9.Cu")
		(net 639)
	)
	(segment
		(start 106.7 182.9)
		(end 102.2 182.9)
		(width 0.1)
		(layer "In9.Cu")
		(net 639)
	)
	(segment
		(start 108.7 180.9)
		(end 108.7 181.2)
		(width 0.1)
		(layer "In9.Cu")
		(net 639)
	)
	(segment
		(start 108.7 181.2)
		(end 108.2 181.7)
		(width 0.1)
		(layer "In9.Cu")
		(net 639)
	)
	(segment
		(start 125.410501 183.3)
		(end 124.7 182.589499)
		(width 0.1)
		(layer "In9.Cu")
		(net 639)
	)
	(segment
		(start 101.85 181.9)
		(end 102.425 181.325)
		(width 0.1)
		(layer "In9.Cu")
		(net 639)
	)
	(segment
		(start 107.225 182.075)
		(end 107.225 182.375)
		(width 0.1)
		(layer "In9.Cu")
		(net 639)
	)
	(segment
		(start 124.7 182.589499)
		(end 124.7 181.630916)
		(width 0.1)
		(layer "In9.Cu")
		(net 639)
	)
	(segment
		(start 102.425 181.325)
		(end 102.425 178.825)
		(width 0.1)
		(layer "In9.Cu")
		(net 639)
	)
	(segment
		(start 126.3775 183.3)
		(end 125.410501 183.3)
		(width 0.1)
		(layer "In9.Cu")
		(net 639)
	)
	(segment
		(start 108.2 181.7)
		(end 107.6 181.7)
		(width 0.1)
		(layer "In9.Cu")
		(net 639)
	)
	(segment
		(start 105.144 176.106)
		(end 107.574 176.106)
		(width 0.1)
		(layer "In9.Cu")
		(net 639)
	)
	(segment
		(start 103.375 175.635)
		(end 103.65 175.36)
		(width 0.15)
		(layer "F.Cu")
		(net 640)
	)
	(segment
		(start 102.496501 175.635)
		(end 103.375 175.635)
		(width 0.15)
		(layer "F.Cu")
		(net 640)
	)
	(segment
		(start 103.65 175.36)
		(end 104.38 175.36)
		(width 0.15)
		(layer "F.Cu")
		(net 640)
	)
	(segment
		(start 126.376501 183.301)
		(end 125.877001 183.8005)
		(width 0.256)
		(layer "F.Cu")
		(net 641)
	)
	(segment
		(start 107.26 175.02)
		(end 107.81 175.02)
		(width 0.15)
		(layer "F.Cu")
		(net 641)
	)
	(via
		(at 125.877001 183.8005)
		(size 0.45)
		(drill 0.1)
		(layers "F.Cu" "B.Cu")
		(net 641)
	)
	(via
		(at 107.81 175.02)
		(size 0.45)
		(drill 0.1)
		(layers "F.Cu" "B.Cu")
		(net 641)
	)
	(segment
		(start 107.81 175.02)
		(end 109.22 175.02)
		(width 0.15)
		(layer "B.Cu")
		(net 641)
	)
	(segment
		(start 110 175.8)
		(end 110 176.63)
		(width 0.15)
		(layer "B.Cu")
		(net 641)
	)
	(segment
		(start 109.22 175.02)
		(end 110 175.8)
		(width 0.15)
		(layer "B.Cu")
		(net 641)
	)
	(segment
		(start 124.45 182.95)
		(end 124.1 182.95)
		(width 0.1)
		(layer "In9.Cu")
		(net 641)
	)
	(segment
		(start 107.802 175.028)
		(end 107.81 175.02)
		(width 0.1)
		(layer "In9.Cu")
		(net 641)
	)
	(segment
		(start 105.050963 175.028)
		(end 107.802 175.028)
		(width 0.1)
		(layer "In9.Cu")
		(net 641)
	)
	(segment
		(start 111.524331 180.15)
		(end 107.924331 183.75)
		(width 0.1)
		(layer "In9.Cu")
		(net 641)
	)
	(segment
		(start 101.3 181.65)
		(end 101.85 181.1)
		(width 0.1)
		(layer "In9.Cu")
		(net 641)
	)
	(segment
		(start 125.3005 183.8005)
		(end 124.45 182.95)
		(width 0.1)
		(layer "In9.Cu")
		(net 641)
	)
	(segment
		(start 125.877001 183.8005)
		(end 125.3005 183.8005)
		(width 0.1)
		(layer "In9.Cu")
		(net 641)
	)
	(segment
		(start 101.85 181.1)
		(end 101.85 178.228963)
		(width 0.1)
		(layer "In9.Cu")
		(net 641)
	)
	(segment
		(start 101.3 183.1)
		(end 101.3 181.65)
		(width 0.1)
		(layer "In9.Cu")
		(net 641)
	)
	(segment
		(start 101.95 183.75)
		(end 101.3 183.1)
		(width 0.1)
		(layer "In9.Cu")
		(net 641)
	)
	(segment
		(start 101.85 178.228963)
		(end 105.050963 175.028)
		(width 0.1)
		(layer "In9.Cu")
		(net 641)
	)
	(segment
		(start 107.924331 183.75)
		(end 101.95 183.75)
		(width 0.1)
		(layer "In9.Cu")
		(net 641)
	)
	(segment
		(start 124.1 182.95)
		(end 121.3 180.15)
		(width 0.1)
		(layer "In9.Cu")
		(net 641)
	)
	(segment
		(start 121.3 180.15)
		(end 111.524331 180.15)
		(width 0.1)
		(layer "In9.Cu")
		(net 641)
	)
	(segment
		(start 103.74 172.01)
		(end 103.517344 171.787344)
		(width 0.15)
		(layer "F.Cu")
		(net 642)
	)
	(segment
		(start 104.38 172.01)
		(end 103.74 172.01)
		(width 0.15)
		(layer "F.Cu")
		(net 642)
	)
	(segment
		(start 103.517344 171.787344)
		(end 103.517344 171.464471)
		(width 0.15)
		(layer "F.Cu")
		(net 642)
	)
	(segment
		(start 103.188873 171.136)
		(end 102.496501 171.136)
		(width 0.15)
		(layer "F.Cu")
		(net 642)
	)
	(segment
		(start 103.517344 171.464471)
		(end 103.188873 171.136)
		(width 0.15)
		(layer "F.Cu")
		(net 642)
	)
	(segment
		(start 107.8 172.76)
		(end 107.765 172.76)
		(width 0.1)
		(layer "F.Cu")
		(net 643)
	)
	(segment
		(start 128.376501 187.301)
		(end 127.877001 187.8005)
		(width 0.256)
		(layer "F.Cu")
		(net 643)
	)
	(segment
		(start 107.765 172.76)
		(end 107.265 172.26)
		(width 0.15)
		(layer "F.Cu")
		(net 643)
	)
	(via
		(at 107.8 172.76)
		(size 0.45)
		(drill 0.1)
		(layers "F.Cu" "B.Cu")
		(net 643)
	)
	(via
		(at 127.877001 187.8005)
		(size 0.45)
		(drill 0.1)
		(layers "F.Cu" "B.Cu")
		(net 643)
	)
	(segment
		(start 108.63 172.76)
		(end 110 174.13)
		(width 0.15)
		(layer "B.Cu")
		(net 643)
	)
	(segment
		(start 107.8 172.76)
		(end 108.63 172.76)
		(width 0.15)
		(layer "B.Cu")
		(net 643)
	)
	(segment
		(start 119.65 185.1)
		(end 119.3 184.75)
		(width 0.1)
		(layer "In9.Cu")
		(net 643)
	)
	(segment
		(start 100.15 187.65)
		(end 96.426 183.926)
		(width 0.1)
		(layer "In9.Cu")
		(net 643)
	)
	(segment
		(start 127.877001 187.8005)
		(end 127.276501 187.2)
		(width 0.1)
		(layer "In9.Cu")
		(net 643)
	)
	(segment
		(start 127.276501 187.2)
		(end 125.4 187.2)
		(width 0.1)
		(layer "In9.Cu")
		(net 643)
	)
	(segment
		(start 109.5 187.65)
		(end 100.15 187.65)
		(width 0.1)
		(layer "In9.Cu")
		(net 643)
	)
	(segment
		(start 123.3 185.1)
		(end 119.65 185.1)
		(width 0.1)
		(layer "In9.Cu")
		(net 643)
	)
	(segment
		(start 116 184.75)
		(end 115.8 184.95)
		(width 0.1)
		(layer "In9.Cu")
		(net 643)
	)
	(segment
		(start 115.8 184.95)
		(end 112.2 184.95)
		(width 0.1)
		(layer "In9.Cu")
		(net 643)
	)
	(segment
		(start 125.4 187.2)
		(end 123.3 185.1)
		(width 0.1)
		(layer "In9.Cu")
		(net 643)
	)
	(segment
		(start 96.426 174.849)
		(end 99.265 172.01)
		(width 0.1)
		(layer "In9.Cu")
		(net 643)
	)
	(segment
		(start 96.426 183.926)
		(end 96.426 174.849)
		(width 0.1)
		(layer "In9.Cu")
		(net 643)
	)
	(segment
		(start 112.2 184.95)
		(end 109.5 187.65)
		(width 0.1)
		(layer "In9.Cu")
		(net 643)
	)
	(segment
		(start 99.265 172.01)
		(end 107.05 172.01)
		(width 0.1)
		(layer "In9.Cu")
		(net 643)
	)
	(segment
		(start 107.05 172.01)
		(end 107.8 172.76)
		(width 0.1)
		(layer "In9.Cu")
		(net 643)
	)
	(segment
		(start 119.3 184.75)
		(end 116 184.75)
		(width 0.1)
		(layer "In9.Cu")
		(net 643)
	)
	(segment
		(start 104.38 171.66)
		(end 104.08 171.66)
		(width 0.15)
		(layer "F.Cu")
		(net 644)
	)
	(segment
		(start 99.909 169.5495)
		(end 100.307501 169.948001)
		(width 0.15)
		(layer "F.Cu")
		(net 644)
	)
	(segment
		(start 99.849 169.5495)
		(end 99.909 169.5495)
		(width 0.15)
		(layer "F.Cu")
		(net 644)
	)
	(segment
		(start 104.08 171.66)
		(end 103.31 170.89)
		(width 0.15)
		(layer "F.Cu")
		(net 644)
	)
	(segment
		(start 100.307501 169.948001)
		(end 100.307501 170.4475)
		(width 0.15)
		(layer "F.Cu")
		(net 644)
	)
	(segment
		(start 103.31 170.89)
		(end 103.31 170.54)
		(width 0.15)
		(layer "F.Cu")
		(net 644)
	)
	(via
		(at 103.31 170.54)
		(size 0.45)
		(drill 0.1)
		(layers "F.Cu" "B.Cu")
		(net 644)
	)
	(via
		(at 99.849 169.5495)
		(size 0.45)
		(drill 0.1)
		(layers "F.Cu" "B.Cu")
		(net 644)
	)
	(segment
		(start 103.309 170.5395)
		(end 100.839 170.5395)
		(width 0.15)
		(layer "B.Cu")
		(net 644)
	)
	(segment
		(start 100.839 170.5395)
		(end 99.849 169.5495)
		(width 0.15)
		(layer "B.Cu")
		(net 644)
	)
	(segment
		(start 129.376501 187.301)
		(end 128.877001 187.8005)
		(width 0.256)
		(layer "F.Cu")
		(net 645)
	)
	(segment
		(start 107.635 171.63)
		(end 107.88 171.63)
		(width 0.15)
		(layer "F.Cu")
		(net 645)
	)
	(segment
		(start 107.265 171.26)
		(end 107.635 171.63)
		(width 0.15)
		(layer "F.Cu")
		(net 645)
	)
	(via
		(at 128.877001 187.8005)
		(size 0.45)
		(drill 0.1)
		(layers "F.Cu" "B.Cu")
		(net 645)
	)
	(via
		(at 107.88 171.63)
		(size 0.45)
		(drill 0.1)
		(layers "F.Cu" "B.Cu")
		(net 645)
	)
	(segment
		(start 110 171.63)
		(end 107.88 171.63)
		(width 0.15)
		(layer "B.Cu")
		(net 645)
	)
	(segment
		(start 109.7 188.2)
		(end 99.5 188.2)
		(width 0.1)
		(layer "In9.Cu")
		(net 645)
	)
	(segment
		(start 112.5 185.4)
		(end 109.7 188.2)
		(width 0.1)
		(layer "In9.Cu")
		(net 645)
	)
	(segment
		(start 127.622501 188.35)
		(end 127.35 188.077499)
		(width 0.1)
		(layer "In9.Cu")
		(net 645)
	)
	(segment
		(start 127.35 187.743168)
		(end 127.032332 187.4255)
		(width 0.1)
		(layer "In9.Cu")
		(net 645)
	)
	(segment
		(start 99.5 188.2)
		(end 95.7 184.4)
		(width 0.1)
		(layer "In9.Cu")
		(net 645)
	)
	(segment
		(start 127.35 188.077499)
		(end 127.35 187.743168)
		(width 0.1)
		(layer "In9.Cu")
		(net 645)
	)
	(segment
		(start 128.348501 188.35)
		(end 127.622501 188.35)
		(width 0.1)
		(layer "In9.Cu")
		(net 645)
	)
	(segment
		(start 123.1 185.4)
		(end 112.5 185.4)
		(width 0.1)
		(layer "In9.Cu")
		(net 645)
	)
	(segment
		(start 128.877001 187.8005)
		(end 128.877001 187.8215)
		(width 0.1)
		(layer "In9.Cu")
		(net 645)
	)
	(segment
		(start 107.505157 171.255157)
		(end 107.88 171.63)
		(width 0.1)
		(layer "In9.Cu")
		(net 645)
	)
	(segment
		(start 125.1255 187.4255)
		(end 123.1 185.4)
		(width 0.1)
		(layer "In9.Cu")
		(net 645)
	)
	(segment
		(start 98.444843 171.255157)
		(end 107.505157 171.255157)
		(width 0.1)
		(layer "In9.Cu")
		(net 645)
	)
	(segment
		(start 95.7 184.4)
		(end 95.7 174)
		(width 0.1)
		(layer "In9.Cu")
		(net 645)
	)
	(segment
		(start 128.877001 187.8215)
		(end 128.348501 188.35)
		(width 0.1)
		(layer "In9.Cu")
		(net 645)
	)
	(segment
		(start 95.7 174)
		(end 98.444843 171.255157)
		(width 0.1)
		(layer "In9.Cu")
		(net 645)
	)
	(segment
		(start 127.032332 187.4255)
		(end 125.1255 187.4255)
		(width 0.1)
		(layer "In9.Cu")
		(net 645)
	)
	(segment
		(start 105.650999 179.091)
		(end 105.645 179.085)
		(width 0.15)
		(layer "F.Cu")
		(net 646)
	)
	(segment
		(start 98.808501 178.323)
		(end 98.808501 179.691499)
		(width 0.15)
		(layer "F.Cu")
		(net 646)
	)
	(segment
		(start 105.651 180.435)
		(end 105.650999 179.091)
		(width 0.15)
		(layer "F.Cu")
		(net 646)
	)
	(segment
		(start 98.808501 179.691499)
		(end 98.8 179.7)
		(width 0.15)
		(layer "F.Cu")
		(net 646)
	)
	(via
		(at 98.8 179.7)
		(size 0.45)
		(drill 0.1)
		(layers "F.Cu" "B.Cu")
		(net 646)
	)
	(via
		(at 105.645 179.085)
		(size 0.45)
		(drill 0.1)
		(layers "F.Cu" "B.Cu")
		(net 646)
	)
	(segment
		(start 105.645 179.085)
		(end 105.11 178.55)
		(width 0.15)
		(layer "B.Cu")
		(net 646)
	)
	(segment
		(start 98 180)
		(end 98.3 179.7)
		(width 0.15)
		(layer "B.Cu")
		(net 646)
	)
	(segment
		(start 99.5 177.55)
		(end 98.8 178.25)
		(width 0.15)
		(layer "B.Cu")
		(net 646)
	)
	(segment
		(start 98.3 179.7)
		(end 98.8 179.7)
		(width 0.15)
		(layer "B.Cu")
		(net 646)
	)
	(segment
		(start 98.8 178.25)
		(end 98.8 179.7)
		(width 0.15)
		(layer "B.Cu")
		(net 646)
	)
	(segment
		(start 103.8 177.55)
		(end 99.5 177.55)
		(width 0.15)
		(layer "B.Cu")
		(net 646)
	)
	(segment
		(start 98 180.465)
		(end 98 180)
		(width 0.15)
		(layer "B.Cu")
		(net 646)
	)
	(segment
		(start 104.8 178.55)
		(end 103.8 177.55)
		(width 0.15)
		(layer "B.Cu")
		(net 646)
	)
	(segment
		(start 105.11 178.55)
		(end 104.8 178.55)
		(width 0.15)
		(layer "B.Cu")
		(net 646)
	)
	(segment
		(start 128.376501 185.301)
		(end 127.877001 185.8005)
		(width 0.256)
		(layer "F.Cu")
		(net 647)
	)
	(via
		(at 127.877001 185.8005)
		(size 0.45)
		(drill 0.1)
		(layers "F.Cu" "B.Cu")
		(net 647)
	)
	(via
		(at 98 182.15)
		(size 0.45)
		(drill 0.1)
		(layers "F.Cu" "B.Cu")
		(net 647)
	)
	(segment
		(start 98 181.435)
		(end 98 182.15)
		(width 0.15)
		(layer "B.Cu")
		(net 647)
	)
	(segment
		(start 111.7 184.5)
		(end 109.3 186.9)
		(width 0.1)
		(layer "In9.Cu")
		(net 647)
	)
	(segment
		(start 125.1255 186.4255)
		(end 123.5 184.8)
		(width 0.1)
		(layer "In9.Cu")
		(net 647)
	)
	(segment
		(start 114.1 184.5)
		(end 111.7 184.5)
		(width 0.1)
		(layer "In9.Cu")
		(net 647)
	)
	(segment
		(start 120.6 184.8)
		(end 119.65 183.85)
		(width 0.1)
		(layer "In9.Cu")
		(net 647)
	)
	(segment
		(start 98 184.2)
		(end 98 182.15)
		(width 0.1)
		(layer "In9.Cu")
		(net 647)
	)
	(segment
		(start 127.252 186.4255)
		(end 125.1255 186.4255)
		(width 0.1)
		(layer "In9.Cu")
		(net 647)
	)
	(segment
		(start 109.3 186.9)
		(end 100.7 186.9)
		(width 0.1)
		(layer "In9.Cu")
		(net 647)
	)
	(segment
		(start 123.5 184.8)
		(end 120.6 184.8)
		(width 0.1)
		(layer "In9.Cu")
		(net 647)
	)
	(segment
		(start 119.65 183.85)
		(end 114.75 183.85)
		(width 0.1)
		(layer "In9.Cu")
		(net 647)
	)
	(segment
		(start 127.877001 185.8005)
		(end 127.252 186.4255)
		(width 0.1)
		(layer "In9.Cu")
		(net 647)
	)
	(segment
		(start 114.75 183.85)
		(end 114.1 184.5)
		(width 0.1)
		(layer "In9.Cu")
		(net 647)
	)
	(segment
		(start 100.7 186.9)
		(end 98 184.2)
		(width 0.1)
		(layer "In9.Cu")
		(net 647)
	)
	(segment
		(start 104.656999 179.091)
		(end 104.651 179.085)
		(width 0.15)
		(layer "F.Cu")
		(net 648)
	)
	(segment
		(start 99.308501 179.191499)
		(end 99.3 179.2)
		(width 0.15)
		(layer "F.Cu")
		(net 648)
	)
	(segment
		(start 104.657 180.435)
		(end 104.656999 179.091)
		(width 0.15)
		(layer "F.Cu")
		(net 648)
	)
	(segment
		(start 99.308501 178.323)
		(end 99.308501 179.191499)
		(width 0.15)
		(layer "F.Cu")
		(net 648)
	)
	(via
		(at 99.3 179.2)
		(size 0.45)
		(drill 0.1)
		(layers "F.Cu" "B.Cu")
		(net 648)
	)
	(via
		(at 104.651 179.085)
		(size 0.45)
		(drill 0.1)
		(layers "F.Cu" "B.Cu")
		(net 648)
	)
	(segment
		(start 99.3 180.215)
		(end 99.05 180.465)
		(width 0.15)
		(layer "B.Cu")
		(net 648)
	)
	(segment
		(start 103.666 178.1)
		(end 99.85 178.1)
		(width 0.15)
		(layer "B.Cu")
		(net 648)
	)
	(segment
		(start 104.651 179.085)
		(end 103.666 178.1)
		(width 0.15)
		(layer "B.Cu")
		(net 648)
	)
	(segment
		(start 99.3 179.2)
		(end 99.3 180.215)
		(width 0.15)
		(layer "B.Cu")
		(net 648)
	)
	(segment
		(start 99.3 178.65)
		(end 99.3 179.2)
		(width 0.15)
		(layer "B.Cu")
		(net 648)
	)
	(segment
		(start 99.85 178.1)
		(end 99.3 178.65)
		(width 0.15)
		(layer "B.Cu")
		(net 648)
	)
	(segment
		(start 128.376501 184.301)
		(end 127.877001 184.8005)
		(width 0.256)
		(layer "F.Cu")
		(net 649)
	)
	(via
		(at 98.6 182.625)
		(size 0.45)
		(drill 0.1)
		(layers "F.Cu" "B.Cu")
		(net 649)
	)
	(via
		(at 127.877001 184.8005)
		(size 0.45)
		(drill 0.1)
		(layers "F.Cu" "B.Cu")
		(net 649)
	)
	(segment
		(start 98.6 181.885)
		(end 98.6 182.625)
		(width 0.15)
		(layer "B.Cu")
		(net 649)
	)
	(segment
		(start 99.05 181.435)
		(end 98.6 181.885)
		(width 0.15)
		(layer "B.Cu")
		(net 649)
	)
	(segment
		(start 98.6 182.625)
		(end 98.6 183.7)
		(width 0.1)
		(layer "In9.Cu")
		(net 649)
	)
	(segment
		(start 119.9 183.2)
		(end 121.15 184.45)
		(width 0.1)
		(layer "In9.Cu")
		(net 649)
	)
	(segment
		(start 127.252001 185.4255)
		(end 127.877001 184.8005)
		(width 0.1)
		(layer "In9.Cu")
		(net 649)
	)
	(segment
		(start 127.032332 186.1755)
		(end 127.252001 185.955831)
		(width 0.1)
		(layer "In9.Cu")
		(net 649)
	)
	(segment
		(start 127.252001 185.955831)
		(end 127.252001 185.4255)
		(width 0.1)
		(layer "In9.Cu")
		(net 649)
	)
	(segment
		(start 125.4755 186.1755)
		(end 127.032332 186.1755)
		(width 0.1)
		(layer "In9.Cu")
		(net 649)
	)
	(segment
		(start 121.15 184.45)
		(end 123.75 184.45)
		(width 0.1)
		(layer "In9.Cu")
		(net 649)
	)
	(segment
		(start 123.75 184.45)
		(end 125.4755 186.1755)
		(width 0.1)
		(layer "In9.Cu")
		(net 649)
	)
	(segment
		(start 101.2 186.3)
		(end 108.85 186.3)
		(width 0.1)
		(layer "In9.Cu")
		(net 649)
	)
	(segment
		(start 108.85 186.3)
		(end 111.95 183.2)
		(width 0.1)
		(layer "In9.Cu")
		(net 649)
	)
	(segment
		(start 98.6 183.7)
		(end 101.2 186.3)
		(width 0.1)
		(layer "In9.Cu")
		(net 649)
	)
	(segment
		(start 111.95 183.2)
		(end 119.9 183.2)
		(width 0.1)
		(layer "In9.Cu")
		(net 649)
	)
	(segment
		(start 99.808501 179.691499)
		(end 99.8 179.7)
		(width 0.15)
		(layer "F.Cu")
		(net 650)
	)
	(segment
		(start 104.156999 180.435)
		(end 104.157 179.585)
		(width 0.15)
		(layer "F.Cu")
		(net 650)
	)
	(segment
		(start 99.808501 178.323)
		(end 99.808501 179.691499)
		(width 0.15)
		(layer "F.Cu")
		(net 650)
	)
	(via
		(at 99.8 179.7)
		(size 0.45)
		(drill 0.1)
		(layers "F.Cu" "B.Cu")
		(net 650)
	)
	(via
		(at 104.157 179.585)
		(size 0.45)
		(drill 0.1)
		(layers "F.Cu" "B.Cu")
		(net 650)
	)
	(segment
		(start 103.122 178.55)
		(end 104.157 179.585)
		(width 0.15)
		(layer "B.Cu")
		(net 650)
	)
	(segment
		(start 99.8 179.7)
		(end 99.8 178.8)
		(width 0.15)
		(layer "B.Cu")
		(net 650)
	)
	(segment
		(start 99.8 180.165)
		(end 100.1 180.465)
		(width 0.15)
		(layer "B.Cu")
		(net 650)
	)
	(segment
		(start 100.05 178.55)
		(end 103.122 178.55)
		(width 0.15)
		(layer "B.Cu")
		(net 650)
	)
	(segment
		(start 99.8 179.7)
		(end 99.8 180.165)
		(width 0.15)
		(layer "B.Cu")
		(net 650)
	)
	(segment
		(start 99.8 178.8)
		(end 100.05 178.55)
		(width 0.15)
		(layer "B.Cu")
		(net 650)
	)
	(segment
		(start 126.376501 185.301)
		(end 125.877001 185.8005)
		(width 0.256)
		(layer "F.Cu")
		(net 651)
	)
	(via
		(at 125.877001 185.8005)
		(size 0.45)
		(drill 0.1)
		(layers "F.Cu" "B.Cu")
		(net 651)
	)
	(via
		(at 99.225 182.225)
		(size 0.45)
		(drill 0.1)
		(layers "F.Cu" "B.Cu")
		(net 651)
	)
	(segment
		(start 100.1 181.435)
		(end 100.1 181.875)
		(width 0.15)
		(layer "B.Cu")
		(net 651)
	)
	(segment
		(start 99.75 182.225)
		(end 99.225 182.225)
		(width 0.15)
		(layer "B.Cu")
		(net 651)
	)
	(segment
		(start 100.1 181.875)
		(end 99.75 182.225)
		(width 0.15)
		(layer "B.Cu")
		(net 651)
	)
	(segment
		(start 119.75 182.1)
		(end 121.815001 184.165001)
		(width 0.1)
		(layer "In9.Cu")
		(net 651)
	)
	(segment
		(start 99.225 183.15)
		(end 101.375 185.3)
		(width 0.1)
		(layer "In9.Cu")
		(net 651)
	)
	(segment
		(start 112.15 182.1)
		(end 119.75 182.1)
		(width 0.1)
		(layer "In9.Cu")
		(net 651)
	)
	(segment
		(start 124.241502 184.165001)
		(end 125.877001 185.8005)
		(width 0.1)
		(layer "In9.Cu")
		(net 651)
	)
	(segment
		(start 108.95 185.3)
		(end 112.15 182.1)
		(width 0.1)
		(layer "In9.Cu")
		(net 651)
	)
	(segment
		(start 121.815001 184.165001)
		(end 124.241502 184.165001)
		(width 0.1)
		(layer "In9.Cu")
		(net 651)
	)
	(segment
		(start 99.225 182.225)
		(end 99.225 183.15)
		(width 0.1)
		(layer "In9.Cu")
		(net 651)
	)
	(segment
		(start 101.375 185.3)
		(end 108.95 185.3)
		(width 0.1)
		(layer "In9.Cu")
		(net 651)
	)
	(segment
		(start 100.6 179.5)
		(end 100.3 179.2)
		(width 0.15)
		(layer "F.Cu")
		(net 652)
	)
	(segment
		(start 100.6 180.965)
		(end 100.6 179.5)
		(width 0.15)
		(layer "F.Cu")
		(net 652)
	)
	(segment
		(start 100.308501 178.323)
		(end 100.308501 179.191499)
		(width 0.15)
		(layer "F.Cu")
		(net 652)
	)
	(segment
		(start 100.308501 179.191499)
		(end 100.3 179.2)
		(width 0.15)
		(layer "F.Cu")
		(net 652)
	)
	(via
		(at 100.3 179.2)
		(size 0.45)
		(drill 0.1)
		(layers "F.Cu" "B.Cu")
		(net 652)
	)
	(segment
		(start 100.3 179.615)
		(end 101.15 180.465)
		(width 0.15)
		(layer "B.Cu")
		(net 652)
	)
	(segment
		(start 100.3 179.2)
		(end 100.3 179.615)
		(width 0.15)
		(layer "B.Cu")
		(net 652)
	)
	(segment
		(start 127.376501 184.301)
		(end 126.877001 184.8005)
		(width 0.256)
		(layer "F.Cu")
		(net 653)
	)
	(via
		(at 99.925 182.625)
		(size 0.45)
		(drill 0.1)
		(layers "F.Cu" "B.Cu")
		(net 653)
	)
	(via
		(at 126.877001 184.8005)
		(size 0.45)
		(drill 0.1)
		(layers "F.Cu" "B.Cu")
		(net 653)
	)
	(segment
		(start 101.15 181.435)
		(end 101.15 181.975)
		(width 0.15)
		(layer "B.Cu")
		(net 653)
	)
	(segment
		(start 101.15 181.975)
		(end 100.5 182.625)
		(width 0.15)
		(layer "B.Cu")
		(net 653)
	)
	(segment
		(start 100.5 182.625)
		(end 99.925 182.625)
		(width 0.15)
		(layer "B.Cu")
		(net 653)
	)
	(segment
		(start 124.3 183.4)
		(end 125.2 184.3)
		(width 0.1)
		(layer "In9.Cu")
		(net 653)
	)
	(segment
		(start 126.376501 184.3)
		(end 126.877001 184.8005)
		(width 0.1)
		(layer "In9.Cu")
		(net 653)
	)
	(segment
		(start 122.5 183.4)
		(end 124.3 183.4)
		(width 0.1)
		(layer "In9.Cu")
		(net 653)
	)
	(segment
		(start 125.2 184.3)
		(end 126.376501 184.3)
		(width 0.1)
		(layer "In9.Cu")
		(net 653)
	)
	(segment
		(start 108.7 184.3)
		(end 112.25 180.75)
		(width 0.1)
		(layer "In9.Cu")
		(net 653)
	)
	(segment
		(start 114.95 181.5)
		(end 120.6 181.5)
		(width 0.1)
		(layer "In9.Cu")
		(net 653)
	)
	(segment
		(start 114.2 180.75)
		(end 114.95 181.5)
		(width 0.1)
		(layer "In9.Cu")
		(net 653)
	)
	(segment
		(start 120.6 181.5)
		(end 122.5 183.4)
		(width 0.1)
		(layer "In9.Cu")
		(net 653)
	)
	(segment
		(start 99.925 182.625)
		(end 101.6 184.3)
		(width 0.1)
		(layer "In9.Cu")
		(net 653)
	)
	(segment
		(start 101.6 184.3)
		(end 108.7 184.3)
		(width 0.1)
		(layer "In9.Cu")
		(net 653)
	)
	(segment
		(start 112.25 180.75)
		(end 114.2 180.75)
		(width 0.1)
		(layer "In9.Cu")
		(net 653)
	)
	(segment
		(start 101.308501 180.623501)
		(end 101.308501 179.758501)
		(width 0.15)
		(layer "F.Cu")
		(net 654)
	)
	(segment
		(start 101.308501 178.323)
		(end 101.308501 179.741499)
		(width 0.15)
		(layer "F.Cu")
		(net 654)
	)
	(segment
		(start 101.308501 179.758501)
		(end 101.3 179.75)
		(width 0.15)
		(layer "F.Cu")
		(net 654)
	)
	(segment
		(start 101.308501 180.623501)
		(end 101.65 180.965)
		(width 0.15)
		(layer "F.Cu")
		(net 654)
	)
	(segment
		(start 101.308501 179.741499)
		(end 101.3 179.75)
		(width 0.15)
		(layer "F.Cu")
		(net 654)
	)
	(via
		(at 101.3 179.75)
		(size 0.45)
		(drill 0.1)
		(layers "F.Cu" "B.Cu")
		(net 654)
	)
	(segment
		(start 101.3 179.75)
		(end 102 179.75)
		(width 0.15)
		(layer "B.Cu")
		(net 654)
	)
	(segment
		(start 102 179.75)
		(end 102.2 179.95)
		(width 0.15)
		(layer "B.Cu")
		(net 654)
	)
	(segment
		(start 102.2 179.95)
		(end 102.2 180.465)
		(width 0.15)
		(layer "B.Cu")
		(net 654)
	)
	(segment
		(start 127.376501 181.301)
		(end 126.877001 181.800501)
		(width 0.256)
		(layer "F.Cu")
		(net 655)
	)
	(via
		(at 126.877001 181.800501)
		(size 0.45)
		(drill 0.1)
		(layers "F.Cu" "B.Cu")
		(net 655)
	)
	(via
		(at 102.4 182.4)
		(size 0.45)
		(drill 0.1)
		(layers "F.Cu" "B.Cu")
		(net 655)
	)
	(segment
		(start 102.2 181.435)
		(end 102.2 182.2)
		(width 0.15)
		(layer "B.Cu")
		(net 655)
	)
	(segment
		(start 102.2 182.2)
		(end 102.4 182.4)
		(width 0.15)
		(layer "B.Cu")
		(net 655)
	)
	(segment
		(start 125.648085 182.3)
		(end 125.05 181.701915)
		(width 0.1)
		(layer "In9.Cu")
		(net 655)
	)
	(segment
		(start 125.05 180.55)
		(end 123.15 178.65)
		(width 0.1)
		(layer "In9.Cu")
		(net 655)
	)
	(segment
		(start 104.85 182.4)
		(end 102.4 182.4)
		(width 0.1)
		(layer "In9.Cu")
		(net 655)
	)
	(segment
		(start 126.377502 182.3)
		(end 125.648085 182.3)
		(width 0.1)
		(layer "In9.Cu")
		(net 655)
	)
	(segment
		(start 108.6 178.65)
		(end 104.85 182.4)
		(width 0.1)
		(layer "In9.Cu")
		(net 655)
	)
	(segment
		(start 123.15 178.65)
		(end 108.6 178.65)
		(width 0.1)
		(layer "In9.Cu")
		(net 655)
	)
	(segment
		(start 125.05 181.701915)
		(end 125.05 180.55)
		(width 0.1)
		(layer "In9.Cu")
		(net 655)
	)
	(segment
		(start 126.877001 181.800501)
		(end 126.377502 182.3)
		(width 0.1)
		(layer "In9.Cu")
		(net 655)
	)
	(segment
		(start 94.148 192.447)
		(end 93.553 192.447)
		(width 0.201)
		(layer "F.Cu")
		(net 656)
	)
	(segment
		(start 92.7 193.3)
		(end 92.7 194.33)
		(width 0.201)
		(layer "F.Cu")
		(net 656)
	)
	(segment
		(start 93.553 192.447)
		(end 92.7 193.3)
		(width 0.201)
		(layer "F.Cu")
		(net 656)
	)
	(segment
		(start 94.699 193.931)
		(end 94.3 194.33)
		(width 0.201)
		(layer "F.Cu")
		(net 657)
	)
	(segment
		(start 94.699 192.998)
		(end 94.699 193.931)
		(width 0.201)
		(layer "F.Cu")
		(net 657)
	)
	(segment
		(start 95.096 192.998)
		(end 95.096 193.696)
		(width 0.201)
		(layer "F.Cu")
		(net 658)
	)
	(segment
		(start 95.096 193.696)
		(end 95.745 194.345)
		(width 0.201)
		(layer "F.Cu")
		(net 658)
	)
	(segment
		(start 95.745 194.345)
		(end 96.3 194.345)
		(width 0.201)
		(layer "F.Cu")
		(net 658)
	)
	(segment
		(start 97.37 193.8)
		(end 97.9 194.33)
		(width 0.201)
		(layer "F.Cu")
		(net 659)
	)
	(segment
		(start 95.499 193.399)
		(end 95.9 193.8)
		(width 0.201)
		(layer "F.Cu")
		(net 659)
	)
	(segment
		(start 95.499 192.998)
		(end 95.499 193.399)
		(width 0.201)
		(layer "F.Cu")
		(net 659)
	)
	(segment
		(start 95.9 193.8)
		(end 97.37 193.8)
		(width 0.201)
		(layer "F.Cu")
		(net 659)
	)
	(segment
		(start 142.375501 186.301)
		(end 142.875001 186.8005)
		(width 0.256)
		(layer "F.Cu")
		(net 660)
	)
	(segment
		(start 88.665001 195.005001)
		(end 88.81 195.15)
		(width 0.16)
		(layer "F.Cu")
		(net 660)
	)
	(segment
		(start 85.135 195.35)
		(end 85.479999 195.005001)
		(width 0.16)
		(layer "F.Cu")
		(net 660)
	)
	(segment
		(start 85.479999 195.005001)
		(end 88.665001 195.005001)
		(width 0.16)
		(layer "F.Cu")
		(net 660)
	)
	(via
		(at 88.81 195.15)
		(size 0.45)
		(drill 0.1)
		(layers "F.Cu" "B.Cu")
		(net 660)
	)
	(via
		(at 142.875001 186.8005)
		(size 0.45)
		(drill 0.1)
		(layers "F.Cu" "B.Cu")
		(net 660)
	)
	(segment
		(start 143.500501 187.39922)
		(end 143.278595 187.177314)
		(width 0.1)
		(layer "In6.Cu")
		(net 660)
	)
	(segment
		(start 92.909422 194.975)
		(end 93.125 194.975)
		(width 0.1)
		(layer "In6.Cu")
		(net 660)
	)
	(segment
		(start 143.288369 189.447045)
		(end 143.323626 189.482302)
		(width 0.1)
		(layer "In6.Cu")
		(net 660)
	)
	(segment
		(start 143.500501 188.100501)
		(end 143.500501 187.39922)
		(width 0.1)
		(layer "In6.Cu")
		(net 660)
	)
	(segment
		(start 92.159422 195.634422)
		(end 92.375 195.634422)
		(width 0.1)
		(layer "In6.Cu")
		(net 660)
	)
	(segment
		(start 142.875003 187.0755)
		(end 142.875003 186.800502)
		(width 0.1)
		(layer "In6.Cu")
		(net 660)
	)
	(segment
		(start 136.083279 196.44)
		(end 143.076237 189.447045)
		(width 0.1)
		(layer "In6.Cu")
		(net 660)
	)
	(segment
		(start 91.767211 195.117211)
		(end 91.767211 195.242211)
		(width 0.1)
		(layer "In6.Cu")
		(net 660)
	)
	(segment
		(start 143.500501 188.750501)
		(end 143.500501 188.700501)
		(width 0.1)
		(layer "In6.Cu")
		(net 660)
	)
	(segment
		(start 143.500501 189.022778)
		(end 143.500501 188.750501)
		(width 0.1)
		(layer "In6.Cu")
		(net 660)
	)
	(segment
		(start 88.985 194.975)
		(end 91.625 194.975)
		(width 0.1)
		(layer "In6.Cu")
		(net 660)
	)
	(segment
		(start 143.535758 189.27017)
		(end 143.5005 189.234912)
		(width 0.1)
		(layer "In6.Cu")
		(net 660)
	)
	(segment
		(start 142.875003 186.800502)
		(end 142.875001 186.8005)
		(width 0.1)
		(layer "In6.Cu")
		(net 660)
	)
	(segment
		(start 88.81 195.15)
		(end 88.985 194.975)
		(width 0.1)
		(layer "In6.Cu")
		(net 660)
	)
	(segment
		(start 143.5005 189.234912)
		(end 143.500501 189.234912)
		(width 0.1)
		(layer "In6.Cu")
		(net 660)
	)
	(segment
		(start 96.013222 196.44)
		(end 136.083279 196.44)
		(width 0.1)
		(layer "In6.Cu")
		(net 660)
	)
	(segment
		(start 94.548222 194.975)
		(end 96.013222 196.44)
		(width 0.1)
		(layer "In6.Cu")
		(net 660)
	)
	(segment
		(start 93.125 194.975)
		(end 94.548222 194.975)
		(width 0.1)
		(layer "In6.Cu")
		(net 660)
	)
	(segment
		(start 142.976817 187.177314)
		(end 142.875003 187.0755)
		(width 0.1)
		(layer "In6.Cu")
		(net 660)
	)
	(segment
		(start 92.767211 195.242211)
		(end 92.767211 195.117211)
		(width 0.1)
		(layer "In6.Cu")
		(net 660)
	)
	(segment
		(start 143.278595 187.177314)
		(end 142.976817 187.177314)
		(width 0.1)
		(layer "In6.Cu")
		(net 660)
	)
	(arc
		(start 143.323626 189.482302)
		(mid 143.429692 189.526236)
		(end 143.535758 189.482302)
		(width 0.1)
		(layer "In6.Cu")
		(net 660)
	)
	(arc
		(start 143.500501 188.700501)
		(mid 143.544435 188.594435)
		(end 143.650501 188.550501)
		(width 0.1)
		(layer "In6.Cu")
		(net 660)
	)
	(arc
		(start 143.535758 189.482302)
		(mid 143.579692 189.376236)
		(end 143.535758 189.27017)
		(width 0.1)
		(layer "In6.Cu")
		(net 660)
	)
	(arc
		(start 91.625 194.975)
		(mid 91.725558 195.016653)
		(end 91.767211 195.117211)
		(width 0.1)
		(layer "In6.Cu")
		(net 660)
	)
	(arc
		(start 143.650501 188.250501)
		(mid 143.544435 188.206567)
		(end 143.500501 188.100501)
		(width 0.1)
		(layer "In6.Cu")
		(net 660)
	)
	(arc
		(start 143.650501 188.550501)
		(mid 143.756567 188.506567)
		(end 143.800501 188.400501)
		(width 0.1)
		(layer "In6.Cu")
		(net 660)
	)
	(arc
		(start 143.076237 189.447045)
		(mid 143.182303 189.403111)
		(end 143.288369 189.447045)
		(width 0.1)
		(layer "In6.Cu")
		(net 660)
	)
	(arc
		(start 143.800501 188.400501)
		(mid 143.756567 188.294435)
		(end 143.650501 188.250501)
		(width 0.1)
		(layer "In6.Cu")
		(net 660)
	)
	(arc
		(start 143.500501 189.234912)
		(mid 143.456566 189.128846)
		(end 143.500501 189.022778)
		(width 0.1)
		(layer "In6.Cu")
		(net 660)
	)
	(arc
		(start 91.767211 195.242211)
		(mid 91.882087 195.519546)
		(end 92.159422 195.634422)
		(width 0.1)
		(layer "In6.Cu")
		(net 660)
	)
	(arc
		(start 92.767211 195.117211)
		(mid 92.808864 195.016653)
		(end 92.909422 194.975)
		(width 0.1)
		(layer "In6.Cu")
		(net 660)
	)
	(arc
		(start 92.375 195.634422)
		(mid 92.652335 195.519546)
		(end 92.767211 195.242211)
		(width 0.1)
		(layer "In6.Cu")
		(net 660)
	)
	(segment
		(start 142.375501 187.301)
		(end 142.875001 187.8005)
		(width 0.256)
		(layer "F.Cu")
		(net 661)
	)
	(segment
		(start 88.665001 194.694999)
		(end 88.81 194.55)
		(width 0.16)
		(layer "F.Cu")
		(net 661)
	)
	(segment
		(start 85.135 194.35)
		(end 85.479999 194.694999)
		(width 0.16)
		(layer "F.Cu")
		(net 661)
	)
	(segment
		(start 85.479999 194.694999)
		(end 88.665001 194.694999)
		(width 0.16)
		(layer "F.Cu")
		(net 661)
	)
	(via
		(at 142.875001 187.8005)
		(size 0.45)
		(drill 0.1)
		(layers "F.Cu" "B.Cu")
		(net 661)
	)
	(via
		(at 88.81 194.55)
		(size 0.45)
		(drill 0.1)
		(layers "F.Cu" "B.Cu")
		(net 661)
	)
	(segment
		(start 92.017211 195.117211)
		(end 92.017211 195.242211)
		(width 0.1)
		(layer "In6.Cu")
		(net 661)
	)
	(segment
		(start 94.651778 194.725)
		(end 96.116778 196.19)
		(width 0.1)
		(layer "In6.Cu")
		(net 661)
	)
	(segment
		(start 88.81 194.55)
		(end 88.985 194.725)
		(width 0.1)
		(layer "In6.Cu")
		(net 661)
	)
	(segment
		(start 143.250501 187.502776)
		(end 143.175039 187.427314)
		(width 0.1)
		(layer "In6.Cu")
		(net 661)
	)
	(segment
		(start 96.116778 196.19)
		(end 135.979723 196.19)
		(width 0.1)
		(layer "In6.Cu")
		(net 661)
	)
	(segment
		(start 142.972189 187.427314)
		(end 142.875001 187.524502)
		(width 0.1)
		(layer "In6.Cu")
		(net 661)
	)
	(segment
		(start 92.517211 195.242211)
		(end 92.517211 195.117211)
		(width 0.1)
		(layer "In6.Cu")
		(net 661)
	)
	(segment
		(start 135.979723 196.19)
		(end 143.250501 188.919222)
		(width 0.1)
		(layer "In6.Cu")
		(net 661)
	)
	(segment
		(start 142.875001 187.524502)
		(end 142.875001 187.8005)
		(width 0.1)
		(layer "In6.Cu")
		(net 661)
	)
	(segment
		(start 143.250501 188.919222)
		(end 143.250501 187.502776)
		(width 0.1)
		(layer "In6.Cu")
		(net 661)
	)
	(segment
		(start 92.159422 195.384422)
		(end 92.375 195.384422)
		(width 0.1)
		(layer "In6.Cu")
		(net 661)
	)
	(segment
		(start 92.909422 194.725)
		(end 93.125 194.725)
		(width 0.1)
		(layer "In6.Cu")
		(net 661)
	)
	(segment
		(start 93.125 194.725)
		(end 94.651778 194.725)
		(width 0.1)
		(layer "In6.Cu")
		(net 661)
	)
	(segment
		(start 88.985 194.725)
		(end 91.625 194.725)
		(width 0.1)
		(layer "In6.Cu")
		(net 661)
	)
	(segment
		(start 143.175039 187.427314)
		(end 142.972189 187.427314)
		(width 0.1)
		(layer "In6.Cu")
		(net 661)
	)
	(arc
		(start 92.517211 195.117211)
		(mid 92.632087 194.839876)
		(end 92.909422 194.725)
		(width 0.1)
		(layer "In6.Cu")
		(net 661)
	)
	(arc
		(start 92.375 195.384422)
		(mid 92.475558 195.342769)
		(end 92.517211 195.242211)
		(width 0.1)
		(layer "In6.Cu")
		(net 661)
	)
	(arc
		(start 92.017211 195.242211)
		(mid 92.058864 195.342769)
		(end 92.159422 195.384422)
		(width 0.1)
		(layer "In6.Cu")
		(net 661)
	)
	(arc
		(start 91.625 194.725)
		(mid 91.902335 194.839876)
		(end 92.017211 195.117211)
		(width 0.1)
		(layer "In6.Cu")
		(net 661)
	)
	(segment
		(start 87.385 193.85)
		(end 87.729999 193.505001)
		(width 0.16)
		(layer "F.Cu")
		(net 662)
	)
	(segment
		(start 87.729999 193.505001)
		(end 89.565125 193.505001)
		(width 0.16)
		(layer "F.Cu")
		(net 662)
	)
	(segment
		(start 139.375501 187.301)
		(end 138.876002 187.8005)
		(width 0.256)
		(layer "F.Cu")
		(net 662)
	)
	(segment
		(start 89.565125 193.505001)
		(end 89.782123 193.721999)
		(width 0.16)
		(layer "F.Cu")
		(net 662)
	)
	(via
		(at 138.876002 187.8005)
		(size 0.45)
		(drill 0.1)
		(layers "F.Cu" "B.Cu")
		(net 662)
	)
	(via
		(at 89.782123 193.721999)
		(size 0.45)
		(drill 0.1)
		(layers "F.Cu" "B.Cu")
		(net 662)
	)
	(segment
		(start 140.37678 187.175501)
		(end 140.700501 187.499222)
		(width 0.1)
		(layer "In6.Cu")
		(net 662)
	)
	(segment
		(start 139.474222 187.175501)
		(end 140.37678 187.175501)
		(width 0.1)
		(layer "In6.Cu")
		(net 662)
	)
	(segment
		(start 140.700501 187.499222)
		(end 140.700501 189.502778)
		(width 0.1)
		(layer "In6.Cu")
		(net 662)
	)
	(segment
		(start 139.252815 187.396908)
		(end 139.474222 187.175501)
		(width 0.1)
		(layer "In6.Cu")
		(net 662)
	)
	(segment
		(start 89.994561 193.509561)
		(end 89.782123 193.721999)
		(width 0.1)
		(layer "In6.Cu")
		(net 662)
	)
	(segment
		(start 139.252815 187.698686)
		(end 139.252815 187.396908)
		(width 0.1)
		(layer "In6.Cu")
		(net 662)
	)
	(segment
		(start 97.648222 194.825)
		(end 96.332783 193.509561)
		(width 0.1)
		(layer "In6.Cu")
		(net 662)
	)
	(segment
		(start 135.378279 194.825)
		(end 97.648222 194.825)
		(width 0.1)
		(layer "In6.Cu")
		(net 662)
	)
	(segment
		(start 138.876002 187.8005)
		(end 139.151001 187.8005)
		(width 0.1)
		(layer "In6.Cu")
		(net 662)
	)
	(segment
		(start 96.332783 193.509561)
		(end 89.994561 193.509561)
		(width 0.1)
		(layer "In6.Cu")
		(net 662)
	)
	(segment
		(start 140.700501 189.502778)
		(end 135.378279 194.825)
		(width 0.1)
		(layer "In6.Cu")
		(net 662)
	)
	(segment
		(start 139.151001 187.8005)
		(end 139.252815 187.698686)
		(width 0.1)
		(layer "In6.Cu")
		(net 662)
	)
	(segment
		(start 87.729999 193.194999)
		(end 89.640001 193.194999)
		(width 0.16)
		(layer "F.Cu")
		(net 663)
	)
	(segment
		(start 140.375501 187.301)
		(end 139.876001 187.800502)
		(width 0.256)
		(layer "F.Cu")
		(net 663)
	)
	(segment
		(start 89.640001 193.194999)
		(end 89.785 193.05)
		(width 0.16)
		(layer "F.Cu")
		(net 663)
	)
	(segment
		(start 87.385 192.85)
		(end 87.729999 193.194999)
		(width 0.16)
		(layer "F.Cu")
		(net 663)
	)
	(via
		(at 139.876001 187.800502)
		(size 0.45)
		(drill 0.1)
		(layers "F.Cu" "B.Cu")
		(net 663)
	)
	(via
		(at 89.785 193.05)
		(size 0.45)
		(drill 0.1)
		(layers "F.Cu" "B.Cu")
		(net 663)
	)
	(segment
		(start 140.250501 189.049499)
		(end 140.300501 189.049499)
		(width 0.1)
		(layer "In6.Cu")
		(net 663)
	)
	(segment
		(start 139.468792 190.15372)
		(end 139.47633 190.161258)
		(width 0.1)
		(layer "In6.Cu")
		(net 663)
	)
	(segment
		(start 140.300501 188.749499)
		(end 140.250501 188.749499)
		(width 0.1)
		(layer "In6.Cu")
		(net 663)
	)
	(segment
		(start 140.112728 189.524862)
		(end 140.105189 189.517323)
		(width 0.1)
		(layer "In6.Cu")
		(net 663)
	)
	(segment
		(start 140.300501 188.149499)
		(end 140.250501 188.149499)
		(width 0.1)
		(layer "In6.Cu")
		(net 663)
	)
	(segment
		(start 140.450501 187.602778)
		(end 140.450501 187.999499)
		(width 0.1)
		(layer "In6.Cu")
		(net 663)
	)
	(segment
		(start 140.450501 189.199499)
		(end 140.450501 189.249499)
		(width 0.1)
		(layer "In6.Cu")
		(net 663)
	)
	(segment
		(start 135.274723 194.575)
		(end 97.751778 194.575)
		(width 0.1)
		(layer "In6.Cu")
		(net 663)
	)
	(segment
		(start 139.476331 190.373391)
		(end 135.274723 194.575)
		(width 0.1)
		(layer "In6.Cu")
		(net 663)
	)
	(segment
		(start 139.900595 189.949125)
		(end 139.900596 189.949126)
		(width 0.1)
		(layer "In6.Cu")
		(net 663)
	)
	(segment
		(start 139.688463 189.949127)
		(end 139.680924 189.941588)
		(width 0.1)
		(layer "In6.Cu")
		(net 663)
	)
	(segment
		(start 139.47633 190.37339)
		(end 139.476331 190.373391)
		(width 0.1)
		(layer "In6.Cu")
		(net 663)
	)
	(segment
		(start 140.112727 189.524862)
		(end 140.112728 189.524862)
		(width 0.1)
		(layer "In6.Cu")
		(net 663)
	)
	(segment
		(start 139.600003 187.800502)
		(end 139.502815 187.703314)
		(width 0.1)
		(layer "In6.Cu")
		(net 663)
	)
	(segment
		(start 89.994561 193.259561)
		(end 89.785 193.05)
		(width 0.1)
		(layer "In6.Cu")
		(net 663)
	)
	(segment
		(start 139.876001 187.800502)
		(end 139.600003 187.800502)
		(width 0.1)
		(layer "In6.Cu")
		(net 663)
	)
	(segment
		(start 140.273205 187.425482)
		(end 140.450501 187.602778)
		(width 0.1)
		(layer "In6.Cu")
		(net 663)
	)
	(segment
		(start 139.502815 187.703314)
		(end 139.502815 187.500464)
		(width 0.1)
		(layer "In6.Cu")
		(net 663)
	)
	(segment
		(start 140.450501 189.249499)
		(end 140.450501 189.399222)
		(width 0.1)
		(layer "In6.Cu")
		(net 663)
	)
	(segment
		(start 97.751778 194.575)
		(end 96.436339 193.259561)
		(width 0.1)
		(layer "In6.Cu")
		(net 663)
	)
	(segment
		(start 139.577797 187.425482)
		(end 140.273205 187.425482)
		(width 0.1)
		(layer "In6.Cu")
		(net 663)
	)
	(segment
		(start 139.900596 189.949126)
		(end 139.900596 189.949127)
		(width 0.1)
		(layer "In6.Cu")
		(net 663)
	)
	(segment
		(start 139.688462 189.949127)
		(end 139.688463 189.949127)
		(width 0.1)
		(layer "In6.Cu")
		(net 663)
	)
	(segment
		(start 140.250501 188.449499)
		(end 140.300501 188.449499)
		(width 0.1)
		(layer "In6.Cu")
		(net 663)
	)
	(segment
		(start 96.436339 193.259561)
		(end 89.994561 193.259561)
		(width 0.1)
		(layer "In6.Cu")
		(net 663)
	)
	(segment
		(start 139.502815 187.500464)
		(end 139.577797 187.425482)
		(width 0.1)
		(layer "In6.Cu")
		(net 663)
	)
	(segment
		(start 139.893057 189.729455)
		(end 139.900595 189.736993)
		(width 0.1)
		(layer "In6.Cu")
		(net 663)
	)
	(segment
		(start 140.450501 189.399222)
		(end 140.324861 189.524862)
		(width 0.1)
		(layer "In6.Cu")
		(net 663)
	)
	(arc
		(start 139.900596 189.949127)
		(mid 139.794529 189.993061)
		(end 139.688462 189.949127)
		(width 0.1)
		(layer "In6.Cu")
		(net 663)
	)
	(arc
		(start 140.100501 188.899499)
		(mid 140.144435 189.005565)
		(end 140.250501 189.049499)
		(width 0.1)
		(layer "In6.Cu")
		(net 663)
	)
	(arc
		(start 140.100501 188.299499)
		(mid 140.144435 188.405565)
		(end 140.250501 188.449499)
		(width 0.1)
		(layer "In6.Cu")
		(net 663)
	)
	(arc
		(start 140.324861 189.524862)
		(mid 140.218794 189.568796)
		(end 140.112727 189.524862)
		(width 0.1)
		(layer "In6.Cu")
		(net 663)
	)
	(arc
		(start 140.450501 188.599499)
		(mid 140.406567 188.705565)
		(end 140.300501 188.749499)
		(width 0.1)
		(layer "In6.Cu")
		(net 663)
	)
	(arc
		(start 139.47633 190.161258)
		(mid 139.520264 190.267324)
		(end 139.47633 190.37339)
		(width 0.1)
		(layer "In6.Cu")
		(net 663)
	)
	(arc
		(start 140.250501 188.149499)
		(mid 140.144435 188.193433)
		(end 140.100501 188.299499)
		(width 0.1)
		(layer "In6.Cu")
		(net 663)
	)
	(arc
		(start 139.893057 189.517323)
		(mid 139.849123 189.623389)
		(end 139.893057 189.729455)
		(width 0.1)
		(layer "In6.Cu")
		(net 663)
	)
	(arc
		(start 140.300501 189.049499)
		(mid 140.406567 189.093433)
		(end 140.450501 189.199499)
		(width 0.1)
		(layer "In6.Cu")
		(net 663)
	)
	(arc
		(start 139.680924 189.941588)
		(mid 139.574858 189.897654)
		(end 139.468792 189.941588)
		(width 0.1)
		(layer "In6.Cu")
		(net 663)
	)
	(arc
		(start 140.450501 187.999499)
		(mid 140.406567 188.105565)
		(end 140.300501 188.149499)
		(width 0.1)
		(layer "In6.Cu")
		(net 663)
	)
	(arc
		(start 140.105189 189.517323)
		(mid 139.999123 189.473389)
		(end 139.893057 189.517323)
		(width 0.1)
		(layer "In6.Cu")
		(net 663)
	)
	(arc
		(start 140.300501 188.449499)
		(mid 140.406567 188.493433)
		(end 140.450501 188.599499)
		(width 0.1)
		(layer "In6.Cu")
		(net 663)
	)
	(arc
		(start 140.250501 188.749499)
		(mid 140.144435 188.793433)
		(end 140.100501 188.899499)
		(width 0.1)
		(layer "In6.Cu")
		(net 663)
	)
	(arc
		(start 139.468792 189.941588)
		(mid 139.424858 190.047654)
		(end 139.468792 190.15372)
		(width 0.1)
		(layer "In6.Cu")
		(net 663)
	)
	(arc
		(start 139.900595 189.736993)
		(mid 139.944529 189.843059)
		(end 139.900595 189.949125)
		(width 0.1)
		(layer "In6.Cu")
		(net 663)
	)
	(segment
		(start 88.745001 191.906001)
		(end 88.89 192.051)
		(width 0.16)
		(layer "F.Cu")
		(net 664)
	)
	(segment
		(start 85.135 192.252)
		(end 85.480999 191.906001)
		(width 0.16)
		(layer "F.Cu")
		(net 664)
	)
	(segment
		(start 138.376501 186.301)
		(end 137.877001 186.8005)
		(width 0.256)
		(layer "F.Cu")
		(net 664)
	)
	(segment
		(start 85.480999 191.906001)
		(end 88.745001 191.906001)
		(width 0.16)
		(layer "F.Cu")
		(net 664)
	)
	(via
		(at 137.877001 186.8005)
		(size 0.45)
		(drill 0.1)
		(layers "F.Cu" "B.Cu")
		(net 664)
	)
	(via
		(at 88.89 192.051)
		(size 0.45)
		(drill 0.1)
		(layers "F.Cu" "B.Cu")
		(net 664)
	)
	(segment
		(start 103.082 193.442)
		(end 103.422 193.442)
		(width 0.1)
		(layer "In6.Cu")
		(net 664)
	)
	(segment
		(start 104.922 193.442)
		(end 105.047256 193.442)
		(width 0.1)
		(layer "In6.Cu")
		(net 664)
	)
	(segment
		(start 99.699222 191.876)
		(end 101.265222 193.442)
		(width 0.1)
		(layer "In6.Cu")
		(net 664)
	)
	(segment
		(start 105.047256 193.442)
		(end 105.298 193.442)
		(width 0.1)
		(layer "In6.Cu")
		(net 664)
	)
	(segment
		(start 138.500501 187.39722)
		(end 138.280595 187.177314)
		(width 0.1)
		(layer "In6.Cu")
		(net 664)
	)
	(segment
		(start 137.877003 186.800502)
		(end 137.877001 186.8005)
		(width 0.1)
		(layer "In6.Cu")
		(net 664)
	)
	(segment
		(start 106.870188 193.442)
		(end 134.706279 193.442)
		(width 0.1)
		(layer "In6.Cu")
		(net 664)
	)
	(segment
		(start 138.280595 187.177314)
		(end 137.978817 187.177314)
		(width 0.1)
		(layer "In6.Cu")
		(net 664)
	)
	(segment
		(start 102.607 191.892)
		(end 102.607 192.967)
		(width 0.1)
		(layer "In6.Cu")
		(net 664)
	)
	(segment
		(start 138.500501 189.647778)
		(end 138.500501 187.39722)
		(width 0.1)
		(layer "In6.Cu")
		(net 664)
	)
	(segment
		(start 137.978817 187.177314)
		(end 137.877003 187.0755)
		(width 0.1)
		(layer "In6.Cu")
		(net 664)
	)
	(segment
		(start 103.922 192.942)
		(end 103.922 191.917)
		(width 0.1)
		(layer "In6.Cu")
		(net 664)
	)
	(segment
		(start 137.877003 187.0755)
		(end 137.877003 186.800502)
		(width 0.1)
		(layer "In6.Cu")
		(net 664)
	)
	(segment
		(start 105.798 192.942)
		(end 105.798 191.839938)
		(width 0.1)
		(layer "In6.Cu")
		(net 664)
	)
	(segment
		(start 88.89 192.051)
		(end 89.065 191.876)
		(width 0.1)
		(layer "In6.Cu")
		(net 664)
	)
	(segment
		(start 104.422 191.917)
		(end 104.422 192.942)
		(width 0.1)
		(layer "In6.Cu")
		(net 664)
	)
	(segment
		(start 101.265222 193.442)
		(end 101.682 193.442)
		(width 0.1)
		(layer "In6.Cu")
		(net 664)
	)
	(segment
		(start 106.798 193.442)
		(end 106.870188 193.442)
		(width 0.1)
		(layer "In6.Cu")
		(net 664)
	)
	(segment
		(start 106.298 191.839938)
		(end 106.298 192.942)
		(width 0.1)
		(layer "In6.Cu")
		(net 664)
	)
	(segment
		(start 134.706279 193.442)
		(end 138.500501 189.647778)
		(width 0.1)
		(layer "In6.Cu")
		(net 664)
	)
	(segment
		(start 102.157 192.967)
		(end 102.157 191.892)
		(width 0.1)
		(layer "In6.Cu")
		(net 664)
	)
	(segment
		(start 89.065 191.876)
		(end 99.699222 191.876)
		(width 0.1)
		(layer "In6.Cu")
		(net 664)
	)
	(arc
		(start 102.157 191.892)
		(mid 102.222901 191.732901)
		(end 102.382 191.667)
		(width 0.1)
		(layer "In6.Cu")
		(net 664)
	)
	(arc
		(start 106.298 192.942)
		(mid 106.444447 193.295553)
		(end 106.798 193.442)
		(width 0.1)
		(layer "In6.Cu")
		(net 664)
	)
	(arc
		(start 104.422 192.942)
		(mid 104.568447 193.295553)
		(end 104.922 193.442)
		(width 0.1)
		(layer "In6.Cu")
		(net 664)
	)
	(arc
		(start 103.422 193.442)
		(mid 103.775553 193.295553)
		(end 103.922 192.942)
		(width 0.1)
		(layer "In6.Cu")
		(net 664)
	)
	(arc
		(start 101.682 193.442)
		(mid 102.017876 193.302876)
		(end 102.157 192.967)
		(width 0.1)
		(layer "In6.Cu")
		(net 664)
	)
	(arc
		(start 103.922 191.917)
		(mid 103.995223 191.740223)
		(end 104.172 191.667)
		(width 0.1)
		(layer "In6.Cu")
		(net 664)
	)
	(arc
		(start 104.172 191.667)
		(mid 104.348777 191.740223)
		(end 104.422 191.917)
		(width 0.1)
		(layer "In6.Cu")
		(net 664)
	)
	(arc
		(start 102.382 191.667)
		(mid 102.541099 191.732901)
		(end 102.607 191.892)
		(width 0.1)
		(layer "In6.Cu")
		(net 664)
	)
	(arc
		(start 105.798 191.839938)
		(mid 105.871223 191.663161)
		(end 106.048 191.589938)
		(width 0.1)
		(layer "In6.Cu")
		(net 664)
	)
	(arc
		(start 102.607 192.967)
		(mid 102.746124 193.302876)
		(end 103.082 193.442)
		(width 0.1)
		(layer "In6.Cu")
		(net 664)
	)
	(arc
		(start 105.298 193.442)
		(mid 105.651553 193.295553)
		(end 105.798 192.942)
		(width 0.1)
		(layer "In6.Cu")
		(net 664)
	)
	(arc
		(start 106.048 191.589938)
		(mid 106.224777 191.663161)
		(end 106.298 191.839938)
		(width 0.1)
		(layer "In6.Cu")
		(net 664)
	)
	(segment
		(start 85.480999 191.595999)
		(end 88.745001 191.595999)
		(width 0.16)
		(layer "F.Cu")
		(net 665)
	)
	(segment
		(start 138.376501 187.301)
		(end 137.877001 187.8005)
		(width 0.256)
		(layer "F.Cu")
		(net 665)
	)
	(segment
		(start 88.745001 191.595999)
		(end 88.89 191.451)
		(width 0.16)
		(layer "F.Cu")
		(net 665)
	)
	(segment
		(start 85.135 191.25)
		(end 85.480999 191.595999)
		(width 0.16)
		(layer "F.Cu")
		(net 665)
	)
	(via
		(at 88.89 191.451)
		(size 0.45)
		(drill 0.1)
		(layers "F.Cu" "B.Cu")
		(net 665)
	)
	(via
		(at 137.877001 187.8005)
		(size 0.45)
		(drill 0.1)
		(layers "F.Cu" "B.Cu")
		(net 665)
	)
	(segment
		(start 104.672 191.917)
		(end 104.672 192.942)
		(width 0.1)
		(layer "In6.Cu")
		(net 665)
	)
	(segment
		(start 89.065 191.626)
		(end 99.802778 191.626)
		(width 0.1)
		(layer "In6.Cu")
		(net 665)
	)
	(segment
		(start 105.047256 193.192)
		(end 105.298 193.192)
		(width 0.1)
		(layer "In6.Cu")
		(net 665)
	)
	(segment
		(start 138.062023 188.375501)
		(end 138.125501 188.375501)
		(width 0.1)
		(layer "In6.Cu")
		(net 665)
	)
	(segment
		(start 137.974189 187.427314)
		(end 137.877001 187.524502)
		(width 0.1)
		(layer "In6.Cu")
		(net 665)
	)
	(segment
		(start 102.857 191.892)
		(end 102.857 192.967)
		(width 0.1)
		(layer "In6.Cu")
		(net 665)
	)
	(segment
		(start 106.548 191.839938)
		(end 106.548 192.942)
		(width 0.1)
		(layer "In6.Cu")
		(net 665)
	)
	(segment
		(start 138.250501 189.544222)
		(end 138.250501 188.750501)
		(width 0.1)
		(layer "In6.Cu")
		(net 665)
	)
	(segment
		(start 99.802778 191.626)
		(end 101.368778 193.192)
		(width 0.1)
		(layer "In6.Cu")
		(net 665)
	)
	(segment
		(start 103.672 192.942)
		(end 103.672 191.917)
		(width 0.1)
		(layer "In6.Cu")
		(net 665)
	)
	(segment
		(start 106.870188 193.192)
		(end 134.602723 193.192)
		(width 0.1)
		(layer "In6.Cu")
		(net 665)
	)
	(segment
		(start 134.602723 193.192)
		(end 138.250501 189.544222)
		(width 0.1)
		(layer "In6.Cu")
		(net 665)
	)
	(segment
		(start 101.368778 193.192)
		(end 101.682 193.192)
		(width 0.1)
		(layer "In6.Cu")
		(net 665)
	)
	(segment
		(start 105.548 192.942)
		(end 105.548 191.839938)
		(width 0.1)
		(layer "In6.Cu")
		(net 665)
	)
	(segment
		(start 138.177039 187.427314)
		(end 137.974189 187.427314)
		(width 0.1)
		(layer "In6.Cu")
		(net 665)
	)
	(segment
		(start 106.798 193.192)
		(end 106.870188 193.192)
		(width 0.1)
		(layer "In6.Cu")
		(net 665)
	)
	(segment
		(start 138.250501 188.250501)
		(end 138.250501 187.500776)
		(width 0.1)
		(layer "In6.Cu")
		(net 665)
	)
	(segment
		(start 103.082 193.192)
		(end 103.422 193.192)
		(width 0.1)
		(layer "In6.Cu")
		(net 665)
	)
	(segment
		(start 104.922 193.192)
		(end 105.047256 193.192)
		(width 0.1)
		(layer "In6.Cu")
		(net 665)
	)
	(segment
		(start 138.250501 187.500776)
		(end 138.177039 187.427314)
		(width 0.1)
		(layer "In6.Cu")
		(net 665)
	)
	(segment
		(start 101.907 192.967)
		(end 101.907 191.892)
		(width 0.1)
		(layer "In6.Cu")
		(net 665)
	)
	(segment
		(start 138.125501 188.625501)
		(end 138.062023 188.625501)
		(width 0.1)
		(layer "In6.Cu")
		(net 665)
	)
	(segment
		(start 88.89 191.451)
		(end 89.065 191.626)
		(width 0.1)
		(layer "In6.Cu")
		(net 665)
	)
	(segment
		(start 137.877001 187.524502)
		(end 137.877001 187.8005)
		(width 0.1)
		(layer "In6.Cu")
		(net 665)
	)
	(arc
		(start 137.937023 188.500501)
		(mid 137.973635 188.412113)
		(end 138.062023 188.375501)
		(width 0.1)
		(layer "In6.Cu")
		(net 665)
	)
	(arc
		(start 105.298 193.192)
		(mid 105.474777 193.118777)
		(end 105.548 192.942)
		(width 0.1)
		(layer "In6.Cu")
		(net 665)
	)
	(arc
		(start 102.382 191.417)
		(mid 102.717876 191.556124)
		(end 102.857 191.892)
		(width 0.1)
		(layer "In6.Cu")
		(net 665)
	)
	(arc
		(start 102.857 192.967)
		(mid 102.922901 193.126099)
		(end 103.082 193.192)
		(width 0.1)
		(layer "In6.Cu")
		(net 665)
	)
	(arc
		(start 138.250501 188.750501)
		(mid 138.213889 188.662113)
		(end 138.125501 188.625501)
		(width 0.1)
		(layer "In6.Cu")
		(net 665)
	)
	(arc
		(start 104.172 191.417)
		(mid 104.525553 191.563447)
		(end 104.672 191.917)
		(width 0.1)
		(layer "In6.Cu")
		(net 665)
	)
	(arc
		(start 104.672 192.942)
		(mid 104.745223 193.118777)
		(end 104.922 193.192)
		(width 0.1)
		(layer "In6.Cu")
		(net 665)
	)
	(arc
		(start 106.548 192.942)
		(mid 106.621223 193.118777)
		(end 106.798 193.192)
		(width 0.1)
		(layer "In6.Cu")
		(net 665)
	)
	(arc
		(start 103.672 191.917)
		(mid 103.818447 191.563447)
		(end 104.172 191.417)
		(width 0.1)
		(layer "In6.Cu")
		(net 665)
	)
	(arc
		(start 138.125501 188.375501)
		(mid 138.213889 188.338889)
		(end 138.250501 188.250501)
		(width 0.1)
		(layer "In6.Cu")
		(net 665)
	)
	(arc
		(start 103.422 193.192)
		(mid 103.598777 193.118777)
		(end 103.672 192.942)
		(width 0.1)
		(layer "In6.Cu")
		(net 665)
	)
	(arc
		(start 101.907 191.892)
		(mid 102.046124 191.556124)
		(end 102.382 191.417)
		(width 0.1)
		(layer "In6.Cu")
		(net 665)
	)
	(arc
		(start 138.062023 188.625501)
		(mid 137.973635 188.588889)
		(end 137.937023 188.500501)
		(width 0.1)
		(layer "In6.Cu")
		(net 665)
	)
	(arc
		(start 106.048 191.339938)
		(mid 106.401553 191.486385)
		(end 106.548 191.839938)
		(width 0.1)
		(layer "In6.Cu")
		(net 665)
	)
	(arc
		(start 101.682 193.192)
		(mid 101.841099 193.126099)
		(end 101.907 192.967)
		(width 0.1)
		(layer "In6.Cu")
		(net 665)
	)
	(arc
		(start 105.548 191.839938)
		(mid 105.694447 191.486385)
		(end 106.048 191.339938)
		(width 0.1)
		(layer "In6.Cu")
		(net 665)
	)
	(segment
		(start 87.697876 190.434002)
		(end 89.717878 190.434002)
		(width 0.16)
		(layer "F.Cu")
		(net 666)
	)
	(segment
		(start 87.352877 190.779001)
		(end 87.697876 190.434002)
		(width 0.16)
		(layer "F.Cu")
		(net 666)
	)
	(segment
		(start 137.376501 186.301)
		(end 136.877001 186.8005)
		(width 0.256)
		(layer "F.Cu")
		(net 666)
	)
	(segment
		(start 89.717878 190.434002)
		(end 89.862877 190.579001)
		(width 0.16)
		(layer "F.Cu")
		(net 666)
	)
	(via
		(at 136.877001 186.8005)
		(size 0.45)
		(drill 0.1)
		(layers "F.Cu" "B.Cu")
		(net 666)
	)
	(via
		(at 89.862877 190.579001)
		(size 0.45)
		(drill 0.1)
		(layers "F.Cu" "B.Cu")
		(net 666)
	)
	(segment
		(start 137.500501 187.39722)
		(end 137.280595 187.177314)
		(width 0.1)
		(layer "In6.Cu")
		(net 666)
	)
	(segment
		(start 137.500501 188.719778)
		(end 137.500501 187.39722)
		(width 0.1)
		(layer "In6.Cu")
		(net 666)
	)
	(segment
		(start 90.037877 190.404001)
		(end 107.274001 190.404001)
		(width 0.1)
		(layer "In6.Cu")
		(net 666)
	)
	(segment
		(start 112.344001 190.404001)
		(end 112.827223 190.404001)
		(width 0.1)
		(layer "In6.Cu")
		(net 666)
	)
	(segment
		(start 111.094001 190.654001)
		(end 111.094001 192.106304)
		(width 0.1)
		(layer "In6.Cu")
		(net 666)
	)
	(segment
		(start 108.774001 190.404001)
		(end 109.014001 190.404001)
		(width 0.1)
		(layer "In6.Cu")
		(net 666)
	)
	(segment
		(start 114.364222 191.941)
		(end 134.279279 191.941)
		(width 0.1)
		(layer "In6.Cu")
		(net 666)
	)
	(segment
		(start 108.524001 192.129001)
		(end 108.524001 190.654001)
		(width 0.1)
		(layer "In6.Cu")
		(net 666)
	)
	(segment
		(start 107.524001 190.654001)
		(end 107.524001 192.129001)
		(width 0.1)
		(layer "In6.Cu")
		(net 666)
	)
	(segment
		(start 137.280595 187.177314)
		(end 136.978817 187.177314)
		(width 0.1)
		(layer "In6.Cu")
		(net 666)
	)
	(segment
		(start 134.279279 191.941)
		(end 137.500501 188.719778)
		(width 0.1)
		(layer "In6.Cu")
		(net 666)
	)
	(segment
		(start 112.094001 192.106304)
		(end 112.094001 190.654001)
		(width 0.1)
		(layer "In6.Cu")
		(net 666)
	)
	(segment
		(start 136.877003 186.800502)
		(end 136.877001 186.8005)
		(width 0.1)
		(layer "In6.Cu")
		(net 666)
	)
	(segment
		(start 89.862877 190.579001)
		(end 90.037877 190.404001)
		(width 0.1)
		(layer "In6.Cu")
		(net 666)
	)
	(segment
		(start 136.877003 187.0755)
		(end 136.877003 186.800502)
		(width 0.1)
		(layer "In6.Cu")
		(net 666)
	)
	(segment
		(start 136.978817 187.177314)
		(end 136.877003 187.0755)
		(width 0.1)
		(layer "In6.Cu")
		(net 666)
	)
	(segment
		(start 110.264001 192.079001)
		(end 110.264001 190.654001)
		(width 0.1)
		(layer "In6.Cu")
		(net 666)
	)
	(segment
		(start 110.514001 190.404001)
		(end 110.844001 190.404001)
		(width 0.1)
		(layer "In6.Cu")
		(net 666)
	)
	(segment
		(start 112.827223 190.404001)
		(end 114.364222 191.941)
		(width 0.1)
		(layer "In6.Cu")
		(net 666)
	)
	(segment
		(start 109.264001 190.654001)
		(end 109.264001 192.079001)
		(width 0.1)
		(layer "In6.Cu")
		(net 666)
	)
	(arc
		(start 107.274001 190.404001)
		(mid 107.450778 190.477224)
		(end 107.524001 190.654001)
		(width 0.1)
		(layer "In6.Cu")
		(net 666)
	)
	(arc
		(start 109.014001 190.404001)
		(mid 109.190778 190.477224)
		(end 109.264001 190.654001)
		(width 0.1)
		(layer "In6.Cu")
		(net 666)
	)
	(arc
		(start 112.094001 190.654001)
		(mid 112.167224 190.477224)
		(end 112.344001 190.404001)
		(width 0.1)
		(layer "In6.Cu")
		(net 666)
	)
	(arc
		(start 109.764001 192.579001)
		(mid 110.117554 192.432554)
		(end 110.264001 192.079001)
		(width 0.1)
		(layer "In6.Cu")
		(net 666)
	)
	(arc
		(start 108.024001 192.629001)
		(mid 108.377554 192.482554)
		(end 108.524001 192.129001)
		(width 0.1)
		(layer "In6.Cu")
		(net 666)
	)
	(arc
		(start 111.594001 192.606304)
		(mid 111.947554 192.459857)
		(end 112.094001 192.106304)
		(width 0.1)
		(layer "In6.Cu")
		(net 666)
	)
	(arc
		(start 108.524001 190.654001)
		(mid 108.597224 190.477224)
		(end 108.774001 190.404001)
		(width 0.1)
		(layer "In6.Cu")
		(net 666)
	)
	(arc
		(start 111.094001 192.106304)
		(mid 111.240448 192.459857)
		(end 111.594001 192.606304)
		(width 0.1)
		(layer "In6.Cu")
		(net 666)
	)
	(arc
		(start 110.264001 190.654001)
		(mid 110.337224 190.477224)
		(end 110.514001 190.404001)
		(width 0.1)
		(layer "In6.Cu")
		(net 666)
	)
	(arc
		(start 110.844001 190.404001)
		(mid 111.020778 190.477224)
		(end 111.094001 190.654001)
		(width 0.1)
		(layer "In6.Cu")
		(net 666)
	)
	(arc
		(start 107.524001 192.129001)
		(mid 107.670448 192.482554)
		(end 108.024001 192.629001)
		(width 0.1)
		(layer "In6.Cu")
		(net 666)
	)
	(arc
		(start 109.264001 192.079001)
		(mid 109.410448 192.432554)
		(end 109.764001 192.579001)
		(width 0.1)
		(layer "In6.Cu")
		(net 666)
	)
	(segment
		(start 137.376501 187.301)
		(end 136.877001 187.8005)
		(width 0.256)
		(layer "F.Cu")
		(net 667)
	)
	(segment
		(start 89.717878 190.124)
		(end 89.862877 189.979001)
		(width 0.16)
		(layer "F.Cu")
		(net 667)
	)
	(segment
		(start 87.697876 190.124)
		(end 89.717878 190.124)
		(width 0.16)
		(layer "F.Cu")
		(net 667)
	)
	(segment
		(start 87.352877 189.779001)
		(end 87.697876 190.124)
		(width 0.16)
		(layer "F.Cu")
		(net 667)
	)
	(via
		(at 136.877001 187.8005)
		(size 0.45)
		(drill 0.1)
		(layers "F.Cu" "B.Cu")
		(net 667)
	)
	(via
		(at 89.862877 189.979001)
		(size 0.45)
		(drill 0.1)
		(layers "F.Cu" "B.Cu")
		(net 667)
	)
	(segment
		(start 114.467778 191.691)
		(end 134.175723 191.691)
		(width 0.1)
		(layer "In6.Cu")
		(net 667)
	)
	(segment
		(start 136.882651 188.767349)
		(end 136.922348 188.727652)
		(width 0.1)
		(layer "In6.Cu")
		(net 667)
	)
	(segment
		(start 89.862877 189.979001)
		(end 90.037877 190.154001)
		(width 0.1)
		(layer "In6.Cu")
		(net 667)
	)
	(segment
		(start 90.037877 190.154001)
		(end 107.274001 190.154001)
		(width 0.1)
		(layer "In6.Cu")
		(net 667)
	)
	(segment
		(start 136.519289 189.150711)
		(end 136.557348 189.112652)
		(width 0.1)
		(layer "In6.Cu")
		(net 667)
	)
	(segment
		(start 111.344001 190.654001)
		(end 111.344001 192.106304)
		(width 0.1)
		(layer "In6.Cu")
		(net 667)
	)
	(segment
		(start 111.844001 192.106304)
		(end 111.844001 190.654001)
		(width 0.1)
		(layer "In6.Cu")
		(net 667)
	)
	(segment
		(start 136.812651 189.054073)
		(end 136.824072 189.042652)
		(width 0.1)
		(layer "In6.Cu")
		(net 667)
	)
	(segment
		(start 108.274001 192.129001)
		(end 108.274001 190.654001)
		(width 0.1)
		(layer "In6.Cu")
		(net 667)
	)
	(segment
		(start 108.774001 190.154001)
		(end 109.014001 190.154001)
		(width 0.1)
		(layer "In6.Cu")
		(net 667)
	)
	(segment
		(start 137.250501 188.574801)
		(end 137.250501 187.500776)
		(width 0.1)
		(layer "In6.Cu")
		(net 667)
	)
	(segment
		(start 109.514001 190.654001)
		(end 109.514001 192.079001)
		(width 0.1)
		(layer "In6.Cu")
		(net 667)
	)
	(segment
		(start 136.877001 187.524502)
		(end 136.877001 187.8005)
		(width 0.1)
		(layer "In6.Cu")
		(net 667)
	)
	(segment
		(start 137.177039 187.427314)
		(end 136.974189 187.427314)
		(width 0.1)
		(layer "In6.Cu")
		(net 667)
	)
	(segment
		(start 137.197651 188.669072)
		(end 137.221211 188.645512)
		(width 0.1)
		(layer "In6.Cu")
		(net 667)
	)
	(segment
		(start 110.014001 192.079001)
		(end 110.014001 190.654001)
		(width 0.1)
		(layer "In6.Cu")
		(net 667)
	)
	(segment
		(start 136.974189 187.427314)
		(end 136.877001 187.524502)
		(width 0.1)
		(layer "In6.Cu")
		(net 667)
	)
	(segment
		(start 134.175723 191.691)
		(end 136.46071 189.406013)
		(width 0.1)
		(layer "In6.Cu")
		(net 667)
	)
	(segment
		(start 110.514001 190.154001)
		(end 110.844001 190.154001)
		(width 0.1)
		(layer "In6.Cu")
		(net 667)
	)
	(segment
		(start 136.628059 189.083362)
		(end 136.741941 189.083362)
		(width 0.1)
		(layer "In6.Cu")
		(net 667)
	)
	(segment
		(start 112.344001 190.154001)
		(end 112.930779 190.154001)
		(width 0.1)
		(layer "In6.Cu")
		(net 667)
	)
	(segment
		(start 112.930779 190.154001)
		(end 114.467778 191.691)
		(width 0.1)
		(layer "In6.Cu")
		(net 667)
	)
	(segment
		(start 136.853362 188.971941)
		(end 136.853362 188.838059)
		(width 0.1)
		(layer "In6.Cu")
		(net 667)
	)
	(segment
		(start 136.49 189.335302)
		(end 136.49 189.221421)
		(width 0.1)
		(layer "In6.Cu")
		(net 667)
	)
	(segment
		(start 136.993059 188.698362)
		(end 137.12694 188.698362)
		(width 0.1)
		(layer "In6.Cu")
		(net 667)
	)
	(segment
		(start 107.774001 190.654001)
		(end 107.774001 192.129001)
		(width 0.1)
		(layer "In6.Cu")
		(net 667)
	)
	(segment
		(start 137.250501 187.500776)
		(end 137.177039 187.427314)
		(width 0.1)
		(layer "In6.Cu")
		(net 667)
	)
	(arc
		(start 107.774001 192.129001)
		(mid 107.847224 192.305778)
		(end 108.024001 192.379001)
		(width 0.1)
		(layer "In6.Cu")
		(net 667)
	)
	(arc
		(start 111.844001 190.654001)
		(mid 111.990448 190.300448)
		(end 112.344001 190.154001)
		(width 0.1)
		(layer "In6.Cu")
		(net 667)
	)
	(arc
		(start 136.741941 189.083362)
		(mid 136.780209 189.07575)
		(end 136.812651 189.054073)
		(width 0.1)
		(layer "In6.Cu")
		(net 667)
	)
	(arc
		(start 108.274001 190.654001)
		(mid 108.420448 190.300448)
		(end 108.774001 190.154001)
		(width 0.1)
		(layer "In6.Cu")
		(net 667)
	)
	(arc
		(start 137.12694 188.698362)
		(mid 137.165209 188.69075)
		(end 137.197651 188.669072)
		(width 0.1)
		(layer "In6.Cu")
		(net 667)
	)
	(arc
		(start 109.014001 190.154001)
		(mid 109.367554 190.300448)
		(end 109.514001 190.654001)
		(width 0.1)
		(layer "In6.Cu")
		(net 667)
	)
	(arc
		(start 136.49 189.221421)
		(mid 136.497612 189.183153)
		(end 136.519289 189.150711)
		(width 0.1)
		(layer "In6.Cu")
		(net 667)
	)
	(arc
		(start 136.557348 189.112652)
		(mid 136.58979 189.090974)
		(end 136.628059 189.083362)
		(width 0.1)
		(layer "In6.Cu")
		(net 667)
	)
	(arc
		(start 108.024001 192.379001)
		(mid 108.200778 192.305778)
		(end 108.274001 192.129001)
		(width 0.1)
		(layer "In6.Cu")
		(net 667)
	)
	(arc
		(start 136.853362 188.838059)
		(mid 136.860974 188.799791)
		(end 136.882651 188.767349)
		(width 0.1)
		(layer "In6.Cu")
		(net 667)
	)
	(arc
		(start 136.824072 189.042652)
		(mid 136.84575 189.01021)
		(end 136.853362 188.971941)
		(width 0.1)
		(layer "In6.Cu")
		(net 667)
	)
	(arc
		(start 111.344001 192.106304)
		(mid 111.417224 192.283081)
		(end 111.594001 192.356304)
		(width 0.1)
		(layer "In6.Cu")
		(net 667)
	)
	(arc
		(start 110.844001 190.154001)
		(mid 111.197554 190.300448)
		(end 111.344001 190.654001)
		(width 0.1)
		(layer "In6.Cu")
		(net 667)
	)
	(arc
		(start 136.46071 189.406013)
		(mid 136.482388 189.373571)
		(end 136.49 189.335302)
		(width 0.1)
		(layer "In6.Cu")
		(net 667)
	)
	(arc
		(start 109.514001 192.079001)
		(mid 109.587224 192.255778)
		(end 109.764001 192.329001)
		(width 0.1)
		(layer "In6.Cu")
		(net 667)
	)
	(arc
		(start 107.274001 190.154001)
		(mid 107.627554 190.300448)
		(end 107.774001 190.654001)
		(width 0.1)
		(layer "In6.Cu")
		(net 667)
	)
	(arc
		(start 111.594001 192.356304)
		(mid 111.770778 192.283081)
		(end 111.844001 192.106304)
		(width 0.1)
		(layer "In6.Cu")
		(net 667)
	)
	(arc
		(start 110.014001 190.654001)
		(mid 110.160448 190.300448)
		(end 110.514001 190.154001)
		(width 0.1)
		(layer "In6.Cu")
		(net 667)
	)
	(arc
		(start 137.221211 188.645512)
		(mid 137.242889 188.61307)
		(end 137.250501 188.574801)
		(width 0.1)
		(layer "In6.Cu")
		(net 667)
	)
	(arc
		(start 109.764001 192.329001)
		(mid 109.940778 192.255778)
		(end 110.014001 192.079001)
		(width 0.1)
		(layer "In6.Cu")
		(net 667)
	)
	(arc
		(start 136.922348 188.727652)
		(mid 136.95479 188.705974)
		(end 136.993059 188.698362)
		(width 0.1)
		(layer "In6.Cu")
		(net 667)
	)
	(segment
		(start 96.685 189.515)
		(end 97.7 189.515)
		(width 0.201)
		(layer "F.Cu")
		(net 668)
	)
	(segment
		(start 95.896 190.699)
		(end 95.896 190.004)
		(width 0.201)
		(layer "F.Cu")
		(net 668)
	)
	(segment
		(start 96.325 169.425)
		(end 96.309501 169.440499)
		(width 0.15)
		(layer "F.Cu")
		(net 668)
	)
	(segment
		(start 96.309501 169.440499)
		(end 96.309501 170.448)
		(width 0.15)
		(layer "F.Cu")
		(net 668)
	)
	(segment
		(start 95.896 190.004)
		(end 96.385 189.515)
		(width 0.201)
		(layer "F.Cu")
		(net 668)
	)
	(segment
		(start 96.385 189.515)
		(end 96.685 189.515)
		(width 0.201)
		(layer "F.Cu")
		(net 668)
	)
	(via
		(at 96.685 189.515)
		(size 0.45)
		(drill 0.1)
		(layers "F.Cu" "B.Cu")
		(net 668)
	)
	(via
		(at 96.325 169.425)
		(size 0.45)
		(drill 0.1)
		(layers "F.Cu" "B.Cu")
		(net 668)
	)
	(segment
		(start 96.325 184.025)
		(end 97.1 184.8)
		(width 0.15)
		(layer "In2.Cu")
		(net 668)
	)
	(segment
		(start 96.685 188.815)
		(end 96.685 189.515)
		(width 0.15)
		(layer "In2.Cu")
		(net 668)
	)
	(segment
		(start 97.1 184.8)
		(end 97.1 188.4)
		(width 0.15)
		(layer "In2.Cu")
		(net 668)
	)
	(segment
		(start 97.1 188.4)
		(end 96.685 188.815)
		(width 0.15)
		(layer "In2.Cu")
		(net 668)
	)
	(segment
		(start 96.325 169.425)
		(end 96.325 184.025)
		(width 0.15)
		(layer "In2.Cu")
		(net 668)
	)
	(segment
		(start 85.114501 165.85)
		(end 85.7 165.85)
		(width 0.256)
		(layer "F.Cu")
		(net 669)
	)
	(segment
		(start 86.15 166.3)
		(end 86.15 167)
		(width 0.256)
		(layer "F.Cu")
		(net 669)
	)
	(segment
		(start 85.185 167.5)
		(end 85.65 167.5)
		(width 0.256)
		(layer "F.Cu")
		(net 669)
	)
	(segment
		(start 85.105501 165.841)
		(end 85.114501 165.85)
		(width 0.256)
		(layer "F.Cu")
		(net 669)
	)
	(segment
		(start 143.375501 182.301)
		(end 143.875002 182.8005)
		(width 0.256)
		(layer "F.Cu")
		(net 669)
	)
	(segment
		(start 85.7 165.85)
		(end 86.15 166.3)
		(width 0.256)
		(layer "F.Cu")
		(net 669)
	)
	(segment
		(start 85.185 167.5)
		(end 84.413 167.5)
		(width 0.256)
		(layer "F.Cu")
		(net 669)
	)
	(segment
		(start 85.65 167.5)
		(end 86.15 167)
		(width 0.256)
		(layer "F.Cu")
		(net 669)
	)
	(via
		(at 86.15 167)
		(size 0.45)
		(drill 0.1)
		(layers "F.Cu" "B.Cu")
		(net 669)
	)
	(via
		(at 143.875002 182.8005)
		(size 0.45)
		(drill 0.1)
		(layers "F.Cu" "B.Cu")
		(net 669)
	)
	(segment
		(start 85.230499 166.884)
		(end 86.034 166.884)
		(width 0.256)
		(layer "B.Cu")
		(net 669)
	)
	(segment
		(start 86.034 166.884)
		(end 86.15 167)
		(width 0.256)
		(layer "B.Cu")
		(net 669)
	)
	(segment
		(start 111.35 183.9)
		(end 113.35 181.9)
		(width 0.1)
		(layer "In6.Cu")
		(net 669)
	)
	(segment
		(start 140.6245 182.1755)
		(end 143.250002 182.1755)
		(width 0.1)
		(layer "In6.Cu")
		(net 669)
	)
	(segment
		(start 119.55 180.7)
		(end 124.95 180.7)
		(width 0.1)
		(layer "In6.Cu")
		(net 669)
	)
	(segment
		(start 88.2 168.624185)
		(end 92.65 173.074185)
		(width 0.1)
		(layer "In6.Cu")
		(net 669)
	)
	(segment
		(start 86.15 167)
		(end 87.3 167)
		(width 0.1)
		(layer "In6.Cu")
		(net 669)
	)
	(segment
		(start 140.4 181.951)
		(end 140.6245 182.1755)
		(width 0.1)
		(layer "In6.Cu")
		(net 669)
	)
	(segment
		(start 92.65 181.65)
		(end 94.9 183.9)
		(width 0.1)
		(layer "In6.Cu")
		(net 669)
	)
	(segment
		(start 92.65 173.074185)
		(end 92.65 181.65)
		(width 0.1)
		(layer "In6.Cu")
		(net 669)
	)
	(segment
		(start 94.9 183.9)
		(end 111.35 183.9)
		(width 0.1)
		(layer "In6.Cu")
		(net 669)
	)
	(segment
		(start 125.35 180.3)
		(end 138.2 180.3)
		(width 0.1)
		(layer "In6.Cu")
		(net 669)
	)
	(segment
		(start 140.4 181.6)
		(end 140.4 181.951)
		(width 0.1)
		(layer "In6.Cu")
		(net 669)
	)
	(segment
		(start 118.35 181.9)
		(end 119.55 180.7)
		(width 0.1)
		(layer "In6.Cu")
		(net 669)
	)
	(segment
		(start 138.2 180.3)
		(end 139.2 181.3)
		(width 0.1)
		(layer "In6.Cu")
		(net 669)
	)
	(segment
		(start 124.95 180.7)
		(end 125.35 180.3)
		(width 0.1)
		(layer "In6.Cu")
		(net 669)
	)
	(segment
		(start 113.35 181.9)
		(end 118.35 181.9)
		(width 0.1)
		(layer "In6.Cu")
		(net 669)
	)
	(segment
		(start 143.250002 182.1755)
		(end 143.875002 182.8005)
		(width 0.1)
		(layer "In6.Cu")
		(net 669)
	)
	(segment
		(start 88.2 167.9)
		(end 88.2 168.624185)
		(width 0.1)
		(layer "In6.Cu")
		(net 669)
	)
	(segment
		(start 140.1 181.3)
		(end 140.4 181.6)
		(width 0.1)
		(layer "In6.Cu")
		(net 669)
	)
	(segment
		(start 139.2 181.3)
		(end 140.1 181.3)
		(width 0.1)
		(layer "In6.Cu")
		(net 669)
	)
	(segment
		(start 87.3 167)
		(end 88.2 167.9)
		(width 0.1)
		(layer "In6.Cu")
		(net 669)
	)
	(segment
		(start 106.25 184.284)
		(end 105.651 183.685)
		(width 0.15)
		(layer "F.Cu")
		(net 670)
	)
	(segment
		(start 105.651 183.685)
		(end 105.651 182.934)
		(width 0.15)
		(layer "F.Cu")
		(net 670)
	)
	(segment
		(start 106.25 184.315)
		(end 106.25 184.284)
		(width 0.15)
		(layer "F.Cu")
		(net 670)
	)
	(segment
		(start 178.35 194.15)
		(end 178.756999 194.556999)
		(width 0.177)
		(layer "F.Cu")
		(net 671)
	)
	(segment
		(start 107.3 185.285)
		(end 106.25 185.285)
		(width 0.15)
		(layer "F.Cu")
		(net 671)
	)
	(segment
		(start 178.756999 194.556999)
		(end 180.278 194.556999)
		(width 0.177)
		(layer "F.Cu")
		(net 671)
	)
	(segment
		(start 106.225 185.285)
		(end 105.737096 185.772904)
		(width 0.15)
		(layer "F.Cu")
		(net 671)
	)
	(via
		(at 178.35 194.15)
		(size 0.45)
		(drill 0.1)
		(layers "F.Cu" "B.Cu")
		(net 671)
	)
	(via
		(at 105.737096 185.772904)
		(size 0.45)
		(drill 0.1)
		(layers "F.Cu" "B.Cu")
		(net 671)
	)
	(segment
		(start 178.35 194.15)
		(end 178.75 194.15)
		(width 0.15)
		(layer "B.Cu")
		(net 671)
	)
	(segment
		(start 105.737096 186.627096)
		(end 105.937096 186.827096)
		(width 0.15)
		(layer "B.Cu")
		(net 671)
	)
	(segment
		(start 178.75 194.15)
		(end 179.6 193.3)
		(width 0.15)
		(layer "B.Cu")
		(net 671)
	)
	(segment
		(start 179.6 193.3)
		(end 179.6 192.715)
		(width 0.15)
		(layer "B.Cu")
		(net 671)
	)
	(segment
		(start 105.937096 186.827096)
		(end 105.937096 187.9)
		(width 0.15)
		(layer "B.Cu")
		(net 671)
	)
	(segment
		(start 179.6 192.715)
		(end 180.315 192)
		(width 0.15)
		(layer "B.Cu")
		(net 671)
	)
	(segment
		(start 105.737096 185.772904)
		(end 105.737096 186.627096)
		(width 0.15)
		(layer "B.Cu")
		(net 671)
	)
	(segment
		(start 176.5 189.15)
		(end 175.3 187.95)
		(width 0.1)
		(layer "In4.Cu")
		(net 671)
	)
	(segment
		(start 112.196001 193.596001)
		(end 105.737096 187.137096)
		(width 0.1)
		(layer "In4.Cu")
		(net 671)
	)
	(segment
		(start 105.737096 187.137096)
		(end 105.737096 185.772904)
		(width 0.1)
		(layer "In4.Cu")
		(net 671)
	)
	(segment
		(start 153.7 194.7)
		(end 152.596001 193.596001)
		(width 0.1)
		(layer "In4.Cu")
		(net 671)
	)
	(segment
		(start 152.596001 193.596001)
		(end 112.196001 193.596001)
		(width 0.1)
		(layer "In4.Cu")
		(net 671)
	)
	(segment
		(start 175.3 187.95)
		(end 163.7 187.95)
		(width 0.1)
		(layer "In4.Cu")
		(net 671)
	)
	(segment
		(start 163.7 187.95)
		(end 156.95 194.7)
		(width 0.1)
		(layer "In4.Cu")
		(net 671)
	)
	(segment
		(start 176.5 190)
		(end 176.5 189.15)
		(width 0.1)
		(layer "In4.Cu")
		(net 671)
	)
	(segment
		(start 156.95 194.7)
		(end 153.7 194.7)
		(width 0.1)
		(layer "In4.Cu")
		(net 671)
	)
	(segment
		(start 178.35 194.15)
		(end 177.5 193.3)
		(width 0.1)
		(layer "In4.Cu")
		(net 671)
	)
	(segment
		(start 177.5 191)
		(end 176.5 190)
		(width 0.1)
		(layer "In4.Cu")
		(net 671)
	)
	(segment
		(start 177.5 193.3)
		(end 177.5 191)
		(width 0.1)
		(layer "In4.Cu")
		(net 671)
	)
	(segment
		(start 103.075 185.27)
		(end 103.562904 185.757904)
		(width 0.15)
		(layer "F.Cu")
		(net 672)
	)
	(segment
		(start 102 185.285)
		(end 103.035 185.285)
		(width 0.15)
		(layer "F.Cu")
		(net 672)
	)
	(segment
		(start 179.005 198.313)
		(end 179.011 198.307)
		(width 0.177)
		(layer "F.Cu")
		(net 672)
	)
	(segment
		(start 103.035 185.285)
		(end 103.05 185.27)
		(width 0.15)
		(layer "F.Cu")
		(net 672)
	)
	(segment
		(start 179.011 198.307)
		(end 180.278 198.306999)
		(width 0.177)
		(layer "F.Cu")
		(net 672)
	)
	(via
		(at 103.562904 185.757904)
		(size 0.45)
		(drill 0.1)
		(layers "F.Cu" "B.Cu")
		(net 672)
	)
	(via
		(at 179.005 198.313)
		(size 0.45)
		(drill 0.1)
		(layers "F.Cu" "B.Cu")
		(net 672)
	)
	(segment
		(start 180.315 199.4)
		(end 179.45 199.4)
		(width 0.15)
		(layer "B.Cu")
		(net 672)
	)
	(segment
		(start 103.562904 185.757904)
		(end 103.562904 186.612096)
		(width 0.15)
		(layer "B.Cu")
		(net 672)
	)
	(segment
		(start 179.005 198.955)
		(end 179.005 198.313)
		(width 0.15)
		(layer "B.Cu")
		(net 672)
	)
	(segment
		(start 103.562904 186.612096)
		(end 103.362904 186.812096)
		(width 0.15)
		(layer "B.Cu")
		(net 672)
	)
	(segment
		(start 179.45 199.4)
		(end 179.005 198.955)
		(width 0.15)
		(layer "B.Cu")
		(net 672)
	)
	(segment
		(start 103.362904 186.812096)
		(end 103.362904 187.885)
		(width 0.15)
		(layer "B.Cu")
		(net 672)
	)
	(segment
		(start 110.740901 194.740901)
		(end 151.740901 194.740901)
		(width 0.1)
		(layer "In4.Cu")
		(net 672)
	)
	(segment
		(start 164.45 188.85)
		(end 175.05 188.85)
		(width 0.1)
		(layer "In4.Cu")
		(net 672)
	)
	(segment
		(start 175.6 189.4)
		(end 175.6 189.9)
		(width 0.1)
		(layer "In4.Cu")
		(net 672)
	)
	(segment
		(start 175.05 188.85)
		(end 175.6 189.4)
		(width 0.1)
		(layer "In4.Cu")
		(net 672)
	)
	(segment
		(start 178.196 197.504)
		(end 178.196 195.346)
		(width 0.1)
		(layer "In4.Cu")
		(net 672)
	)
	(segment
		(start 103.562904 185.757904)
		(end 103.562904 187.562904)
		(width 0.1)
		(layer "In4.Cu")
		(net 672)
	)
	(segment
		(start 175.6 189.9)
		(end 177 191.3)
		(width 0.1)
		(layer "In4.Cu")
		(net 672)
	)
	(segment
		(start 178.196 195.346)
		(end 177 194.15)
		(width 0.1)
		(layer "In4.Cu")
		(net 672)
	)
	(segment
		(start 157.45 195.85)
		(end 164.45 188.85)
		(width 0.1)
		(layer "In4.Cu")
		(net 672)
	)
	(segment
		(start 152.85 195.85)
		(end 157.45 195.85)
		(width 0.1)
		(layer "In4.Cu")
		(net 672)
	)
	(segment
		(start 178.196 197.504)
		(end 179.005 198.313)
		(width 0.1)
		(layer "In4.Cu")
		(net 672)
	)
	(segment
		(start 103.562904 187.562904)
		(end 110.740901 194.740901)
		(width 0.1)
		(layer "In4.Cu")
		(net 672)
	)
	(segment
		(start 151.740901 194.740901)
		(end 152.85 195.85)
		(width 0.1)
		(layer "In4.Cu")
		(net 672)
	)
	(segment
		(start 177 191.3)
		(end 177 194.15)
		(width 0.1)
		(layer "In4.Cu")
		(net 672)
	)
	(segment
		(start 94.300501 158.285)
		(end 94.300501 160.026)
		(width 0.256)
		(layer "F.Cu")
		(net 673)
	)
	(segment
		(start 97.425501 160.551)
		(end 99.500501 162.626)
		(width 0.256)
		(layer "F.Cu")
		(net 673)
	)
	(segment
		(start 99.500501 162.626)
		(end 99.500501 162.726)
		(width 0.256)
		(layer "F.Cu")
		(net 673)
	)
	(segment
		(start 94.300501 160.026)
		(end 94.825501 160.551)
		(width 0.256)
		(layer "F.Cu")
		(net 673)
	)
	(segment
		(start 126.376502 169.302)
		(end 125.877001 168.8025)
		(width 0.256)
		(layer "F.Cu")
		(net 673)
	)
	(segment
		(start 94.825501 160.551)
		(end 97.425501 160.551)
		(width 0.256)
		(layer "F.Cu")
		(net 673)
	)
	(via
		(at 125.877001 168.8025)
		(size 0.45)
		(drill 0.1)
		(layers "F.Cu" "B.Cu")
		(net 673)
	)
	(via
		(at 99.500501 162.726)
		(size 0.45)
		(drill 0.1)
		(layers "F.Cu" "B.Cu")
		(net 673)
	)
	(segment
		(start 99.500501 163.441)
		(end 99.525501 163.466)
		(width 0.256)
		(layer "B.Cu")
		(net 673)
	)
	(segment
		(start 99.500501 162.061)
		(end 99.500501 163.441)
		(width 0.256)
		(layer "B.Cu")
		(net 673)
	)
	(segment
		(start 111.177996 167.184282)
		(end 111.177996 167.184283)
		(width 0.1)
		(layer "In9.Cu")
		(net 673)
	)
	(segment
		(start 110.301438 167.777995)
		(end 110.301439 167.777995)
		(width 0.1)
		(layer "In9.Cu")
		(net 673)
	)
	(segment
		(start 108.038682 165.515239)
		(end 108.038683 165.515239)
		(width 0.1)
		(layer "In9.Cu")
		(net 673)
	)
	(segment
		(start 110.867129 168.343685)
		(end 110.867127 168.343684)
		(width 0.1)
		(layer "In9.Cu")
		(net 673)
	)
	(segment
		(start 120.7 168.5)
		(end 111.9 168.5)
		(width 0.1)
		(layer "In9.Cu")
		(net 673)
	)
	(segment
		(start 102.976513 164.226)
		(end 100.075501 164.226)
		(width 0.1)
		(layer "In9.Cu")
		(net 673)
	)
	(segment
		(start 103.302513 163.9)
		(end 102.976513 164.226)
		(width 0.1)
		(layer "In9.Cu")
		(net 673)
	)
	(segment
		(start 108.632395 164.355838)
		(end 108.632394 164.355838)
		(width 0.1)
		(layer "In9.Cu")
		(net 673)
	)
	(segment
		(start 100.075501 164.226)
		(end 99.500501 163.651)
		(width 0.1)
		(layer "In9.Cu")
		(net 673)
	)
	(segment
		(start 109.480929 165.487215)
		(end 109.480929 165.487216)
		(width 0.1)
		(layer "In9.Cu")
		(net 673)
	)
	(segment
		(start 111.305406 168.188249)
		(end 111.149971 168.343685)
		(width 0.1)
		(layer "In9.Cu")
		(net 673)
	)
	(segment
		(start 111.305407 168.188249)
		(end 111.305406 168.188249)
		(width 0.1)
		(layer "In9.Cu")
		(net 673)
	)
	(segment
		(start 109.480929 165.487216)
		(end 108.887214 166.080927)
		(width 0.1)
		(layer "In9.Cu")
		(net 673)
	)
	(segment
		(start 107.472993 164.666706)
		(end 107.628429 164.511271)
		(width 0.1)
		(layer "In9.Cu")
		(net 673)
	)
	(segment
		(start 110.867128 168.060842)
		(end 111.460839 167.467126)
		(width 0.1)
		(layer "In9.Cu")
		(net 673)
	)
	(segment
		(start 125.877001 168.8025)
		(end 125.874501 168.8)
		(width 0.1)
		(layer "In9.Cu")
		(net 673)
	)
	(segment
		(start 109.17006 166.363774)
		(end 109.17006 166.363773)
		(width 0.1)
		(layer "In9.Cu")
		(net 673)
	)
	(segment
		(start 107.628428 164.228427)
		(end 107.3 163.9)
		(width 0.1)
		(layer "In9.Cu")
		(net 673)
	)
	(segment
		(start 110.867126 168.060841)
		(end 110.867128 168.060842)
		(width 0.1)
		(layer "In9.Cu")
		(net 673)
	)
	(segment
		(start 108.91524 164.921526)
		(end 108.91524 164.921527)
		(width 0.1)
		(layer "In9.Cu")
		(net 673)
	)
	(segment
		(start 110.301438 167.495151)
		(end 110.89515 166.901437)
		(width 0.1)
		(layer "In9.Cu")
		(net 673)
	)
	(segment
		(start 110.329462 166.052905)
		(end 110.329461 166.052905)
		(width 0.1)
		(layer "In9.Cu")
		(net 673)
	)
	(segment
		(start 110.046618 166.052905)
		(end 109.452903 166.646616)
		(width 0.1)
		(layer "In9.Cu")
		(net 673)
	)
	(segment
		(start 109.17006 166.646617)
		(end 109.170061 166.646617)
		(width 0.1)
		(layer "In9.Cu")
		(net 673)
	)
	(segment
		(start 107.472993 164.666707)
		(end 107.472993 164.666706)
		(width 0.1)
		(layer "In9.Cu")
		(net 673)
	)
	(segment
		(start 108.038682 165.232395)
		(end 108.632394 164.638681)
		(width 0.1)
		(layer "In9.Cu")
		(net 673)
	)
	(segment
		(start 109.735749 166.929463)
		(end 109.735749 166.929462)
		(width 0.1)
		(layer "In9.Cu")
		(net 673)
	)
	(segment
		(start 109.17006 166.363773)
		(end 109.763772 165.770059)
		(width 0.1)
		(layer "In9.Cu")
		(net 673)
	)
	(segment
		(start 99.500501 163.651)
		(end 99.500501 162.726)
		(width 0.1)
		(layer "In9.Cu")
		(net 673)
	)
	(segment
		(start 108.604371 165.798085)
		(end 108.604371 165.798084)
		(width 0.1)
		(layer "In9.Cu")
		(net 673)
	)
	(segment
		(start 108.038682 165.232396)
		(end 108.038682 165.232395)
		(width 0.1)
		(layer "In9.Cu")
		(net 673)
	)
	(segment
		(start 110.895151 166.618594)
		(end 110.89515 166.618594)
		(width 0.1)
		(layer "In9.Cu")
		(net 673)
	)
	(segment
		(start 108.91524 164.921527)
		(end 108.321525 165.515238)
		(width 0.1)
		(layer "In9.Cu")
		(net 673)
	)
	(segment
		(start 108.349551 164.355838)
		(end 107.755836 164.949549)
		(width 0.1)
		(layer "In9.Cu")
		(net 673)
	)
	(segment
		(start 107.472993 164.94955)
		(end 107.472994 164.94955)
		(width 0.1)
		(layer "In9.Cu")
		(net 673)
	)
	(segment
		(start 109.763773 165.487216)
		(end 109.763772 165.487216)
		(width 0.1)
		(layer "In9.Cu")
		(net 673)
	)
	(segment
		(start 110.612307 166.618593)
		(end 110.612307 166.618594)
		(width 0.1)
		(layer "In9.Cu")
		(net 673)
	)
	(segment
		(start 107.628429 164.228429)
		(end 107.628428 164.228427)
		(width 0.1)
		(layer "In9.Cu")
		(net 673)
	)
	(segment
		(start 111.9 168.5)
		(end 111.58825 168.18825)
		(width 0.1)
		(layer "In9.Cu")
		(net 673)
	)
	(segment
		(start 110.046618 166.052904)
		(end 110.046618 166.052905)
		(width 0.1)
		(layer "In9.Cu")
		(net 673)
	)
	(segment
		(start 107.3 163.9)
		(end 103.302513 163.9)
		(width 0.1)
		(layer "In9.Cu")
		(net 673)
	)
	(segment
		(start 108.349551 164.355837)
		(end 108.349551 164.355838)
		(width 0.1)
		(layer "In9.Cu")
		(net 673)
	)
	(segment
		(start 125.874501 168.8)
		(end 121 168.8)
		(width 0.1)
		(layer "In9.Cu")
		(net 673)
	)
	(segment
		(start 109.735749 166.929462)
		(end 110.329461 166.335748)
		(width 0.1)
		(layer "In9.Cu")
		(net 673)
	)
	(segment
		(start 109.735749 167.212306)
		(end 109.73575 167.212306)
		(width 0.1)
		(layer "In9.Cu")
		(net 673)
	)
	(segment
		(start 108.604371 165.798084)
		(end 109.198083 165.20437)
		(width 0.1)
		(layer "In9.Cu")
		(net 673)
	)
	(segment
		(start 108.604371 166.080928)
		(end 108.604372 166.080928)
		(width 0.1)
		(layer "In9.Cu")
		(net 673)
	)
	(segment
		(start 110.301438 167.495152)
		(end 110.301438 167.495151)
		(width 0.1)
		(layer "In9.Cu")
		(net 673)
	)
	(segment
		(start 111.177996 167.184283)
		(end 110.584281 167.777994)
		(width 0.1)
		(layer "In9.Cu")
		(net 673)
	)
	(segment
		(start 121 168.8)
		(end 120.7 168.5)
		(width 0.1)
		(layer "In9.Cu")
		(net 673)
	)
	(segment
		(start 111.46084 167.184283)
		(end 111.460839 167.184283)
		(width 0.1)
		(layer "In9.Cu")
		(net 673)
	)
	(segment
		(start 109.198084 164.921527)
		(end 109.198083 164.921527)
		(width 0.1)
		(layer "In9.Cu")
		(net 673)
	)
	(segment
		(start 110.612307 166.618594)
		(end 110.018592 167.212305)
		(width 0.1)
		(layer "In9.Cu")
		(net 673)
	)
	(arc
		(start 108.321525 165.515238)
		(mid 108.180104 165.573817)
		(end 108.038682 165.515239)
		(width 0.1)
		(layer "In9.Cu")
		(net 673)
	)
	(arc
		(start 110.89515 166.618594)
		(mid 110.753729 166.560015)
		(end 110.612307 166.618593)
		(width 0.1)
		(layer "In9.Cu")
		(net 673)
	)
	(arc
		(start 109.763772 165.487216)
		(mid 109.622351 165.428637)
		(end 109.480929 165.487215)
		(width 0.1)
		(layer "In9.Cu")
		(net 673)
	)
	(arc
		(start 110.018592 167.212305)
		(mid 109.877171 167.270884)
		(end 109.735749 167.212306)
		(width 0.1)
		(layer "In9.Cu")
		(net 673)
	)
	(arc
		(start 109.763772 165.770059)
		(mid 109.822351 165.628638)
		(end 109.763773 165.487216)
		(width 0.1)
		(layer "In9.Cu")
		(net 673)
	)
	(arc
		(start 109.198083 164.921527)
		(mid 109.056662 164.862948)
		(end 108.91524 164.921526)
		(width 0.1)
		(layer "In9.Cu")
		(net 673)
	)
	(arc
		(start 110.301439 167.777995)
		(mid 110.24286 167.636574)
		(end 110.301438 167.495152)
		(width 0.1)
		(layer "In9.Cu")
		(net 673)
	)
	(arc
		(start 109.452903 166.646616)
		(mid 109.311482 166.705195)
		(end 109.17006 166.646617)
		(width 0.1)
		(layer "In9.Cu")
		(net 673)
	)
	(arc
		(start 111.460839 167.184283)
		(mid 111.319418 167.125704)
		(end 111.177996 167.184282)
		(width 0.1)
		(layer "In9.Cu")
		(net 673)
	)
	(arc
		(start 110.584281 167.777994)
		(mid 110.44286 167.836573)
		(end 110.301438 167.777995)
		(width 0.1)
		(layer "In9.Cu")
		(net 673)
	)
	(arc
		(start 110.329461 166.052905)
		(mid 110.18804 165.994326)
		(end 110.046618 166.052904)
		(width 0.1)
		(layer "In9.Cu")
		(net 673)
	)
	(arc
		(start 108.632394 164.355838)
		(mid 108.490973 164.297259)
		(end 108.349551 164.355837)
		(width 0.1)
		(layer "In9.Cu")
		(net 673)
	)
	(arc
		(start 108.604372 166.080928)
		(mid 108.545793 165.939507)
		(end 108.604371 165.798085)
		(width 0.1)
		(layer "In9.Cu")
		(net 673)
	)
	(arc
		(start 111.149971 168.343685)
		(mid 111.008549 168.402262)
		(end 110.867129 168.343685)
		(width 0.1)
		(layer "In9.Cu")
		(net 673)
	)
	(arc
		(start 109.170061 166.646617)
		(mid 109.111482 166.505196)
		(end 109.17006 166.363774)
		(width 0.1)
		(layer "In9.Cu")
		(net 673)
	)
	(arc
		(start 110.329461 166.335748)
		(mid 110.38804 166.194327)
		(end 110.329462 166.052905)
		(width 0.1)
		(layer "In9.Cu")
		(net 673)
	)
	(arc
		(start 108.038683 165.515239)
		(mid 107.980104 165.373818)
		(end 108.038682 165.232396)
		(width 0.1)
		(layer "In9.Cu")
		(net 673)
	)
	(arc
		(start 109.198083 165.20437)
		(mid 109.256662 165.062949)
		(end 109.198084 164.921527)
		(width 0.1)
		(layer "In9.Cu")
		(net 673)
	)
	(arc
		(start 107.755836 164.949549)
		(mid 107.614415 165.008128)
		(end 107.472993 164.94955)
		(width 0.1)
		(layer "In9.Cu")
		(net 673)
	)
	(arc
		(start 110.89515 166.901437)
		(mid 110.953729 166.760016)
		(end 110.895151 166.618594)
		(width 0.1)
		(layer "In9.Cu")
		(net 673)
	)
	(arc
		(start 107.472994 164.94955)
		(mid 107.414415 164.808129)
		(end 107.472993 164.666707)
		(width 0.1)
		(layer "In9.Cu")
		(net 673)
	)
	(arc
		(start 111.58825 168.18825)
		(mid 111.446829 168.129671)
		(end 111.305407 168.188249)
		(width 0.1)
		(layer "In9.Cu")
		(net 673)
	)
	(arc
		(start 109.73575 167.212306)
		(mid 109.677171 167.070885)
		(end 109.735749 166.929463)
		(width 0.1)
		(layer "In9.Cu")
		(net 673)
	)
	(arc
		(start 107.628429 164.511271)
		(mid 107.687006 164.369849)
		(end 107.628429 164.228429)
		(width 0.1)
		(layer "In9.Cu")
		(net 673)
	)
	(arc
		(start 111.460839 167.467126)
		(mid 111.519418 167.325705)
		(end 111.46084 167.184283)
		(width 0.1)
		(layer "In9.Cu")
		(net 673)
	)
	(arc
		(start 108.632394 164.638681)
		(mid 108.690973 164.49726)
		(end 108.632395 164.355838)
		(width 0.1)
		(layer "In9.Cu")
		(net 673)
	)
	(arc
		(start 110.867127 168.343684)
		(mid 110.808548 168.202263)
		(end 110.867126 168.060841)
		(width 0.1)
		(layer "In9.Cu")
		(net 673)
	)
	(arc
		(start 108.887214 166.080927)
		(mid 108.745793 166.139506)
		(end 108.604371 166.080928)
		(width 0.1)
		(layer "In9.Cu")
		(net 673)
	)
	(segment
		(start 93.800501 160.650501)
		(end 94.201 161.051)
		(width 0.256)
		(layer "F.Cu")
		(net 674)
	)
	(segment
		(start 127.3765 169.302)
		(end 126.877001 168.8025)
		(width 0.256)
		(layer "F.Cu")
		(net 674)
	)
	(segment
		(start 93.800501 158.285)
		(end 93.800501 160.650501)
		(width 0.256)
		(layer "F.Cu")
		(net 674)
	)
	(segment
		(start 94.201 161.051)
		(end 96.775501 161.051)
		(width 0.256)
		(layer "F.Cu")
		(net 674)
	)
	(segment
		(start 96.775501 161.051)
		(end 98.450501 162.726)
		(width 0.256)
		(layer "F.Cu")
		(net 674)
	)
	(via
		(at 98.450501 162.726)
		(size 0.45)
		(drill 0.1)
		(layers "F.Cu" "B.Cu")
		(net 674)
	)
	(via
		(at 126.877001 168.8025)
		(size 0.45)
		(drill 0.1)
		(layers "F.Cu" "B.Cu")
		(net 674)
	)
	(segment
		(start 98.450501 163.441)
		(end 98.475501 163.466)
		(width 0.256)
		(layer "B.Cu")
		(net 674)
	)
	(segment
		(start 98.450501 162.061)
		(end 98.450501 163.441)
		(width 0.256)
		(layer "B.Cu")
		(net 674)
	)
	(segment
		(start 118.250501 169.191198)
		(end 118.250501 169.660802)
		(width 0.1)
		(layer "In9.Cu")
		(net 674)
	)
	(segment
		(start 114.650501 169.660802)
		(end 114.650501 169.191198)
		(width 0.1)
		(layer "In9.Cu")
		(net 674)
	)
	(segment
		(start 118.650501 169.660802)
		(end 118.650501 169.191198)
		(width 0.1)
		(layer "In9.Cu")
		(net 674)
	)
	(segment
		(start 117.450501 169.191198)
		(end 117.450501 169.660802)
		(width 0.1)
		(layer "In9.Cu")
		(net 674)
	)
	(segment
		(start 115.450501 169.660802)
		(end 115.450501 169.191198)
		(width 0.1)
		(layer "In9.Cu")
		(net 674)
	)
	(segment
		(start 112.450501 169.426)
		(end 111.326 169.426)
		(width 0.1)
		(layer "In9.Cu")
		(net 674)
	)
	(segment
		(start 98.450501 163.500999)
		(end 98.450501 162.726)
		(width 0.1)
		(layer "In9.Cu")
		(net 674)
	)
	(segment
		(start 116.650501 169.191198)
		(end 116.650501 169.660802)
		(width 0.1)
		(layer "In9.Cu")
		(net 674)
	)
	(segment
		(start 106.5 164.6)
		(end 99.549501 164.6)
		(width 0.1)
		(layer "In9.Cu")
		(net 674)
	)
	(segment
		(start 123.674 169.426)
		(end 120.450501 169.426)
		(width 0.1)
		(layer "In9.Cu")
		(net 674)
	)
	(segment
		(start 114.250501 169.191198)
		(end 114.250501 169.660802)
		(width 0.1)
		(layer "In9.Cu")
		(net 674)
	)
	(segment
		(start 117.850501 169.660802)
		(end 117.850501 169.191198)
		(width 0.1)
		(layer "In9.Cu")
		(net 674)
	)
	(segment
		(start 115.050501 169.191198)
		(end 115.050501 169.660802)
		(width 0.1)
		(layer "In9.Cu")
		(net 674)
	)
	(segment
		(start 119.850501 169.191198)
		(end 119.850501 169.660802)
		(width 0.1)
		(layer "In9.Cu")
		(net 674)
	)
	(segment
		(start 119.050501 169.191198)
		(end 119.050501 169.660802)
		(width 0.1)
		(layer "In9.Cu")
		(net 674)
	)
	(segment
		(start 120.250501 169.226)
		(end 120.250501 169.191198)
		(width 0.1)
		(layer "In9.Cu")
		(net 674)
	)
	(segment
		(start 112.650501 169.191198)
		(end 112.650501 169.226)
		(width 0.1)
		(layer "In9.Cu")
		(net 674)
	)
	(segment
		(start 113.850501 169.660802)
		(end 113.850501 169.191198)
		(width 0.1)
		(layer "In9.Cu")
		(net 674)
	)
	(segment
		(start 119.450501 169.660802)
		(end 119.450501 169.191198)
		(width 0.1)
		(layer "In9.Cu")
		(net 674)
	)
	(segment
		(start 113.050501 169.660802)
		(end 113.050501 169.191198)
		(width 0.1)
		(layer "In9.Cu")
		(net 674)
	)
	(segment
		(start 117.050501 169.660802)
		(end 117.050501 169.191198)
		(width 0.1)
		(layer "In9.Cu")
		(net 674)
	)
	(segment
		(start 123.9225 169.1775)
		(end 123.674 169.426)
		(width 0.1)
		(layer "In9.Cu")
		(net 674)
	)
	(segment
		(start 115.850501 169.191198)
		(end 115.850501 169.660802)
		(width 0.1)
		(layer "In9.Cu")
		(net 674)
	)
	(segment
		(start 111.326 169.426)
		(end 106.5 164.6)
		(width 0.1)
		(layer "In9.Cu")
		(net 674)
	)
	(segment
		(start 116.250501 169.660802)
		(end 116.250501 169.191198)
		(width 0.1)
		(layer "In9.Cu")
		(net 674)
	)
	(segment
		(start 113.450501 169.191198)
		(end 113.450501 169.660802)
		(width 0.1)
		(layer "In9.Cu")
		(net 674)
	)
	(segment
		(start 126.502001 169.1775)
		(end 123.9225 169.1775)
		(width 0.1)
		(layer "In9.Cu")
		(net 674)
	)
	(segment
		(start 126.877001 168.8025)
		(end 126.502001 169.1775)
		(width 0.1)
		(layer "In9.Cu")
		(net 674)
	)
	(segment
		(start 99.549501 164.6)
		(end 98.450501 163.500999)
		(width 0.1)
		(layer "In9.Cu")
		(net 674)
	)
	(arc
		(start 117.250501 169.860802)
		(mid 117.10908 169.802223)
		(end 117.050501 169.660802)
		(width 0.1)
		(layer "In9.Cu")
		(net 674)
	)
	(arc
		(start 117.450501 169.660802)
		(mid 117.391922 169.802223)
		(end 117.250501 169.860802)
		(width 0.1)
		(layer "In9.Cu")
		(net 674)
	)
	(arc
		(start 115.650501 169.860802)
		(mid 115.50908 169.802223)
		(end 115.450501 169.660802)
		(width 0.1)
		(layer "In9.Cu")
		(net 674)
	)
	(arc
		(start 118.450501 168.991198)
		(mid 118.30908 169.049777)
		(end 118.250501 169.191198)
		(width 0.1)
		(layer "In9.Cu")
		(net 674)
	)
	(arc
		(start 114.450501 168.991198)
		(mid 114.30908 169.049777)
		(end 114.250501 169.191198)
		(width 0.1)
		(layer "In9.Cu")
		(net 674)
	)
	(arc
		(start 117.650501 168.991198)
		(mid 117.50908 169.049777)
		(end 117.450501 169.191198)
		(width 0.1)
		(layer "In9.Cu")
		(net 674)
	)
	(arc
		(start 115.250501 168.991198)
		(mid 115.10908 169.049777)
		(end 115.050501 169.191198)
		(width 0.1)
		(layer "In9.Cu")
		(net 674)
	)
	(arc
		(start 113.850501 169.191198)
		(mid 113.791922 169.049777)
		(end 113.650501 168.991198)
		(width 0.1)
		(layer "In9.Cu")
		(net 674)
	)
	(arc
		(start 116.850501 168.991198)
		(mid 116.70908 169.049777)
		(end 116.650501 169.191198)
		(width 0.1)
		(layer "In9.Cu")
		(net 674)
	)
	(arc
		(start 116.250501 169.191198)
		(mid 116.191922 169.049777)
		(end 116.050501 168.991198)
		(width 0.1)
		(layer "In9.Cu")
		(net 674)
	)
	(arc
		(start 120.450501 169.426)
		(mid 120.30908 169.367421)
		(end 120.250501 169.226)
		(width 0.1)
		(layer "In9.Cu")
		(net 674)
	)
	(arc
		(start 113.450501 169.660802)
		(mid 113.391922 169.802223)
		(end 113.250501 169.860802)
		(width 0.1)
		(layer "In9.Cu")
		(net 674)
	)
	(arc
		(start 117.850501 169.191198)
		(mid 117.791922 169.049777)
		(end 117.650501 168.991198)
		(width 0.1)
		(layer "In9.Cu")
		(net 674)
	)
	(arc
		(start 114.650501 169.191198)
		(mid 114.591922 169.049777)
		(end 114.450501 168.991198)
		(width 0.1)
		(layer "In9.Cu")
		(net 674)
	)
	(arc
		(start 119.850501 169.660802)
		(mid 119.791922 169.802223)
		(end 119.650501 169.860802)
		(width 0.1)
		(layer "In9.Cu")
		(net 674)
	)
	(arc
		(start 116.650501 169.660802)
		(mid 116.591922 169.802223)
		(end 116.450501 169.860802)
		(width 0.1)
		(layer "In9.Cu")
		(net 674)
	)
	(arc
		(start 118.050501 169.860802)
		(mid 117.90908 169.802223)
		(end 117.850501 169.660802)
		(width 0.1)
		(layer "In9.Cu")
		(net 674)
	)
	(arc
		(start 113.050501 169.191198)
		(mid 112.991922 169.049777)
		(end 112.850501 168.991198)
		(width 0.1)
		(layer "In9.Cu")
		(net 674)
	)
	(arc
		(start 118.250501 169.660802)
		(mid 118.191922 169.802223)
		(end 118.050501 169.860802)
		(width 0.1)
		(layer "In9.Cu")
		(net 674)
	)
	(arc
		(start 119.250501 168.991198)
		(mid 119.10908 169.049777)
		(end 119.050501 169.191198)
		(width 0.1)
		(layer "In9.Cu")
		(net 674)
	)
	(arc
		(start 118.650501 169.191198)
		(mid 118.591922 169.049777)
		(end 118.450501 168.991198)
		(width 0.1)
		(layer "In9.Cu")
		(net 674)
	)
	(arc
		(start 120.250501 169.191198)
		(mid 120.191922 169.049777)
		(end 120.050501 168.991198)
		(width 0.1)
		(layer "In9.Cu")
		(net 674)
	)
	(arc
		(start 115.450501 169.191198)
		(mid 115.391922 169.049777)
		(end 115.250501 168.991198)
		(width 0.1)
		(layer "In9.Cu")
		(net 674)
	)
	(arc
		(start 118.850501 169.860802)
		(mid 118.70908 169.802223)
		(end 118.650501 169.660802)
		(width 0.1)
		(layer "In9.Cu")
		(net 674)
	)
	(arc
		(start 117.050501 169.191198)
		(mid 116.991922 169.049777)
		(end 116.850501 168.991198)
		(width 0.1)
		(layer "In9.Cu")
		(net 674)
	)
	(arc
		(start 114.050501 169.860802)
		(mid 113.90908 169.802223)
		(end 113.850501 169.660802)
		(width 0.1)
		(layer "In9.Cu")
		(net 674)
	)
	(arc
		(start 113.250501 169.860802)
		(mid 113.10908 169.802223)
		(end 113.050501 169.660802)
		(width 0.1)
		(layer "In9.Cu")
		(net 674)
	)
	(arc
		(start 119.450501 169.191198)
		(mid 119.391922 169.049777)
		(end 119.250501 168.991198)
		(width 0.1)
		(layer "In9.Cu")
		(net 674)
	)
	(arc
		(start 112.850501 168.991198)
		(mid 112.70908 169.049777)
		(end 112.650501 169.191198)
		(width 0.1)
		(layer "In9.Cu")
		(net 674)
	)
	(arc
		(start 115.050501 169.660802)
		(mid 114.991922 169.802223)
		(end 114.850501 169.860802)
		(width 0.1)
		(layer "In9.Cu")
		(net 674)
	)
	(arc
		(start 116.450501 169.860802)
		(mid 116.30908 169.802223)
		(end 116.250501 169.660802)
		(width 0.1)
		(layer "In9.Cu")
		(net 674)
	)
	(arc
		(start 120.050501 168.991198)
		(mid 119.90908 169.049777)
		(end 119.850501 169.191198)
		(width 0.1)
		(layer "In9.Cu")
		(net 674)
	)
	(arc
		(start 114.850501 169.860802)
		(mid 114.70908 169.802223)
		(end 114.650501 169.660802)
		(width 0.1)
		(layer "In9.Cu")
		(net 674)
	)
	(arc
		(start 115.850501 169.660802)
		(mid 115.791922 169.802223)
		(end 115.650501 169.860802)
		(width 0.1)
		(layer "In9.Cu")
		(net 674)
	)
	(arc
		(start 113.650501 168.991198)
		(mid 113.50908 169.049777)
		(end 113.450501 169.191198)
		(width 0.1)
		(layer "In9.Cu")
		(net 674)
	)
	(arc
		(start 119.650501 169.860802)
		(mid 119.50908 169.802223)
		(end 119.450501 169.660802)
		(width 0.1)
		(layer "In9.Cu")
		(net 674)
	)
	(arc
		(start 116.050501 168.991198)
		(mid 115.90908 169.049777)
		(end 115.850501 169.191198)
		(width 0.1)
		(layer "In9.Cu")
		(net 674)
	)
	(arc
		(start 114.250501 169.660802)
		(mid 114.191922 169.802223)
		(end 114.050501 169.860802)
		(width 0.1)
		(layer "In9.Cu")
		(net 674)
	)
	(arc
		(start 119.050501 169.660802)
		(mid 118.991922 169.802223)
		(end 118.850501 169.860802)
		(width 0.1)
		(layer "In9.Cu")
		(net 674)
	)
	(arc
		(start 112.650501 169.226)
		(mid 112.591922 169.367421)
		(end 112.450501 169.426)
		(width 0.1)
		(layer "In9.Cu")
		(net 674)
	)
	(segment
		(start 93.676 161.626)
		(end 96.324054 161.626)
		(width 0.256)
		(layer "F.Cu")
		(net 675)
	)
	(segment
		(start 92.301501 158.285)
		(end 92.301501 160.251501)
		(width 0.256)
		(layer "F.Cu")
		(net 675)
	)
	(segment
		(start 126.376501 170.302)
		(end 125.877001 169.8025)
		(width 0.256)
		(layer "F.Cu")
		(net 675)
	)
	(segment
		(start 96.324054 161.626)
		(end 97.417852 162.719798)
		(width 0.256)
		(layer "F.Cu")
		(net 675)
	)
	(segment
		(start 92.301501 160.251501)
		(end 93.676 161.626)
		(width 0.256)
		(layer "F.Cu")
		(net 675)
	)
	(via
		(at 97.417852 162.719798)
		(size 0.45)
		(drill 0.1)
		(layers "F.Cu" "B.Cu")
		(net 675)
	)
	(via
		(at 125.877001 169.8025)
		(size 0.45)
		(drill 0.1)
		(layers "F.Cu" "B.Cu")
		(net 675)
	)
	(segment
		(start 97.425501 162.061)
		(end 97.425501 163.466)
		(width 0.256)
		(layer "B.Cu")
		(net 675)
	)
	(segment
		(start 104 165.2)
		(end 98.549501 165.2)
		(width 0.1)
		(layer "In9.Cu")
		(net 675)
	)
	(segment
		(start 109.8 171)
		(end 104 165.2)
		(width 0.1)
		(layer "In9.Cu")
		(net 675)
	)
	(segment
		(start 98.549501 165.2)
		(end 97.417852 164.068351)
		(width 0.1)
		(layer "In9.Cu")
		(net 675)
	)
	(segment
		(start 125.877001 169.8025)
		(end 125.875501 169.801)
		(width 0.1)
		(layer "In9.Cu")
		(net 675)
	)
	(segment
		(start 112.424501 171)
		(end 112.424501 171.24105)
		(width 0.1)
		(layer "In9.Cu")
		(net 675)
	)
	(segment
		(start 125.875501 169.801)
		(end 124.999 169.801)
		(width 0.1)
		(layer "In9.Cu")
		(net 675)
	)
	(segment
		(start 114.024501 170.75895)
		(end 114.024501 171)
		(width 0.1)
		(layer "In9.Cu")
		(net 675)
	)
	(segment
		(start 113.624501 171)
		(end 113.624501 170.75895)
		(width 0.1)
		(layer "In9.Cu")
		(net 675)
	)
	(segment
		(start 111.624501 170.75895)
		(end 111.624501 171)
		(width 0.1)
		(layer "In9.Cu")
		(net 675)
	)
	(segment
		(start 115.624501 171)
		(end 115.624501 171.24105)
		(width 0.1)
		(layer "In9.Cu")
		(net 675)
	)
	(segment
		(start 117.224501 171.2)
		(end 117.224501 171.24105)
		(width 0.1)
		(layer "In9.Cu")
		(net 675)
	)
	(segment
		(start 97.417852 164.068351)
		(end 97.417852 162.719798)
		(width 0.1)
		(layer "In9.Cu")
		(net 675)
	)
	(segment
		(start 116.824501 171.24105)
		(end 116.824501 171.2)
		(width 0.1)
		(layer "In9.Cu")
		(net 675)
	)
	(segment
		(start 114.824501 171)
		(end 114.824501 171.24105)
		(width 0.1)
		(layer "In9.Cu")
		(net 675)
	)
	(segment
		(start 116.824501 171.2)
		(end 116.824501 170.75895)
		(width 0.1)
		(layer "In9.Cu")
		(net 675)
	)
	(segment
		(start 114.824501 170.75895)
		(end 114.824501 171)
		(width 0.1)
		(layer "In9.Cu")
		(net 675)
	)
	(segment
		(start 116.424501 171)
		(end 116.424501 171.24105)
		(width 0.1)
		(layer "In9.Cu")
		(net 675)
	)
	(segment
		(start 112.824501 171.24105)
		(end 112.824501 171)
		(width 0.1)
		(layer "In9.Cu")
		(net 675)
	)
	(segment
		(start 113.624501 171.24105)
		(end 113.624501 171)
		(width 0.1)
		(layer "In9.Cu")
		(net 675)
	)
	(segment
		(start 111.024501 171)
		(end 109.8 171)
		(width 0.1)
		(layer "In9.Cu")
		(net 675)
	)
	(segment
		(start 112.424501 170.75895)
		(end 112.424501 171)
		(width 0.1)
		(layer "In9.Cu")
		(net 675)
	)
	(segment
		(start 124.999 169.801)
		(end 123.8 171)
		(width 0.1)
		(layer "In9.Cu")
		(net 675)
	)
	(segment
		(start 112.824501 171)
		(end 112.824501 170.75895)
		(width 0.1)
		(layer "In9.Cu")
		(net 675)
	)
	(segment
		(start 115.224501 171)
		(end 115.224501 170.75895)
		(width 0.1)
		(layer "In9.Cu")
		(net 675)
	)
	(segment
		(start 112.024501 171.24105)
		(end 112.024501 171)
		(width 0.1)
		(layer "In9.Cu")
		(net 675)
	)
	(segment
		(start 112.024501 171)
		(end 112.024501 170.75895)
		(width 0.1)
		(layer "In9.Cu")
		(net 675)
	)
	(segment
		(start 114.424501 171.24105)
		(end 114.424501 171)
		(width 0.1)
		(layer "In9.Cu")
		(net 675)
	)
	(segment
		(start 113.224501 170.75895)
		(end 113.224501 171)
		(width 0.1)
		(layer "In9.Cu")
		(net 675)
	)
	(segment
		(start 113.224501 171)
		(end 113.224501 171.24105)
		(width 0.1)
		(layer "In9.Cu")
		(net 675)
	)
	(segment
		(start 116.024501 171)
		(end 116.024501 170.75895)
		(width 0.1)
		(layer "In9.Cu")
		(net 675)
	)
	(segment
		(start 111.624501 171)
		(end 111.624501 171.24105)
		(width 0.1)
		(layer "In9.Cu")
		(net 675)
	)
	(segment
		(start 115.624501 170.75895)
		(end 115.624501 171)
		(width 0.1)
		(layer "In9.Cu")
		(net 675)
	)
	(segment
		(start 115.224501 171.24105)
		(end 115.224501 171)
		(width 0.1)
		(layer "In9.Cu")
		(net 675)
	)
	(segment
		(start 116.424501 170.75895)
		(end 116.424501 171)
		(width 0.1)
		(layer "In9.Cu")
		(net 675)
	)
	(segment
		(start 114.424501 171)
		(end 114.424501 170.75895)
		(width 0.1)
		(layer "In9.Cu")
		(net 675)
	)
	(segment
		(start 111.224501 171.24105)
		(end 111.224501 171.2)
		(width 0.1)
		(layer "In9.Cu")
		(net 675)
	)
	(segment
		(start 114.024501 171)
		(end 114.024501 171.24105)
		(width 0.1)
		(layer "In9.Cu")
		(net 675)
	)
	(segment
		(start 123.8 171)
		(end 117.424501 171)
		(width 0.1)
		(layer "In9.Cu")
		(net 675)
	)
	(segment
		(start 116.024501 171.24105)
		(end 116.024501 171)
		(width 0.1)
		(layer "In9.Cu")
		(net 675)
	)
	(arc
		(start 111.424501 171.44105)
		(mid 111.28308 171.382471)
		(end 111.224501 171.24105)
		(width 0.1)
		(layer "In9.Cu")
		(net 675)
	)
	(arc
		(start 113.024501 171.44105)
		(mid 112.88308 171.382471)
		(end 112.824501 171.24105)
		(width 0.1)
		(layer "In9.Cu")
		(net 675)
	)
	(arc
		(start 113.424501 170.55895)
		(mid 113.28308 170.617529)
		(end 113.224501 170.75895)
		(width 0.1)
		(layer "In9.Cu")
		(net 675)
	)
	(arc
		(start 114.424501 170.75895)
		(mid 114.365922 170.617529)
		(end 114.224501 170.55895)
		(width 0.1)
		(layer "In9.Cu")
		(net 675)
	)
	(arc
		(start 115.624501 171.24105)
		(mid 115.565922 171.382471)
		(end 115.424501 171.44105)
		(width 0.1)
		(layer "In9.Cu")
		(net 675)
	)
	(arc
		(start 114.224501 170.55895)
		(mid 114.08308 170.617529)
		(end 114.024501 170.75895)
		(width 0.1)
		(layer "In9.Cu")
		(net 675)
	)
	(arc
		(start 112.424501 171.24105)
		(mid 112.365922 171.382471)
		(end 112.224501 171.44105)
		(width 0.1)
		(layer "In9.Cu")
		(net 675)
	)
	(arc
		(start 111.224501 171.2)
		(mid 111.165922 171.058579)
		(end 111.024501 171)
		(width 0.1)
		(layer "In9.Cu")
		(net 675)
	)
	(arc
		(start 115.424501 171.44105)
		(mid 115.28308 171.382471)
		(end 115.224501 171.24105)
		(width 0.1)
		(layer "In9.Cu")
		(net 675)
	)
	(arc
		(start 114.624501 171.44105)
		(mid 114.48308 171.382471)
		(end 114.424501 171.24105)
		(width 0.1)
		(layer "In9.Cu")
		(net 675)
	)
	(arc
		(start 117.224501 171.24105)
		(mid 117.165922 171.382471)
		(end 117.024501 171.44105)
		(width 0.1)
		(layer "In9.Cu")
		(net 675)
	)
	(arc
		(start 116.824501 170.75895)
		(mid 116.765922 170.617529)
		(end 116.624501 170.55895)
		(width 0.1)
		(layer "In9.Cu")
		(net 675)
	)
	(arc
		(start 115.224501 170.75895)
		(mid 115.165922 170.617529)
		(end 115.024501 170.55895)
		(width 0.1)
		(layer "In9.Cu")
		(net 675)
	)
	(arc
		(start 114.024501 171.24105)
		(mid 113.965922 171.382471)
		(end 113.824501 171.44105)
		(width 0.1)
		(layer "In9.Cu")
		(net 675)
	)
	(arc
		(start 113.224501 171.24105)
		(mid 113.165922 171.382471)
		(end 113.024501 171.44105)
		(width 0.1)
		(layer "In9.Cu")
		(net 675)
	)
	(arc
		(start 111.824501 170.55895)
		(mid 111.68308 170.617529)
		(end 111.624501 170.75895)
		(width 0.1)
		(layer "In9.Cu")
		(net 675)
	)
	(arc
		(start 113.624501 170.75895)
		(mid 113.565922 170.617529)
		(end 113.424501 170.55895)
		(width 0.1)
		(layer "In9.Cu")
		(net 675)
	)
	(arc
		(start 115.824501 170.55895)
		(mid 115.68308 170.617529)
		(end 115.624501 170.75895)
		(width 0.1)
		(layer "In9.Cu")
		(net 675)
	)
	(arc
		(start 116.424501 171.24105)
		(mid 116.365922 171.382471)
		(end 116.224501 171.44105)
		(width 0.1)
		(layer "In9.Cu")
		(net 675)
	)
	(arc
		(start 117.424501 171)
		(mid 117.28308 171.058579)
		(end 117.224501 171.2)
		(width 0.1)
		(layer "In9.Cu")
		(net 675)
	)
	(arc
		(start 115.024501 170.55895)
		(mid 114.88308 170.617529)
		(end 114.824501 170.75895)
		(width 0.1)
		(layer "In9.Cu")
		(net 675)
	)
	(arc
		(start 111.624501 171.24105)
		(mid 111.565922 171.382471)
		(end 111.424501 171.44105)
		(width 0.1)
		(layer "In9.Cu")
		(net 675)
	)
	(arc
		(start 113.824501 171.44105)
		(mid 113.68308 171.382471)
		(end 113.624501 171.24105)
		(width 0.1)
		(layer "In9.Cu")
		(net 675)
	)
	(arc
		(start 112.024501 170.75895)
		(mid 111.965922 170.617529)
		(end 111.824501 170.55895)
		(width 0.1)
		(layer "In9.Cu")
		(net 675)
	)
	(arc
		(start 116.024501 170.75895)
		(mid 115.965922 170.617529)
		(end 115.824501 170.55895)
		(width 0.1)
		(layer "In9.Cu")
		(net 675)
	)
	(arc
		(start 112.624501 170.55895)
		(mid 112.48308 170.617529)
		(end 112.424501 170.75895)
		(width 0.1)
		(layer "In9.Cu")
		(net 675)
	)
	(arc
		(start 116.224501 171.44105)
		(mid 116.08308 171.382471)
		(end 116.024501 171.24105)
		(width 0.1)
		(layer "In9.Cu")
		(net 675)
	)
	(arc
		(start 116.624501 170.55895)
		(mid 116.48308 170.617529)
		(end 116.424501 170.75895)
		(width 0.1)
		(layer "In9.Cu")
		(net 675)
	)
	(arc
		(start 117.024501 171.44105)
		(mid 116.88308 171.382471)
		(end 116.824501 171.24105)
		(width 0.1)
		(layer "In9.Cu")
		(net 675)
	)
	(arc
		(start 114.824501 171.24105)
		(mid 114.765922 171.382471)
		(end 114.624501 171.44105)
		(width 0.1)
		(layer "In9.Cu")
		(net 675)
	)
	(arc
		(start 112.224501 171.44105)
		(mid 112.08308 171.382471)
		(end 112.024501 171.24105)
		(width 0.1)
		(layer "In9.Cu")
		(net 675)
	)
	(arc
		(start 112.824501 170.75895)
		(mid 112.765922 170.617529)
		(end 112.624501 170.55895)
		(width 0.1)
		(layer "In9.Cu")
		(net 675)
	)
	(segment
		(start 91.801501 160.901501)
		(end 93.126 162.226)
		(width 0.256)
		(layer "F.Cu")
		(net 676)
	)
	(segment
		(start 127.376501 171.302)
		(end 126.877001 170.8025)
		(width 0.256)
		(layer "F.Cu")
		(net 676)
	)
	(segment
		(start 91.801501 158.285)
		(end 91.801501 160.901501)
		(width 0.256)
		(layer "F.Cu")
		(net 676)
	)
	(segment
		(start 93.126 162.226)
		(end 95.800501 162.226)
		(width 0.256)
		(layer "F.Cu")
		(net 676)
	)
	(segment
		(start 95.800501 162.226)
		(end 96.350501 162.776)
		(width 0.256)
		(layer "F.Cu")
		(net 676)
	)
	(via
		(at 96.350501 162.776)
		(size 0.45)
		(drill 0.1)
		(layers "F.Cu" "B.Cu")
		(net 676)
	)
	(via
		(at 126.877001 170.8025)
		(size 0.45)
		(drill 0.1)
		(layers "F.Cu" "B.Cu")
		(net 676)
	)
	(segment
		(start 96.375501 162.061)
		(end 96.375501 163.466)
		(width 0.256)
		(layer "B.Cu")
		(net 676)
	)
	(segment
		(start 117.976501 172.042668)
		(end 117.976501 172)
		(width 0.1)
		(layer "In9.Cu")
		(net 676)
	)
	(segment
		(start 118.776501 172.042668)
		(end 118.776501 171.557332)
		(width 0.1)
		(layer "In9.Cu")
		(net 676)
	)
	(segment
		(start 120.776501 171.557332)
		(end 120.776501 172.042668)
		(width 0.1)
		(layer "In9.Cu")
		(net 676)
	)
	(segment
		(start 103.424501 165.5)
		(end 97.874501 165.5)
		(width 0.1)
		(layer "In9.Cu")
		(net 676)
	)
	(segment
		(start 118.376501 171.557332)
		(end 118.376501 172.042668)
		(width 0.1)
		(layer "In9.Cu")
		(net 676)
	)
	(segment
		(start 123.176501 172)
		(end 123.176501 172.042668)
		(width 0.1)
		(layer "In9.Cu")
		(net 676)
	)
	(segment
		(start 120.376501 172.042668)
		(end 120.376501 171.557332)
		(width 0.1)
		(layer "In9.Cu")
		(net 676)
	)
	(segment
		(start 119.176501 171.557332)
		(end 119.176501 172.042668)
		(width 0.1)
		(layer "In9.Cu")
		(net 676)
	)
	(segment
		(start 126.400501 170.326)
		(end 125.374 170.326)
		(width 0.1)
		(layer "In9.Cu")
		(net 676)
	)
	(segment
		(start 121.176501 172.042668)
		(end 121.176501 171.557332)
		(width 0.1)
		(layer "In9.Cu")
		(net 676)
	)
	(segment
		(start 121.976501 172.042668)
		(end 121.976501 171.557332)
		(width 0.1)
		(layer "In9.Cu")
		(net 676)
	)
	(segment
		(start 122.376501 171.557332)
		(end 122.376501 172.042668)
		(width 0.1)
		(layer "In9.Cu")
		(net 676)
	)
	(segment
		(start 125.374 170.326)
		(end 123.9 171.8)
		(width 0.1)
		(layer "In9.Cu")
		(net 676)
	)
	(segment
		(start 122.776501 172.042668)
		(end 122.776501 171.557332)
		(width 0.1)
		(layer "In9.Cu")
		(net 676)
	)
	(segment
		(start 96.350501 163.976)
		(end 96.350501 162.776)
		(width 0.1)
		(layer "In9.Cu")
		(net 676)
	)
	(segment
		(start 123.9 171.8)
		(end 123.376501 171.8)
		(width 0.1)
		(layer "In9.Cu")
		(net 676)
	)
	(segment
		(start 119.976501 171.557332)
		(end 119.976501 172.042668)
		(width 0.1)
		(layer "In9.Cu")
		(net 676)
	)
	(segment
		(start 126.877001 170.8025)
		(end 126.400501 170.326)
		(width 0.1)
		(layer "In9.Cu")
		(net 676)
	)
	(segment
		(start 109.724501 171.8)
		(end 103.424501 165.5)
		(width 0.1)
		(layer "In9.Cu")
		(net 676)
	)
	(segment
		(start 117.776501 171.8)
		(end 109.724501 171.8)
		(width 0.1)
		(layer "In9.Cu")
		(net 676)
	)
	(segment
		(start 119.576501 172.042668)
		(end 119.576501 171.557332)
		(width 0.1)
		(layer "In9.Cu")
		(net 676)
	)
	(segment
		(start 121.576501 171.557332)
		(end 121.576501 172.042668)
		(width 0.1)
		(layer "In9.Cu")
		(net 676)
	)
	(segment
		(start 97.874501 165.5)
		(end 96.350501 163.976)
		(width 0.1)
		(layer "In9.Cu")
		(net 676)
	)
	(arc
		(start 119.376501 171.357332)
		(mid 119.23508 171.415911)
		(end 119.176501 171.557332)
		(width 0.1)
		(layer "In9.Cu")
		(net 676)
	)
	(arc
		(start 120.576501 172.242668)
		(mid 120.43508 172.184089)
		(end 120.376501 172.042668)
		(width 0.1)
		(layer "In9.Cu")
		(net 676)
	)
	(arc
		(start 122.176501 172.242668)
		(mid 122.03508 172.184089)
		(end 121.976501 172.042668)
		(width 0.1)
		(layer "In9.Cu")
		(net 676)
	)
	(arc
		(start 123.176501 172.042668)
		(mid 123.117922 172.184089)
		(end 122.976501 172.242668)
		(width 0.1)
		(layer "In9.Cu")
		(net 676)
	)
	(arc
		(start 118.976501 172.242668)
		(mid 118.83508 172.184089)
		(end 118.776501 172.042668)
		(width 0.1)
		(layer "In9.Cu")
		(net 676)
	)
	(arc
		(start 120.176501 171.357332)
		(mid 120.03508 171.415911)
		(end 119.976501 171.557332)
		(width 0.1)
		(layer "In9.Cu")
		(net 676)
	)
	(arc
		(start 119.176501 172.042668)
		(mid 119.117922 172.184089)
		(end 118.976501 172.242668)
		(width 0.1)
		(layer "In9.Cu")
		(net 676)
	)
	(arc
		(start 118.776501 171.557332)
		(mid 118.717922 171.415911)
		(end 118.576501 171.357332)
		(width 0.1)
		(layer "In9.Cu")
		(net 676)
	)
	(arc
		(start 117.976501 172)
		(mid 117.917922 171.858579)
		(end 117.776501 171.8)
		(width 0.1)
		(layer "In9.Cu")
		(net 676)
	)
	(arc
		(start 122.576501 171.357332)
		(mid 122.43508 171.415911)
		(end 122.376501 171.557332)
		(width 0.1)
		(layer "In9.Cu")
		(net 676)
	)
	(arc
		(start 119.976501 172.042668)
		(mid 119.917922 172.184089)
		(end 119.776501 172.242668)
		(width 0.1)
		(layer "In9.Cu")
		(net 676)
	)
	(arc
		(start 118.576501 171.357332)
		(mid 118.43508 171.415911)
		(end 118.376501 171.557332)
		(width 0.1)
		(layer "In9.Cu")
		(net 676)
	)
	(arc
		(start 120.376501 171.557332)
		(mid 120.317922 171.415911)
		(end 120.176501 171.357332)
		(width 0.1)
		(layer "In9.Cu")
		(net 676)
	)
	(arc
		(start 119.576501 171.557332)
		(mid 119.517922 171.415911)
		(end 119.376501 171.357332)
		(width 0.1)
		(layer "In9.Cu")
		(net 676)
	)
	(arc
		(start 122.976501 172.242668)
		(mid 122.83508 172.184089)
		(end 122.776501 172.042668)
		(width 0.1)
		(layer "In9.Cu")
		(net 676)
	)
	(arc
		(start 120.776501 172.042668)
		(mid 120.717922 172.184089)
		(end 120.576501 172.242668)
		(width 0.1)
		(layer "In9.Cu")
		(net 676)
	)
	(arc
		(start 119.776501 172.242668)
		(mid 119.63508 172.184089)
		(end 119.576501 172.042668)
		(width 0.1)
		(layer "In9.Cu")
		(net 676)
	)
	(arc
		(start 121.176501 171.557332)
		(mid 121.117922 171.415911)
		(end 120.976501 171.357332)
		(width 0.1)
		(layer "In9.Cu")
		(net 676)
	)
	(arc
		(start 122.376501 172.042668)
		(mid 122.317922 172.184089)
		(end 122.176501 172.242668)
		(width 0.1)
		(layer "In9.Cu")
		(net 676)
	)
	(arc
		(start 118.376501 172.042668)
		(mid 118.317922 172.184089)
		(end 118.176501 172.242668)
		(width 0.1)
		(layer "In9.Cu")
		(net 676)
	)
	(arc
		(start 121.576501 172.042668)
		(mid 121.517922 172.184089)
		(end 121.376501 172.242668)
		(width 0.1)
		(layer "In9.Cu")
		(net 676)
	)
	(arc
		(start 123.376501 171.8)
		(mid 123.23508 171.858579)
		(end 123.176501 172)
		(width 0.1)
		(layer "In9.Cu")
		(net 676)
	)
	(arc
		(start 120.976501 171.357332)
		(mid 120.83508 171.415911)
		(end 120.776501 171.557332)
		(width 0.1)
		(layer "In9.Cu")
		(net 676)
	)
	(arc
		(start 121.776501 171.357332)
		(mid 121.63508 171.415911)
		(end 121.576501 171.557332)
		(width 0.1)
		(layer "In9.Cu")
		(net 676)
	)
	(arc
		(start 121.976501 171.557332)
		(mid 121.917922 171.415911)
		(end 121.776501 171.357332)
		(width 0.1)
		(layer "In9.Cu")
		(net 676)
	)
	(arc
		(start 122.776501 171.557332)
		(mid 122.717922 171.415911)
		(end 122.576501 171.357332)
		(width 0.1)
		(layer "In9.Cu")
		(net 676)
	)
	(arc
		(start 121.376501 172.242668)
		(mid 121.23508 172.184089)
		(end 121.176501 172.042668)
		(width 0.1)
		(layer "In9.Cu")
		(net 676)
	)
	(arc
		(start 118.176501 172.242668)
		(mid 118.03508 172.184089)
		(end 117.976501 172.042668)
		(width 0.1)
		(layer "In9.Cu")
		(net 676)
	)
	(segment
		(start 127.376501 168.302)
		(end 126.877001 167.8025)
		(width 0.256)
		(layer "F.Cu")
		(net 677)
	)
	(segment
		(start 94.800501 159.601)
		(end 95.225501 160.026)
		(width 0.256)
		(layer "F.Cu")
		(net 677)
	)
	(segment
		(start 95.225501 160.026)
		(end 98.075501 160.026)
		(width 0.256)
		(layer "F.Cu")
		(net 677)
	)
	(segment
		(start 101.600501 162.729)
		(end 101.600501 162.726)
		(width 0.256)
		(layer "F.Cu")
		(net 677)
	)
	(segment
		(start 100.000501 161.951)
		(end 100.000501 163.126)
		(width 0.256)
		(layer "F.Cu")
		(net 677)
	)
	(segment
		(start 98.075501 160.026)
		(end 100.000501 161.951)
		(width 0.256)
		(layer "F.Cu")
		(net 677)
	)
	(segment
		(start 100.000501 163.126)
		(end 100.225501 163.351)
		(width 0.256)
		(layer "F.Cu")
		(net 677)
	)
	(segment
		(start 94.800501 158.285)
		(end 94.800501 159.601)
		(width 0.256)
		(layer "F.Cu")
		(net 677)
	)
	(segment
		(start 100.225501 163.351)
		(end 100.978501 163.351)
		(width 0.256)
		(layer "F.Cu")
		(net 677)
	)
	(segment
		(start 100.978501 163.351)
		(end 101.600501 162.729)
		(width 0.256)
		(layer "F.Cu")
		(net 677)
	)
	(via
		(at 126.877001 167.8025)
		(size 0.45)
		(drill 0.1)
		(layers "F.Cu" "B.Cu")
		(net 677)
	)
	(via
		(at 101.600501 162.726)
		(size 0.45)
		(drill 0.1)
		(layers "F.Cu" "B.Cu")
		(net 677)
	)
	(segment
		(start 101.625501 163.466)
		(end 101.625501 162.086)
		(width 0.256)
		(layer "B.Cu")
		(net 677)
	)
	(segment
		(start 112.707242 162.811891)
		(end 112.236392 163.282742)
		(width 0.1)
		(layer "In9.Cu")
		(net 677)
	)
	(segment
		(start 114.969982 165.074631)
		(end 114.875979 165.168635)
		(width 0.1)
		(layer "In9.Cu")
		(net 677)
	)
	(segment
		(start 113.933447 165.262639)
		(end 113.933447 165.26264)
		(width 0.1)
		(layer "In9.Cu")
		(net 677)
	)
	(segment
		(start 110.224501 160.8)
		(end 110.350501 160.926)
		(width 0.1)
		(layer "In9.Cu")
		(net 677)
	)
	(segment
		(start 111.010189 161.114839)
		(end 111.01019 161.114838)
		(width 0.1)
		(layer "In9.Cu")
		(net 677)
	)
	(segment
		(start 101.600501 162.726)
		(end 101.600501 162.699499)
		(width 0.1)
		(layer "In9.Cu")
		(net 677)
	)
	(segment
		(start 123.3775 167.3775)
		(end 126.452001 167.3775)
		(width 0.1)
		(layer "In9.Cu")
		(net 677)
	)
	(segment
		(start 111.387865 162.434214)
		(end 111.387864 162.434215)
		(width 0.1)
		(layer "In9.Cu")
		(net 677)
	)
	(segment
		(start 111.953549 162.9999)
		(end 112.424399 162.529047)
		(width 0.1)
		(layer "In9.Cu")
		(net 677)
	)
	(segment
		(start 111.575873 161.397679)
		(end 111.575873 161.397678)
		(width 0.1)
		(layer "In9.Cu")
		(net 677)
	)
	(segment
		(start 110.822179 161.86853)
		(end 111.293029 161.397677)
		(width 0.1)
		(layer "In9.Cu")
		(net 677)
	)
	(segment
		(start 114.216289 165.26264)
		(end 114.687139 164.791787)
		(width 0.1)
		(layer "In9.Cu")
		(net 677)
	)
	(segment
		(start 113.272927 163.377576)
		(end 112.802077 163.848427)
		(width 0.1)
		(layer "In9.Cu")
		(net 677)
	)
	(segment
		(start 113.650604 164.696955)
		(end 114.121454 164.226102)
		(width 0.1)
		(layer "In9.Cu")
		(net 677)
	)
	(segment
		(start 113.838613 163.660419)
		(end 113.838613 163.660418)
		(width 0.1)
		(layer "In9.Cu")
		(net 677)
	)
	(segment
		(start 110.82218 161.868529)
		(end 110.822179 161.86853)
		(width 0.1)
		(layer "In9.Cu")
		(net 677)
	)
	(segment
		(start 115.550502 166.126)
		(end 122.126 166.126)
		(width 0.1)
		(layer "In9.Cu")
		(net 677)
	)
	(segment
		(start 111.01019 161.114838)
		(end 110.539337 161.585687)
		(width 0.1)
		(layer "In9.Cu")
		(net 677)
	)
	(segment
		(start 103.5 160.8)
		(end 110.224501 160.8)
		(width 0.1)
		(layer "In9.Cu")
		(net 677)
	)
	(segment
		(start 114.969983 164.791789)
		(end 114.969983 164.791788)
		(width 0.1)
		(layer "In9.Cu")
		(net 677)
	)
	(segment
		(start 114.87598 165.451478)
		(end 115.550502 166.126)
		(width 0.1)
		(layer "In9.Cu")
		(net 677)
	)
	(segment
		(start 112.802077 164.131269)
		(end 112.802077 164.13127)
		(width 0.1)
		(layer "In9.Cu")
		(net 677)
	)
	(segment
		(start 122.126 166.126)
		(end 123.3775 167.3775)
		(width 0.1)
		(layer "In9.Cu")
		(net 677)
	)
	(segment
		(start 113.084919 164.13127)
		(end 113.555769 163.660417)
		(width 0.1)
		(layer "In9.Cu")
		(net 677)
	)
	(segment
		(start 113.650605 164.696954)
		(end 113.650604 164.696955)
		(width 0.1)
		(layer "In9.Cu")
		(net 677)
	)
	(segment
		(start 114.404298 164.226104)
		(end 114.404298 164.226103)
		(width 0.1)
		(layer "In9.Cu")
		(net 677)
	)
	(segment
		(start 111.575872 161.680521)
		(end 111.105022 162.151372)
		(width 0.1)
		(layer "In9.Cu")
		(net 677)
	)
	(segment
		(start 111.95355 162.999899)
		(end 111.953549 162.9999)
		(width 0.1)
		(layer "In9.Cu")
		(net 677)
	)
	(segment
		(start 111.010191 160.831997)
		(end 111.01019 160.831996)
		(width 0.1)
		(layer "In9.Cu")
		(net 677)
	)
	(segment
		(start 114.404297 164.508946)
		(end 113.933447 164.979797)
		(width 0.1)
		(layer "In9.Cu")
		(net 677)
	)
	(segment
		(start 113.272928 163.094734)
		(end 113.272928 163.094733)
		(width 0.1)
		(layer "In9.Cu")
		(net 677)
	)
	(segment
		(start 112.141557 162.246206)
		(end 111.670707 162.717057)
		(width 0.1)
		(layer "In9.Cu")
		(net 677)
	)
	(segment
		(start 112.707243 162.529049)
		(end 112.707243 162.529048)
		(width 0.1)
		(layer "In9.Cu")
		(net 677)
	)
	(segment
		(start 112.141558 161.963364)
		(end 112.141558 161.963363)
		(width 0.1)
		(layer "In9.Cu")
		(net 677)
	)
	(segment
		(start 113.08492 164.131269)
		(end 113.084919 164.13127)
		(width 0.1)
		(layer "In9.Cu")
		(net 677)
	)
	(segment
		(start 112.236392 163.565584)
		(end 112.236392 163.565585)
		(width 0.1)
		(layer "In9.Cu")
		(net 677)
	)
	(segment
		(start 112.519235 163.565584)
		(end 112.519234 163.565585)
		(width 0.1)
		(layer "In9.Cu")
		(net 677)
	)
	(segment
		(start 113.838612 163.943261)
		(end 113.367762 164.414112)
		(width 0.1)
		(layer "In9.Cu")
		(net 677)
	)
	(segment
		(start 112.519234 163.565585)
		(end 112.990084 163.094732)
		(width 0.1)
		(layer "In9.Cu")
		(net 677)
	)
	(segment
		(start 111.670707 162.999899)
		(end 111.670707 162.9999)
		(width 0.1)
		(layer "In9.Cu")
		(net 677)
	)
	(segment
		(start 110.539337 161.868529)
		(end 110.539337 161.86853)
		(width 0.1)
		(layer "In9.Cu")
		(net 677)
	)
	(segment
		(start 114.21629 165.262639)
		(end 114.216289 165.26264)
		(width 0.1)
		(layer "In9.Cu")
		(net 677)
	)
	(segment
		(start 111.105022 162.434214)
		(end 111.105022 162.434215)
		(width 0.1)
		(layer "In9.Cu")
		(net 677)
	)
	(segment
		(start 101.600501 162.699499)
		(end 103.5 160.8)
		(width 0.1)
		(layer "In9.Cu")
		(net 677)
	)
	(segment
		(start 111.387864 162.434215)
		(end 111.858714 161.963362)
		(width 0.1)
		(layer "In9.Cu")
		(net 677)
	)
	(segment
		(start 126.452001 167.3775)
		(end 126.877001 167.8025)
		(width 0.1)
		(layer "In9.Cu")
		(net 677)
	)
	(segment
		(start 113.367762 164.696954)
		(end 113.367762 164.696955)
		(width 0.1)
		(layer "In9.Cu")
		(net 677)
	)
	(segment
		(start 110.633344 160.925999)
		(end 110.727348 160.831996)
		(width 0.1)
		(layer "In9.Cu")
		(net 677)
	)
	(arc
		(start 114.875979 165.168635)
		(mid 114.817401 165.310057)
		(end 114.87598 165.451478)
		(width 0.1)
		(layer "In9.Cu")
		(net 677)
	)
	(arc
		(start 110.539337 161.585687)
		(mid 110.480759 161.727108)
		(end 110.539337 161.868529)
		(width 0.1)
		(layer "In9.Cu")
		(net 677)
	)
	(arc
		(start 112.802077 163.848427)
		(mid 112.743499 163.989848)
		(end 112.802077 164.131269)
		(width 0.1)
		(layer "In9.Cu")
		(net 677)
	)
	(arc
		(start 111.105022 162.434215)
		(mid 111.246444 162.492793)
		(end 111.387865 162.434214)
		(width 0.1)
		(layer "In9.Cu")
		(net 677)
	)
	(arc
		(start 110.350501 160.926)
		(mid 110.491923 160.984578)
		(end 110.633344 160.925999)
		(width 0.1)
		(layer "In9.Cu")
		(net 677)
	)
	(arc
		(start 111.670707 162.717057)
		(mid 111.612129 162.858478)
		(end 111.670707 162.999899)
		(width 0.1)
		(layer "In9.Cu")
		(net 677)
	)
	(arc
		(start 112.424399 162.529047)
		(mid 112.565821 162.47047)
		(end 112.707243 162.529049)
		(width 0.1)
		(layer "In9.Cu")
		(net 677)
	)
	(arc
		(start 112.707243 162.529048)
		(mid 112.765821 162.67047)
		(end 112.707242 162.811891)
		(width 0.1)
		(layer "In9.Cu")
		(net 677)
	)
	(arc
		(start 112.802077 164.13127)
		(mid 112.943499 164.189848)
		(end 113.08492 164.131269)
		(width 0.1)
		(layer "In9.Cu")
		(net 677)
	)
	(arc
		(start 113.272928 163.094733)
		(mid 113.331506 163.236155)
		(end 113.272927 163.377576)
		(width 0.1)
		(layer "In9.Cu")
		(net 677)
	)
	(arc
		(start 111.105022 162.151372)
		(mid 111.046444 162.292793)
		(end 111.105022 162.434214)
		(width 0.1)
		(layer "In9.Cu")
		(net 677)
	)
	(arc
		(start 110.727348 160.831996)
		(mid 110.86877 160.773418)
		(end 111.010191 160.831997)
		(width 0.1)
		(layer "In9.Cu")
		(net 677)
	)
	(arc
		(start 114.687139 164.791787)
		(mid 114.828561 164.73321)
		(end 114.969983 164.791789)
		(width 0.1)
		(layer "In9.Cu")
		(net 677)
	)
	(arc
		(start 113.555769 163.660417)
		(mid 113.697191 163.60184)
		(end 113.838613 163.660419)
		(width 0.1)
		(layer "In9.Cu")
		(net 677)
	)
	(arc
		(start 113.933447 165.26264)
		(mid 114.074869 165.321218)
		(end 114.21629 165.262639)
		(width 0.1)
		(layer "In9.Cu")
		(net 677)
	)
	(arc
		(start 113.933447 164.979797)
		(mid 113.874869 165.121218)
		(end 113.933447 165.262639)
		(width 0.1)
		(layer "In9.Cu")
		(net 677)
	)
	(arc
		(start 112.141558 161.963363)
		(mid 112.200136 162.104785)
		(end 112.141557 162.246206)
		(width 0.1)
		(layer "In9.Cu")
		(net 677)
	)
	(arc
		(start 111.575873 161.397678)
		(mid 111.634451 161.5391)
		(end 111.575872 161.680521)
		(width 0.1)
		(layer "In9.Cu")
		(net 677)
	)
	(arc
		(start 113.838613 163.660418)
		(mid 113.897191 163.80184)
		(end 113.838612 163.943261)
		(width 0.1)
		(layer "In9.Cu")
		(net 677)
	)
	(arc
		(start 112.236392 163.282742)
		(mid 112.177814 163.424163)
		(end 112.236392 163.565584)
		(width 0.1)
		(layer "In9.Cu")
		(net 677)
	)
	(arc
		(start 111.293029 161.397677)
		(mid 111.434451 161.3391)
		(end 111.575873 161.397679)
		(width 0.1)
		(layer "In9.Cu")
		(net 677)
	)
	(arc
		(start 110.539337 161.86853)
		(mid 110.680759 161.927108)
		(end 110.82218 161.868529)
		(width 0.1)
		(layer "In9.Cu")
		(net 677)
	)
	(arc
		(start 112.236392 163.565585)
		(mid 112.377814 163.624163)
		(end 112.519235 163.565584)
		(width 0.1)
		(layer "In9.Cu")
		(net 677)
	)
	(arc
		(start 113.367762 164.696955)
		(mid 113.509184 164.755533)
		(end 113.650605 164.696954)
		(width 0.1)
		(layer "In9.Cu")
		(net 677)
	)
	(arc
		(start 114.404298 164.226103)
		(mid 114.462876 164.367525)
		(end 114.404297 164.508946)
		(width 0.1)
		(layer "In9.Cu")
		(net 677)
	)
	(arc
		(start 111.670707 162.9999)
		(mid 111.812129 163.058478)
		(end 111.95355 162.999899)
		(width 0.1)
		(layer "In9.Cu")
		(net 677)
	)
	(arc
		(start 114.969983 164.791788)
		(mid 115.028561 164.93321)
		(end 114.969982 165.074631)
		(width 0.1)
		(layer "In9.Cu")
		(net 677)
	)
	(arc
		(start 111.01019 160.831996)
		(mid 111.068768 160.973418)
		(end 111.010189 161.114839)
		(width 0.1)
		(layer "In9.Cu")
		(net 677)
	)
	(arc
		(start 111.858714 161.963362)
		(mid 112.000136 161.904785)
		(end 112.141558 161.963364)
		(width 0.1)
		(layer "In9.Cu")
		(net 677)
	)
	(arc
		(start 112.990084 163.094732)
		(mid 113.131506 163.036155)
		(end 113.272928 163.094734)
		(width 0.1)
		(layer "In9.Cu")
		(net 677)
	)
	(arc
		(start 113.367762 164.414112)
		(mid 113.309184 164.555533)
		(end 113.367762 164.696954)
		(width 0.1)
		(layer "In9.Cu")
		(net 677)
	)
	(arc
		(start 114.121454 164.226102)
		(mid 114.262876 164.167525)
		(end 114.404298 164.226104)
		(width 0.1)
		(layer "In9.Cu")
		(net 677)
	)
	(segment
		(start 95.800501 158.285)
		(end 95.800501 159.351)
		(width 0.256)
		(layer "F.Cu")
		(net 678)
	)
	(segment
		(start 99.000501 159.601)
		(end 100.500501 161.101)
		(width 0.256)
		(layer "F.Cu")
		(net 678)
	)
	(segment
		(start 96.050501 159.601)
		(end 99.000501 159.601)
		(width 0.256)
		(layer "F.Cu")
		(net 678)
	)
	(segment
		(start 100.500501 161.101)
		(end 100.500501 162.751)
		(width 0.256)
		(layer "F.Cu")
		(net 678)
	)
	(segment
		(start 129.376501 168.302)
		(end 128.877001 167.802499)
		(width 0.256)
		(layer "F.Cu")
		(net 678)
	)
	(segment
		(start 95.800501 159.351)
		(end 96.050501 159.601)
		(width 0.256)
		(layer "F.Cu")
		(net 678)
	)
	(via
		(at 128.877001 167.802499)
		(size 0.45)
		(drill 0.1)
		(layers "F.Cu" "B.Cu")
		(net 678)
	)
	(via
		(at 100.500501 162.751)
		(size 0.45)
		(drill 0.1)
		(layers "F.Cu" "B.Cu")
		(net 678)
	)
	(segment
		(start 100.550501 162.086)
		(end 100.525501 162.061)
		(width 0.256)
		(layer "B.Cu")
		(net 678)
	)
	(segment
		(start 100.550501 163.466)
		(end 100.550501 162.086)
		(width 0.256)
		(layer "B.Cu")
		(net 678)
	)
	(segment
		(start 109.857068 162.767959)
		(end 109.857069 162.767958)
		(width 0.1)
		(layer "In9.Cu")
		(net 678)
	)
	(segment
		(start 113.251179 166.162068)
		(end 113.25118 166.162067)
		(width 0.1)
		(layer "In9.Cu")
		(net 678)
	)
	(segment
		(start 103.476501 162.4)
		(end 108.924501 162.4)
		(width 0.1)
		(layer "In9.Cu")
		(net 678)
	)
	(segment
		(start 100.500501 162.751)
		(end 100.500501 163.126)
		(width 0.1)
		(layer "In9.Cu")
		(net 678)
	)
	(segment
		(start 109.575301 163.615412)
		(end 110.139911 163.050799)
		(width 0.1)
		(layer "In9.Cu")
		(net 678)
	)
	(segment
		(start 102.330501 163.546)
		(end 103.476501 162.4)
		(width 0.1)
		(layer "In9.Cu")
		(net 678)
	)
	(segment
		(start 100.920501 163.546)
		(end 102.330501 163.546)
		(width 0.1)
		(layer "In9.Cu")
		(net 678)
	)
	(segment
		(start 110.140987 164.181096)
		(end 110.140986 164.181097)
		(width 0.1)
		(layer "In9.Cu")
		(net 678)
	)
	(segment
		(start 113.25118 166.162067)
		(end 112.686569 166.726679)
		(width 0.1)
		(layer "In9.Cu")
		(net 678)
	)
	(segment
		(start 111.5552 165.878152)
		(end 111.555199 165.878152)
		(width 0.1)
		(layer "In9.Cu")
		(net 678)
	)
	(segment
		(start 109.433343 162.626)
		(end 109.574227 162.485117)
		(width 0.1)
		(layer "In9.Cu")
		(net 678)
	)
	(segment
		(start 111.272357 165.312466)
		(end 111.272356 165.312467)
		(width 0.1)
		(layer "In9.Cu")
		(net 678)
	)
	(segment
		(start 109.858145 164.181097)
		(end 109.858144 164.181097)
		(width 0.1)
		(layer "In9.Cu")
		(net 678)
	)
	(segment
		(start 109.575302 163.615411)
		(end 109.575301 163.615412)
		(width 0.1)
		(layer "In9.Cu")
		(net 678)
	)
	(segment
		(start 111.554124 164.465013)
		(end 111.554125 164.465012)
		(width 0.1)
		(layer "In9.Cu")
		(net 678)
	)
	(segment
		(start 112.68657 167.009522)
		(end 112.686569 167.009522)
		(width 0.1)
		(layer "In9.Cu")
		(net 678)
	)
	(segment
		(start 110.422754 163.333643)
		(end 110.422755 163.333642)
		(width 0.1)
		(layer "In9.Cu")
		(net 678)
	)
	(segment
		(start 110.988441 163.616487)
		(end 110.98844 163.616485)
		(width 0.1)
		(layer "In9.Cu")
		(net 678)
	)
	(segment
		(start 122.394658 168.1775)
		(end 128.502 168.1775)
		(width 0.1)
		(layer "In9.Cu")
		(net 678)
	)
	(segment
		(start 113.393137 166.868637)
		(end 113.393137 166.868638)
		(width 0.1)
		(layer "In9.Cu")
		(net 678)
	)
	(segment
		(start 113.393137 166.868638)
		(end 113.624501 167.1)
		(width 0.1)
		(layer "In9.Cu")
		(net 678)
	)
	(segment
		(start 112.969411 167.009522)
		(end 113.110294 166.868638)
		(width 0.1)
		(layer "In9.Cu")
		(net 678)
	)
	(segment
		(start 111.554126 164.182172)
		(end 111.554125 164.18217)
		(width 0.1)
		(layer "In9.Cu")
		(net 678)
	)
	(segment
		(start 110.706671 164.746782)
		(end 111.271281 164.182169)
		(width 0.1)
		(layer "In9.Cu")
		(net 678)
	)
	(segment
		(start 121.317158 167.1)
		(end 122.394658 168.1775)
		(width 0.1)
		(layer "In9.Cu")
		(net 678)
	)
	(segment
		(start 113.251181 165.879227)
		(end 113.25118 165.879225)
		(width 0.1)
		(layer "In9.Cu")
		(net 678)
	)
	(segment
		(start 112.685494 165.596383)
		(end 112.685495 165.596382)
		(width 0.1)
		(layer "In9.Cu")
		(net 678)
	)
	(segment
		(start 112.11981 165.030697)
		(end 111.555199 165.595309)
		(width 0.1)
		(layer "In9.Cu")
		(net 678)
	)
	(segment
		(start 111.554125 164.465012)
		(end 110.989514 165.029624)
		(width 0.1)
		(layer "In9.Cu")
		(net 678)
	)
	(segment
		(start 108.924501 162.4)
		(end 109.150501 162.626)
		(width 0.1)
		(layer "In9.Cu")
		(net 678)
	)
	(segment
		(start 110.706672 164.746781)
		(end 110.706671 164.746782)
		(width 0.1)
		(layer "In9.Cu")
		(net 678)
	)
	(segment
		(start 110.422755 163.333642)
		(end 109.858144 163.898254)
		(width 0.1)
		(layer "In9.Cu")
		(net 678)
	)
	(segment
		(start 100.500501 163.126)
		(end 100.920501 163.546)
		(width 0.1)
		(layer "In9.Cu")
		(net 678)
	)
	(segment
		(start 110.989515 165.312467)
		(end 110.989514 165.312467)
		(width 0.1)
		(layer "In9.Cu")
		(net 678)
	)
	(segment
		(start 110.422756 163.050802)
		(end 110.422755 163.0508)
		(width 0.1)
		(layer "In9.Cu")
		(net 678)
	)
	(segment
		(start 112.119809 165.030698)
		(end 112.11981 165.030697)
		(width 0.1)
		(layer "In9.Cu")
		(net 678)
	)
	(segment
		(start 112.403727 166.443836)
		(end 112.403726 166.443837)
		(width 0.1)
		(layer "In9.Cu")
		(net 678)
	)
	(segment
		(start 111.838042 165.878151)
		(end 111.838041 165.878152)
		(width 0.1)
		(layer "In9.Cu")
		(net 678)
	)
	(segment
		(start 112.119811 164.747857)
		(end 112.11981 164.747855)
		(width 0.1)
		(layer "In9.Cu")
		(net 678)
	)
	(segment
		(start 109.85707 162.485116)
		(end 109.857069 162.485116)
		(width 0.1)
		(layer "In9.Cu")
		(net 678)
	)
	(segment
		(start 113.624501 167.1)
		(end 121.317158 167.1)
		(width 0.1)
		(layer "In9.Cu")
		(net 678)
	)
	(segment
		(start 110.42383 164.746782)
		(end 110.423829 164.746782)
		(width 0.1)
		(layer "In9.Cu")
		(net 678)
	)
	(segment
		(start 109.433344 162.625999)
		(end 109.433343 162.626)
		(width 0.1)
		(layer "In9.Cu")
		(net 678)
	)
	(segment
		(start 110.98844 163.899327)
		(end 110.423829 164.463939)
		(width 0.1)
		(layer "In9.Cu")
		(net 678)
	)
	(segment
		(start 111.838041 165.878152)
		(end 112.402651 165.313539)
		(width 0.1)
		(layer "In9.Cu")
		(net 678)
	)
	(segment
		(start 109.857069 162.767958)
		(end 109.292459 163.332569)
		(width 0.1)
		(layer "In9.Cu")
		(net 678)
	)
	(segment
		(start 112.403726 166.443837)
		(end 112.968336 165.879224)
		(width 0.1)
		(layer "In9.Cu")
		(net 678)
	)
	(segment
		(start 110.140986 164.181097)
		(end 110.705596 163.616484)
		(width 0.1)
		(layer "In9.Cu")
		(net 678)
	)
	(segment
		(start 128.502 168.1775)
		(end 128.877001 167.802499)
		(width 0.1)
		(layer "In9.Cu")
		(net 678)
	)
	(segment
		(start 112.685495 165.596382)
		(end 112.120884 166.160994)
		(width 0.1)
		(layer "In9.Cu")
		(net 678)
	)
	(segment
		(start 112.120885 166.443837)
		(end 112.120884 166.443837)
		(width 0.1)
		(layer "In9.Cu")
		(net 678)
	)
	(segment
		(start 109.29246 163.615412)
		(end 109.292459 163.615412)
		(width 0.1)
		(layer "In9.Cu")
		(net 678)
	)
	(segment
		(start 112.969412 167.009521)
		(end 112.969411 167.009522)
		(width 0.1)
		(layer "In9.Cu")
		(net 678)
	)
	(segment
		(start 112.685496 165.313542)
		(end 112.685495 165.31354)
		(width 0.1)
		(layer "In9.Cu")
		(net 678)
	)
	(segment
		(start 111.272356 165.312467)
		(end 111.836966 164.747854)
		(width 0.1)
		(layer "In9.Cu")
		(net 678)
	)
	(segment
		(start 110.988439 163.899328)
		(end 110.98844 163.899327)
		(width 0.1)
		(layer "In9.Cu")
		(net 678)
	)
	(arc
		(start 113.25118 165.879225)
		(mid 113.309758 166.020647)
		(end 113.251179 166.162068)
		(width 0.1)
		(layer "In9.Cu")
		(net 678)
	)
	(arc
		(start 110.423829 164.463939)
		(mid 110.365251 164.605361)
		(end 110.42383 164.746782)
		(width 0.1)
		(layer "In9.Cu")
		(net 678)
	)
	(arc
		(start 110.422755 163.0508)
		(mid 110.481333 163.192222)
		(end 110.422754 163.333643)
		(width 0.1)
		(layer "In9.Cu")
		(net 678)
	)
	(arc
		(start 109.857069 162.485116)
		(mid 109.915647 162.626538)
		(end 109.857068 162.767959)
		(width 0.1)
		(layer "In9.Cu")
		(net 678)
	)
	(arc
		(start 112.686569 166.726679)
		(mid 112.627991 166.868101)
		(end 112.68657 167.009522)
		(width 0.1)
		(layer "In9.Cu")
		(net 678)
	)
	(arc
		(start 109.574227 162.485117)
		(mid 109.715648 162.426538)
		(end 109.85707 162.485116)
		(width 0.1)
		(layer "In9.Cu")
		(net 678)
	)
	(arc
		(start 109.858144 163.898254)
		(mid 109.799566 164.039676)
		(end 109.858145 164.181097)
		(width 0.1)
		(layer "In9.Cu")
		(net 678)
	)
	(arc
		(start 112.120884 166.443837)
		(mid 112.262306 166.502415)
		(end 112.403727 166.443836)
		(width 0.1)
		(layer "In9.Cu")
		(net 678)
	)
	(arc
		(start 112.685495 165.31354)
		(mid 112.744073 165.454962)
		(end 112.685494 165.596383)
		(width 0.1)
		(layer "In9.Cu")
		(net 678)
	)
	(arc
		(start 112.968336 165.879224)
		(mid 113.10976 165.820648)
		(end 113.251181 165.879227)
		(width 0.1)
		(layer "In9.Cu")
		(net 678)
	)
	(arc
		(start 110.989514 165.029624)
		(mid 110.930936 165.171046)
		(end 110.989515 165.312467)
		(width 0.1)
		(layer "In9.Cu")
		(net 678)
	)
	(arc
		(start 111.555199 165.878152)
		(mid 111.696621 165.93673)
		(end 111.838042 165.878151)
		(width 0.1)
		(layer "In9.Cu")
		(net 678)
	)
	(arc
		(start 109.858144 164.181097)
		(mid 109.999566 164.239675)
		(end 110.140987 164.181096)
		(width 0.1)
		(layer "In9.Cu")
		(net 678)
	)
	(arc
		(start 109.292459 163.332569)
		(mid 109.233881 163.473991)
		(end 109.29246 163.615412)
		(width 0.1)
		(layer "In9.Cu")
		(net 678)
	)
	(arc
		(start 113.110294 166.868638)
		(mid 113.251715 166.810059)
		(end 113.393137 166.868637)
		(width 0.1)
		(layer "In9.Cu")
		(net 678)
	)
	(arc
		(start 112.11981 164.747855)
		(mid 112.178388 164.889277)
		(end 112.119809 165.030698)
		(width 0.1)
		(layer "In9.Cu")
		(net 678)
	)
	(arc
		(start 110.423829 164.746782)
		(mid 110.565251 164.80536)
		(end 110.706672 164.746781)
		(width 0.1)
		(layer "In9.Cu")
		(net 678)
	)
	(arc
		(start 110.139911 163.050799)
		(mid 110.281335 162.992223)
		(end 110.422756 163.050802)
		(width 0.1)
		(layer "In9.Cu")
		(net 678)
	)
	(arc
		(start 109.292459 163.615412)
		(mid 109.433881 163.67399)
		(end 109.575302 163.615411)
		(width 0.1)
		(layer "In9.Cu")
		(net 678)
	)
	(arc
		(start 112.686569 167.009522)
		(mid 112.827991 167.0681)
		(end 112.969412 167.009521)
		(width 0.1)
		(layer "In9.Cu")
		(net 678)
	)
	(arc
		(start 110.98844 163.616485)
		(mid 111.047018 163.757907)
		(end 110.988439 163.899328)
		(width 0.1)
		(layer "In9.Cu")
		(net 678)
	)
	(arc
		(start 112.402651 165.313539)
		(mid 112.544075 165.254963)
		(end 112.685496 165.313542)
		(width 0.1)
		(layer "In9.Cu")
		(net 678)
	)
	(arc
		(start 109.150501 162.626)
		(mid 109.291923 162.684578)
		(end 109.433344 162.625999)
		(width 0.1)
		(layer "In9.Cu")
		(net 678)
	)
	(arc
		(start 112.120884 166.160994)
		(mid 112.062306 166.302416)
		(end 112.120885 166.443837)
		(width 0.1)
		(layer "In9.Cu")
		(net 678)
	)
	(arc
		(start 111.554125 164.18217)
		(mid 111.612703 164.323592)
		(end 111.554124 164.465013)
		(width 0.1)
		(layer "In9.Cu")
		(net 678)
	)
	(arc
		(start 110.705596 163.616484)
		(mid 110.84702 163.557908)
		(end 110.988441 163.616487)
		(width 0.1)
		(layer "In9.Cu")
		(net 678)
	)
	(arc
		(start 110.989514 165.312467)
		(mid 111.130936 165.371045)
		(end 111.272357 165.312466)
		(width 0.1)
		(layer "In9.Cu")
		(net 678)
	)
	(arc
		(start 111.555199 165.595309)
		(mid 111.496621 165.736731)
		(end 111.5552 165.878152)
		(width 0.1)
		(layer "In9.Cu")
		(net 678)
	)
	(arc
		(start 111.836966 164.747854)
		(mid 111.97839 164.689278)
		(end 112.119811 164.747857)
		(width 0.1)
		(layer "In9.Cu")
		(net 678)
	)
	(arc
		(start 111.271281 164.182169)
		(mid 111.412705 164.123593)
		(end 111.554126 164.182172)
		(width 0.1)
		(layer "In9.Cu")
		(net 678)
	)
	(segment
		(start 96.291829 155.568859)
		(end 96.091829 155.568859)
		(width 0.1)
		(layer "F.Cu")
		(net 679)
	)
	(segment
		(start 96.31468 155.546008)
		(end 96.291829 155.568859)
		(width 0.1)
		(layer "F.Cu")
		(net 679)
	)
	(segment
		(start 96.968978 155.546008)
		(end 96.31468 155.546008)
		(width 0.1)
		(layer "F.Cu")
		(net 679)
	)
	(segment
		(start 129.3765 167.302)
		(end 128.877001 166.802501)
		(width 0.256)
		(layer "F.Cu")
		(net 679)
	)
	(via
		(at 96.091829 155.568859)
		(size 0.45)
		(drill 0.1)
		(layers "F.Cu" "B.Cu")
		(net 679)
	)
	(via
		(at 128.877001 166.802501)
		(size 0.45)
		(drill 0.1)
		(layers "F.Cu" "B.Cu")
		(net 679)
	)
	(segment
		(start 96.07297 155.55)
		(end 96.091829 155.568859)
		(width 0.201)
		(layer "B.Cu")
		(net 679)
	)
	(segment
		(start 94.258672 155.435)
		(end 95.308672 155.435)
		(width 0.256)
		(layer "B.Cu")
		(net 679)
	)
	(segment
		(start 95.308672 155.435)
		(end 95.95797 155.435)
		(width 0.256)
		(layer "B.Cu")
		(net 679)
	)
	(segment
		(start 95.95797 155.435)
		(end 96.091829 155.568859)
		(width 0.256)
		(layer "B.Cu")
		(net 679)
	)
	(segment
		(start 117.826913 159.938304)
		(end 117.826913 159.938305)
		(width 0.1)
		(layer "In9.Cu")
		(net 679)
	)
	(segment
		(start 118.95829 161.069682)
		(end 118.39418 161.633786)
		(width 0.1)
		(layer "In9.Cu")
		(net 679)
	)
	(segment
		(start 115.282897 158.522503)
		(end 115.847004 157.958396)
		(width 0.1)
		(layer "In9.Cu")
		(net 679)
	)
	(segment
		(start 117.54565 161.068098)
		(end 117.54565 161.068099)
		(width 0.1)
		(layer "In9.Cu")
		(net 679)
	)
	(segment
		(start 118.392601 160.503993)
		(end 117.828492 161.068098)
		(width 0.1)
		(layer "In9.Cu")
		(net 679)
	)
	(segment
		(start 115.847004 157.675554)
		(end 115.847004 157.675553)
		(width 0.1)
		(layer "In9.Cu")
		(net 679)
	)
	(segment
		(start 104.412251 157.126)
		(end 103.412251 158.126)
		(width 0.1)
		(layer "In9.Cu")
		(net 679)
	)
	(segment
		(start 119.1005 161.493157)
		(end 119.100501 161.493157)
		(width 0.1)
		(layer "In9.Cu")
		(net 679)
	)
	(segment
		(start 115.564161 157.675552)
		(end 115.564161 157.675553)
		(width 0.1)
		(layer "In9.Cu")
		(net 679)
	)
	(segment
		(start 118.95829 161.069681)
		(end 118.95829 161.069682)
		(width 0.1)
		(layer "In9.Cu")
		(net 679)
	)
	(segment
		(start 126.350501 164.926)
		(end 126.350501 164.626)
		(width 0.1)
		(layer "In9.Cu")
		(net 679)
	)
	(segment
		(start 126.350501 164.626)
		(end 126.050501 164.326)
		(width 0.1)
		(layer "In9.Cu")
		(net 679)
	)
	(segment
		(start 116.979961 160.219567)
		(end 117.544068 159.65546)
		(width 0.1)
		(layer "In9.Cu")
		(net 679)
	)
	(segment
		(start 115.564161 157.675553)
		(end 115.423528 157.816185)
		(width 0.1)
		(layer "In9.Cu")
		(net 679)
	)
	(segment
		(start 115.848586 159.371034)
		(end 115.848586 159.371035)
		(width 0.1)
		(layer "In9.Cu")
		(net 679)
	)
	(segment
		(start 119.241132 161.069681)
		(end 119.241133 161.069682)
		(width 0.1)
		(layer "In9.Cu")
		(net 679)
	)
	(segment
		(start 115.848585 159.088192)
		(end 115.848585 159.088191)
		(width 0.1)
		(layer "In9.Cu")
		(net 679)
	)
	(segment
		(start 127.350501 165.806331)
		(end 127.350501 165.626)
		(width 0.1)
		(layer "In9.Cu")
		(net 679)
	)
	(segment
		(start 118.111337 161.350944)
		(end 118.111337 161.350943)
		(width 0.1)
		(layer "In9.Cu")
		(net 679)
	)
	(segment
		(start 116.414273 159.653879)
		(end 116.97838 159.089772)
		(width 0.1)
		(layer "In9.Cu")
		(net 679)
	)
	(segment
		(start 116.97838 158.80693)
		(end 116.97838 158.806929)
		(width 0.1)
		(layer "In9.Cu")
		(net 679)
	)
	(segment
		(start 116.979962 160.50241)
		(end 116.979962 160.502411)
		(width 0.1)
		(layer "In9.Cu")
		(net 679)
	)
	(segment
		(start 119.350501 162.026)
		(end 119.100501 161.776)
		(width 0.1)
		(layer "In9.Cu")
		(net 679)
	)
	(segment
		(start 125.426 164.326)
		(end 123.126 162.026)
		(width 0.1)
		(layer "In9.Cu")
		(net 679)
	)
	(segment
		(start 116.412692 158.241242)
		(end 116.412692 158.241241)
		(width 0.1)
		(layer "In9.Cu")
		(net 679)
	)
	(segment
		(start 128.877001 166.802501)
		(end 128.4005 166.326)
		(width 0.1)
		(layer "In9.Cu")
		(net 679)
	)
	(segment
		(start 127.87017 166.326)
		(end 127.350501 165.806331)
		(width 0.1)
		(layer "In9.Cu")
		(net 679)
	)
	(segment
		(start 114.450501 157.126)
		(end 104.412251 157.126)
		(width 0.1)
		(layer "In9.Cu")
		(net 679)
	)
	(segment
		(start 117.545649 160.785255)
		(end 118.109756 160.221148)
		(width 0.1)
		(layer "In9.Cu")
		(net 679)
	)
	(segment
		(start 116.414274 159.936722)
		(end 116.414274 159.936723)
		(width 0.1)
		(layer "In9.Cu")
		(net 679)
	)
	(segment
		(start 116.129849 158.24124)
		(end 116.129849 158.241241)
		(width 0.1)
		(layer "In9.Cu")
		(net 679)
	)
	(segment
		(start 123.126 162.026)
		(end 119.350501 162.026)
		(width 0.1)
		(layer "In9.Cu")
		(net 679)
	)
	(segment
		(start 98.250501 158.126)
		(end 96.091829 155.967328)
		(width 0.1)
		(layer "In9.Cu")
		(net 679)
	)
	(segment
		(start 115.282897 158.522504)
		(end 115.282897 158.522503)
		(width 0.1)
		(layer "In9.Cu")
		(net 679)
	)
	(segment
		(start 116.414273 159.65388)
		(end 116.414273 159.653879)
		(width 0.1)
		(layer "In9.Cu")
		(net 679)
	)
	(segment
		(start 126.050501 164.326)
		(end 125.426 164.326)
		(width 0.1)
		(layer "In9.Cu")
		(net 679)
	)
	(segment
		(start 126.750501 165.326)
		(end 126.350501 164.926)
		(width 0.1)
		(layer "In9.Cu")
		(net 679)
	)
	(segment
		(start 116.129849 158.241241)
		(end 115.56574 158.805346)
		(width 0.1)
		(layer "In9.Cu")
		(net 679)
	)
	(segment
		(start 118.111338 161.633786)
		(end 118.111338 161.633787)
		(width 0.1)
		(layer "In9.Cu")
		(net 679)
	)
	(segment
		(start 117.261225 159.372616)
		(end 117.261225 159.372617)
		(width 0.1)
		(layer "In9.Cu")
		(net 679)
	)
	(segment
		(start 118.392601 160.503992)
		(end 118.392601 160.503993)
		(width 0.1)
		(layer "In9.Cu")
		(net 679)
	)
	(segment
		(start 96.091829 155.967328)
		(end 96.091829 155.568859)
		(width 0.1)
		(layer "In9.Cu")
		(net 679)
	)
	(segment
		(start 103.412251 158.126)
		(end 98.250501 158.126)
		(width 0.1)
		(layer "In9.Cu")
		(net 679)
	)
	(segment
		(start 116.695537 158.806928)
		(end 116.695537 158.806929)
		(width 0.1)
		(layer "In9.Cu")
		(net 679)
	)
	(segment
		(start 115.282898 158.805346)
		(end 115.282898 158.805347)
		(width 0.1)
		(layer "In9.Cu")
		(net 679)
	)
	(segment
		(start 119.100501 161.493157)
		(end 119.241133 161.352524)
		(width 0.1)
		(layer "In9.Cu")
		(net 679)
	)
	(segment
		(start 116.695537 158.806929)
		(end 116.131428 159.371034)
		(width 0.1)
		(layer "In9.Cu")
		(net 679)
	)
	(segment
		(start 117.261225 159.372617)
		(end 116.697116 159.936722)
		(width 0.1)
		(layer "In9.Cu")
		(net 679)
	)
	(segment
		(start 127.350501 165.626)
		(end 127.050501 165.326)
		(width 0.1)
		(layer "In9.Cu")
		(net 679)
	)
	(segment
		(start 117.826913 159.938305)
		(end 117.262804 160.50241)
		(width 0.1)
		(layer "In9.Cu")
		(net 679)
	)
	(segment
		(start 118.675444 160.503994)
		(end 118.675444 160.503993)
		(width 0.1)
		(layer "In9.Cu")
		(net 679)
	)
	(segment
		(start 128.4005 166.326)
		(end 127.87017 166.326)
		(width 0.1)
		(layer "In9.Cu")
		(net 679)
	)
	(segment
		(start 118.109756 159.938306)
		(end 118.109756 159.938305)
		(width 0.1)
		(layer "In9.Cu")
		(net 679)
	)
	(segment
		(start 116.979961 160.219568)
		(end 116.979961 160.219567)
		(width 0.1)
		(layer "In9.Cu")
		(net 679)
	)
	(segment
		(start 117.545649 160.785256)
		(end 117.545649 160.785255)
		(width 0.1)
		(layer "In9.Cu")
		(net 679)
	)
	(segment
		(start 115.848585 159.088191)
		(end 116.412692 158.524084)
		(width 0.1)
		(layer "In9.Cu")
		(net 679)
	)
	(segment
		(start 127.050501 165.326)
		(end 126.750501 165.326)
		(width 0.1)
		(layer "In9.Cu")
		(net 679)
	)
	(segment
		(start 118.111337 161.350943)
		(end 118.675444 160.786836)
		(width 0.1)
		(layer "In9.Cu")
		(net 679)
	)
	(segment
		(start 117.544068 159.372618)
		(end 117.544068 159.372617)
		(width 0.1)
		(layer "In9.Cu")
		(net 679)
	)
	(segment
		(start 115.140685 157.816184)
		(end 114.450501 157.126)
		(width 0.1)
		(layer "In9.Cu")
		(net 679)
	)
	(arc
		(start 115.56574 158.805346)
		(mid 115.42432 158.863925)
		(end 115.282898 158.805346)
		(width 0.1)
		(layer "In9.Cu")
		(net 679)
	)
	(arc
		(start 117.828492 161.068098)
		(mid 117.687072 161.126677)
		(end 117.54565 161.068098)
		(width 0.1)
		(layer "In9.Cu")
		(net 679)
	)
	(arc
		(start 116.97838 159.089772)
		(mid 117.036958 158.948351)
		(end 116.97838 158.80693)
		(width 0.1)
		(layer "In9.Cu")
		(net 679)
	)
	(arc
		(start 116.979962 160.502411)
		(mid 116.921383 160.36099)
		(end 116.979961 160.219568)
		(width 0.1)
		(layer "In9.Cu")
		(net 679)
	)
	(arc
		(start 118.675444 160.503993)
		(mid 118.534023 160.445414)
		(end 118.392601 160.503992)
		(width 0.1)
		(layer "In9.Cu")
		(net 679)
	)
	(arc
		(start 118.39418 161.633786)
		(mid 118.25276 161.692365)
		(end 118.111338 161.633786)
		(width 0.1)
		(layer "In9.Cu")
		(net 679)
	)
	(arc
		(start 117.544068 159.372617)
		(mid 117.402647 159.314038)
		(end 117.261225 159.372616)
		(width 0.1)
		(layer "In9.Cu")
		(net 679)
	)
	(arc
		(start 116.412692 158.524084)
		(mid 116.47127 158.382663)
		(end 116.412692 158.241242)
		(width 0.1)
		(layer "In9.Cu")
		(net 679)
	)
	(arc
		(start 118.675444 160.786836)
		(mid 118.734022 160.645415)
		(end 118.675444 160.503994)
		(width 0.1)
		(layer "In9.Cu")
		(net 679)
	)
	(arc
		(start 118.109756 159.938305)
		(mid 117.968335 159.879726)
		(end 117.826913 159.938304)
		(width 0.1)
		(layer "In9.Cu")
		(net 679)
	)
	(arc
		(start 115.847004 157.675553)
		(mid 115.705583 157.616974)
		(end 115.564161 157.675552)
		(width 0.1)
		(layer "In9.Cu")
		(net 679)
	)
	(arc
		(start 115.848586 159.371035)
		(mid 115.790007 159.229614)
		(end 115.848585 159.088192)
		(width 0.1)
		(layer "In9.Cu")
		(net 679)
	)
	(arc
		(start 119.100501 161.776)
		(mid 119.041922 161.634579)
		(end 119.1005 161.493157)
		(width 0.1)
		(layer "In9.Cu")
		(net 679)
	)
	(arc
		(start 116.697116 159.936722)
		(mid 116.555696 159.995301)
		(end 116.414274 159.936722)
		(width 0.1)
		(layer "In9.Cu")
		(net 679)
	)
	(arc
		(start 115.282898 158.805347)
		(mid 115.224319 158.663926)
		(end 115.282897 158.522504)
		(width 0.1)
		(layer "In9.Cu")
		(net 679)
	)
	(arc
		(start 115.847004 157.958396)
		(mid 115.905582 157.816975)
		(end 115.847004 157.675554)
		(width 0.1)
		(layer "In9.Cu")
		(net 679)
	)
	(arc
		(start 118.109756 160.221148)
		(mid 118.168334 160.079727)
		(end 118.109756 159.938306)
		(width 0.1)
		(layer "In9.Cu")
		(net 679)
	)
	(arc
		(start 115.423528 157.816185)
		(mid 115.282106 157.874763)
		(end 115.140685 157.816184)
		(width 0.1)
		(layer "In9.Cu")
		(net 679)
	)
	(arc
		(start 116.131428 159.371034)
		(mid 115.990008 159.429613)
		(end 115.848586 159.371034)
		(width 0.1)
		(layer "In9.Cu")
		(net 679)
	)
	(arc
		(start 116.412692 158.241241)
		(mid 116.271271 158.182662)
		(end 116.129849 158.24124)
		(width 0.1)
		(layer "In9.Cu")
		(net 679)
	)
	(arc
		(start 116.97838 158.806929)
		(mid 116.836959 158.74835)
		(end 116.695537 158.806928)
		(width 0.1)
		(layer "In9.Cu")
		(net 679)
	)
	(arc
		(start 119.241133 161.069682)
		(mid 119.099712 161.011103)
		(end 118.95829 161.069681)
		(width 0.1)
		(layer "In9.Cu")
		(net 679)
	)
	(arc
		(start 117.54565 161.068099)
		(mid 117.487071 160.926678)
		(end 117.545649 160.785256)
		(width 0.1)
		(layer "In9.Cu")
		(net 679)
	)
	(arc
		(start 117.544068 159.65546)
		(mid 117.602646 159.514039)
		(end 117.544068 159.372618)
		(width 0.1)
		(layer "In9.Cu")
		(net 679)
	)
	(arc
		(start 118.111338 161.633787)
		(mid 118.052759 161.492366)
		(end 118.111337 161.350944)
		(width 0.1)
		(layer "In9.Cu")
		(net 679)
	)
	(arc
		(start 117.262804 160.50241)
		(mid 117.121384 160.560989)
		(end 116.979962 160.50241)
		(width 0.1)
		(layer "In9.Cu")
		(net 679)
	)
	(arc
		(start 119.241133 161.352524)
		(mid 119.299711 161.211102)
		(end 119.241132 161.069681)
		(width 0.1)
		(layer "In9.Cu")
		(net 679)
	)
	(arc
		(start 116.414274 159.936723)
		(mid 116.355695 159.795302)
		(end 116.414273 159.65388)
		(width 0.1)
		(layer "In9.Cu")
		(net 679)
	)
	(segment
		(start 97.050501 157.535)
		(end 97.309501 157.535)
		(width 0.256)
		(layer "F.Cu")
		(net 680)
	)
	(segment
		(start 97.309501 157.535)
		(end 98.635501 158.861)
		(width 0.256)
		(layer "F.Cu")
		(net 680)
	)
	(segment
		(start 126.376501 166.302)
		(end 125.877001 165.8025)
		(width 0.256)
		(layer "F.Cu")
		(net 680)
	)
	(via
		(at 125.877001 165.8025)
		(size 0.45)
		(drill 0.1)
		(layers "F.Cu" "B.Cu")
		(net 680)
	)
	(via
		(at 98.635501 158.861)
		(size 0.45)
		(drill 0.1)
		(layers "F.Cu" "B.Cu")
		(net 680)
	)
	(segment
		(start 98.585 158.810499)
		(end 98.635501 158.861)
		(width 0.256)
		(layer "B.Cu")
		(net 680)
	)
	(segment
		(start 98.585 158.1)
		(end 98.585 158.810499)
		(width 0.256)
		(layer "B.Cu")
		(net 680)
	)
	(segment
		(start 103.371842 158.9)
		(end 104.571842 157.7)
		(width 0.1)
		(layer "In9.Cu")
		(net 680)
	)
	(segment
		(start 118.51225 162.6)
		(end 122.674501 162.6)
		(width 0.1)
		(layer "In9.Cu")
		(net 680)
	)
	(segment
		(start 113.61225 157.7)
		(end 118.51225 162.6)
		(width 0.1)
		(layer "In9.Cu")
		(net 680)
	)
	(segment
		(start 98.635501 158.861)
		(end 98.674501 158.9)
		(width 0.1)
		(layer "In9.Cu")
		(net 680)
	)
	(segment
		(start 98.674501 158.9)
		(end 103.371842 158.9)
		(width 0.1)
		(layer "In9.Cu")
		(net 680)
	)
	(segment
		(start 104.571842 157.7)
		(end 113.61225 157.7)
		(width 0.1)
		(layer "In9.Cu")
		(net 680)
	)
	(segment
		(start 122.674501 162.6)
		(end 125.877001 165.8025)
		(width 0.1)
		(layer "In9.Cu")
		(net 680)
	)
	(segment
		(start 130.376501 167.302)
		(end 129.877 166.8025)
		(width 0.256)
		(layer "F.Cu")
		(net 681)
	)
	(segment
		(start 97.050501 155.034)
		(end 97.58965 155.034)
		(width 0.256)
		(layer "F.Cu")
		(net 681)
	)
	(segment
		(start 97.58965 155.034)
		(end 98.100501 154.523149)
		(width 0.256)
		(layer "F.Cu")
		(net 681)
	)
	(via
		(at 129.877 166.8025)
		(size 0.45)
		(drill 0.1)
		(layers "F.Cu" "B.Cu")
		(net 681)
	)
	(via
		(at 98.100501 154.523149)
		(size 0.45)
		(drill 0.1)
		(layers "F.Cu" "B.Cu")
		(net 681)
	)
	(segment
		(start 98.100501 154.400501)
		(end 98.100501 154.523149)
		(width 0.2)
		(layer "B.Cu")
		(net 681)
	)
	(segment
		(start 97.585 153.885)
		(end 98.100501 154.400501)
		(width 0.2)
		(layer "B.Cu")
		(net 681)
	)
	(segment
		(start 97.585 153.85)
		(end 97.585 153.885)
		(width 0.2)
		(layer "B.Cu")
		(net 681)
	)
	(segment
		(start 129.877 166.8025)
		(end 129.877 166.427)
		(width 0.1)
		(layer "In9.Cu")
		(net 681)
	)
	(segment
		(start 129.275 164.25)
		(end 128.65 164.25)
		(width 0.1)
		(layer "In9.Cu")
		(net 681)
	)
	(segment
		(start 128.4 164)
		(end 128.4 163.325)
		(width 0.1)
		(layer "In9.Cu")
		(net 681)
	)
	(segment
		(start 126.4 162.85583)
		(end 126.4 161.1)
		(width 0.1)
		(layer "In9.Cu")
		(net 681)
	)
	(segment
		(start 128.275 163.2)
		(end 126.74417 163.2)
		(width 0.1)
		(layer "In9.Cu")
		(net 681)
	)
	(segment
		(start 125.826 160.526)
		(end 120.050501 160.526)
		(width 0.1)
		(layer "In9.Cu")
		(net 681)
	)
	(segment
		(start 128.65 164.25)
		(end 128.4 164)
		(width 0.1)
		(layer "In9.Cu")
		(net 681)
	)
	(segment
		(start 129.4 164.375)
		(end 129.275 164.25)
		(width 0.1)
		(layer "In9.Cu")
		(net 681)
	)
	(segment
		(start 128.4 163.325)
		(end 128.275 163.2)
		(width 0.1)
		(layer "In9.Cu")
		(net 681)
	)
	(segment
		(start 129.4 165.95)
		(end 129.4 164.375)
		(width 0.1)
		(layer "In9.Cu")
		(net 681)
	)
	(segment
		(start 126.4 161.1)
		(end 125.826 160.526)
		(width 0.1)
		(layer "In9.Cu")
		(net 681)
	)
	(segment
		(start 113.024501 153.5)
		(end 99.12365 153.5)
		(width 0.1)
		(layer "In9.Cu")
		(net 681)
	)
	(segment
		(start 126.74417 163.2)
		(end 126.4 162.85583)
		(width 0.1)
		(layer "In9.Cu")
		(net 681)
	)
	(segment
		(start 120.050501 160.526)
		(end 113.024501 153.5)
		(width 0.1)
		(layer "In9.Cu")
		(net 681)
	)
	(segment
		(start 99.12365 153.5)
		(end 98.100501 154.523149)
		(width 0.1)
		(layer "In9.Cu")
		(net 681)
	)
	(segment
		(start 129.877 166.427)
		(end 129.4 165.95)
		(width 0.1)
		(layer "In9.Cu")
		(net 681)
	)
	(segment
		(start 127.376501 183.301)
		(end 126.877001 183.8005)
		(width 0.256)
		(layer "F.Cu")
		(net 682)
	)
	(segment
		(start 99.613501 146.394)
		(end 99.775501 146.556)
		(width 0.256)
		(layer "F.Cu")
		(net 682)
	)
	(segment
		(start 99.775501 146.556)
		(end 99.775501 147.251)
		(width 0.256)
		(layer "F.Cu")
		(net 682)
	)
	(segment
		(start 99.775501 147.251)
		(end 99.800501 147.276)
		(width 0.256)
		(layer "F.Cu")
		(net 682)
	)
	(segment
		(start 179.458 193.558)
		(end 180.278 193.558)
		(width 0.177)
		(layer "F.Cu")
		(net 682)
	)
	(segment
		(start 179 193.1)
		(end 179.458 193.558)
		(width 0.177)
		(layer "F.Cu")
		(net 682)
	)
	(segment
		(start 99.613501 143.727)
		(end 99.613501 146.394)
		(width 0.256)
		(layer "F.Cu")
		(net 682)
	)
	(via
		(at 99.800501 147.276)
		(size 0.45)
		(drill 0.1)
		(layers "F.Cu" "B.Cu")
		(net 682)
	)
	(via
		(at 126.877001 183.8005)
		(size 0.45)
		(drill 0.1)
		(layers "F.Cu" "B.Cu")
		(net 682)
	)
	(via
		(at 179 193.1)
		(size 0.45)
		(drill 0.1)
		(layers "F.Cu" "B.Cu")
		(net 682)
	)
	(segment
		(start 180.315 191)
		(end 179.9 191)
		(width 0.15)
		(layer "B.Cu")
		(net 682)
	)
	(segment
		(start 179 191.9)
		(end 179 193.1)
		(width 0.15)
		(layer "B.Cu")
		(net 682)
	)
	(segment
		(start 179.9 191)
		(end 179 191.9)
		(width 0.15)
		(layer "B.Cu")
		(net 682)
	)
	(segment
		(start 104.35 156.95)
		(end 98.703157 151.303157)
		(width 0.1)
		(layer "In2.Cu")
		(net 682)
	)
	(segment
		(start 124.45 182.65)
		(end 116.75 182.65)
		(width 0.1)
		(layer "In2.Cu")
		(net 682)
	)
	(segment
		(start 106.2 163.698998)
		(end 104.35 161.848998)
		(width 0.1)
		(layer "In2.Cu")
		(net 682)
	)
	(segment
		(start 125.1 183.3)
		(end 124.45 182.65)
		(width 0.1)
		(layer "In2.Cu")
		(net 682)
	)
	(segment
		(start 116.75 182.65)
		(end 106.2 172.1)
		(width 0.1)
		(layer "In2.Cu")
		(net 682)
	)
	(segment
		(start 98.703157 149.096843)
		(end 99.800501 147.999499)
		(width 0.1)
		(layer "In2.Cu")
		(net 682)
	)
	(segment
		(start 98.703157 151.303157)
		(end 98.703157 149.096843)
		(width 0.1)
		(layer "In2.Cu")
		(net 682)
	)
	(segment
		(start 104.35 161.848998)
		(end 104.35 156.95)
		(width 0.1)
		(layer "In2.Cu")
		(net 682)
	)
	(segment
		(start 99.800501 147.999499)
		(end 99.800501 147.276)
		(width 0.1)
		(layer "In2.Cu")
		(net 682)
	)
	(segment
		(start 126.877001 183.8005)
		(end 126.376501 183.3)
		(width 0.1)
		(layer "In2.Cu")
		(net 682)
	)
	(segment
		(start 106.2 172.1)
		(end 106.2 163.698998)
		(width 0.1)
		(layer "In2.Cu")
		(net 682)
	)
	(segment
		(start 126.376501 183.3)
		(end 125.1 183.3)
		(width 0.1)
		(layer "In2.Cu")
		(net 682)
	)
	(segment
		(start 130.782832 183.176)
		(end 127.501501 183.176)
		(width 0.1)
		(layer "In4.Cu")
		(net 682)
	)
	(segment
		(start 179 193.1)
		(end 179 190.45)
		(width 0.1)
		(layer "In4.Cu")
		(net 682)
	)
	(segment
		(start 176.3 185.7)
		(end 148.75 185.7)
		(width 0.1)
		(layer "In4.Cu")
		(net 682)
	)
	(segment
		(start 138.1 184.3)
		(end 131.59617 184.3)
		(width 0.1)
		(layer "In4.Cu")
		(net 682)
	)
	(segment
		(start 131.252001 183.955831)
		(end 131.252001 183.645169)
		(width 0.1)
		(layer "In4.Cu")
		(net 682)
	)
	(segment
		(start 131.252001 183.645169)
		(end 130.782832 183.176)
		(width 0.1)
		(layer "In4.Cu")
		(net 682)
	)
	(segment
		(start 178.05 187.45)
		(end 176.3 185.7)
		(width 0.1)
		(layer "In4.Cu")
		(net 682)
	)
	(segment
		(start 148.35 185.3)
		(end 139.1 185.3)
		(width 0.1)
		(layer "In4.Cu")
		(net 682)
	)
	(segment
		(start 131.59617 184.3)
		(end 131.252001 183.955831)
		(width 0.1)
		(layer "In4.Cu")
		(net 682)
	)
	(segment
		(start 178.05 189.5)
		(end 178.05 187.45)
		(width 0.1)
		(layer "In4.Cu")
		(net 682)
	)
	(segment
		(start 148.75 185.7)
		(end 148.35 185.3)
		(width 0.1)
		(layer "In4.Cu")
		(net 682)
	)
	(segment
		(start 127.501501 183.176)
		(end 126.877001 183.8005)
		(width 0.1)
		(layer "In4.Cu")
		(net 682)
	)
	(segment
		(start 139.1 185.3)
		(end 138.1 184.3)
		(width 0.1)
		(layer "In4.Cu")
		(net 682)
	)
	(segment
		(start 179 190.45)
		(end 178.05 189.5)
		(width 0.1)
		(layer "In4.Cu")
		(net 682)
	)
	(segment
		(start 126.376501 184.301)
		(end 125.877001 184.8005)
		(width 0.256)
		(layer "F.Cu")
		(net 683)
	)
	(segment
		(start 98.962501 143.727)
		(end 98.962501 146.439)
		(width 0.256)
		(layer "F.Cu")
		(net 683)
	)
	(segment
		(start 179.005 197.314001)
		(end 179.011 197.308001)
		(width 0.177)
		(layer "F.Cu")
		(net 683)
	)
	(segment
		(start 98.845501 147.221)
		(end 98.900501 147.276)
		(width 0.256)
		(layer "F.Cu")
		(net 683)
	)
	(segment
		(start 98.845501 146.556)
		(end 98.845501 147.221)
		(width 0.256)
		(layer "F.Cu")
		(net 683)
	)
	(segment
		(start 98.962501 146.439)
		(end 98.845501 146.556)
		(width 0.256)
		(layer "F.Cu")
		(net 683)
	)
	(segment
		(start 179.011 197.308001)
		(end 180.278 197.308)
		(width 0.177)
		(layer "F.Cu")
		(net 683)
	)
	(via
		(at 179.005 197.314001)
		(size 0.45)
		(drill 0.1)
		(layers "F.Cu" "B.Cu")
		(net 683)
	)
	(via
		(at 125.877001 184.8005)
		(size 0.45)
		(drill 0.1)
		(layers "F.Cu" "B.Cu")
		(net 683)
	)
	(via
		(at 98.900501 147.276)
		(size 0.45)
		(drill 0.1)
		(layers "F.Cu" "B.Cu")
		(net 683)
	)
	(segment
		(start 179.95 200.4)
		(end 178.6 199.05)
		(width 0.15)
		(layer "B.Cu")
		(net 683)
	)
	(segment
		(start 178.6 199.05)
		(end 178.6 197.719001)
		(width 0.15)
		(layer "B.Cu")
		(net 683)
	)
	(segment
		(start 180.315 200.4)
		(end 179.95 200.4)
		(width 0.15)
		(layer "B.Cu")
		(net 683)
	)
	(segment
		(start 178.6 197.719001)
		(end 179.005 197.314001)
		(width 0.15)
		(layer "B.Cu")
		(net 683)
	)
	(segment
		(start 105.3 164.7)
		(end 103.7 163.1)
		(width 0.1)
		(layer "In2.Cu")
		(net 683)
	)
	(segment
		(start 103.7 157.2)
		(end 98.1 151.6)
		(width 0.1)
		(layer "In2.Cu")
		(net 683)
	)
	(segment
		(start 98.1 148.076501)
		(end 98.900501 147.276)
		(width 0.1)
		(layer "In2.Cu")
		(net 683)
	)
	(segment
		(start 105.3 171.979653)
		(end 105.3 164.7)
		(width 0.1)
		(layer "In2.Cu")
		(net 683)
	)
	(segment
		(start 125.877001 184.8005)
		(end 125.33825 184.26175)
		(width 0.1)
		(layer "In2.Cu")
		(net 683)
	)
	(segment
		(start 107.4 174.079653)
		(end 105.3 171.979653)
		(width 0.1)
		(layer "In2.Cu")
		(net 683)
	)
	(segment
		(start 107.4 175.7)
		(end 107.4 174.079653)
		(width 0.1)
		(layer "In2.Cu")
		(net 683)
	)
	(segment
		(start 98.1 151.6)
		(end 98.1 148.076501)
		(width 0.1)
		(layer "In2.Cu")
		(net 683)
	)
	(segment
		(start 125.33825 184.26175)
		(end 115.96175 184.26175)
		(width 0.1)
		(layer "In2.Cu")
		(net 683)
	)
	(segment
		(start 103.7 163.1)
		(end 103.7 157.2)
		(width 0.1)
		(layer "In2.Cu")
		(net 683)
	)
	(segment
		(start 115.96175 184.26175)
		(end 107.4 175.7)
		(width 0.1)
		(layer "In2.Cu")
		(net 683)
	)
	(segment
		(start 129.624 183.376)
		(end 130.15 183.376)
		(width 0.1)
		(layer "In4.Cu")
		(net 683)
	)
	(segment
		(start 131.6255 185.2255)
		(end 137.832332 185.2255)
		(width 0.1)
		(layer "In4.Cu")
		(net 683)
	)
	(segment
		(start 178.725 193.675)
		(end 178.725 197.034001)
		(width 0.1)
		(layer "In4.Cu")
		(net 683)
	)
	(segment
		(start 130.4 184)
		(end 130.75 184.35)
		(width 0.1)
		(layer "In4.Cu")
		(net 683)
	)
	(segment
		(start 125.877001 184.8005)
		(end 126.377501 184.3)
		(width 0.1)
		(layer "In4.Cu")
		(net 683)
	)
	(segment
		(start 131.1 184.35)
		(end 131.35 184.6)
		(width 0.1)
		(layer "In4.Cu")
		(net 683)
	)
	(segment
		(start 175.8 186.3)
		(end 177.3 187.8)
		(width 0.1)
		(layer "In4.Cu")
		(net 683)
	)
	(segment
		(start 177.3 189.85)
		(end 178.425 190.975)
		(width 0.1)
		(layer "In4.Cu")
		(net 683)
	)
	(segment
		(start 178.425 190.975)
		(end 178.425 193.375)
		(width 0.1)
		(layer "In4.Cu")
		(net 683)
	)
	(segment
		(start 178.725 197.034001)
		(end 179.005 197.314001)
		(width 0.1)
		(layer "In4.Cu")
		(net 683)
	)
	(segment
		(start 129.1 184.3)
		(end 129.4 184)
		(width 0.1)
		(layer "In4.Cu")
		(net 683)
	)
	(segment
		(start 126.377501 184.3)
		(end 129.1 184.3)
		(width 0.1)
		(layer "In4.Cu")
		(net 683)
	)
	(segment
		(start 177.3 187.8)
		(end 177.3 189.85)
		(width 0.1)
		(layer "In4.Cu")
		(net 683)
	)
	(segment
		(start 130.4 183.626)
		(end 130.4 184)
		(width 0.1)
		(layer "In4.Cu")
		(net 683)
	)
	(segment
		(start 178.425 193.375)
		(end 178.725 193.675)
		(width 0.1)
		(layer "In4.Cu")
		(net 683)
	)
	(segment
		(start 131.35 184.6)
		(end 131.35 184.95)
		(width 0.1)
		(layer "In4.Cu")
		(net 683)
	)
	(segment
		(start 137.832332 185.2255)
		(end 138.9 186.293168)
		(width 0.1)
		(layer "In4.Cu")
		(net 683)
	)
	(segment
		(start 131.35 184.95)
		(end 131.6255 185.2255)
		(width 0.1)
		(layer "In4.Cu")
		(net 683)
	)
	(segment
		(start 129.4 184)
		(end 129.4 183.6)
		(width 0.1)
		(layer "In4.Cu")
		(net 683)
	)
	(segment
		(start 138.9 186.293168)
		(end 138.9 186.3)
		(width 0.1)
		(layer "In4.Cu")
		(net 683)
	)
	(segment
		(start 129.4 183.6)
		(end 129.624 183.376)
		(width 0.1)
		(layer "In4.Cu")
		(net 683)
	)
	(segment
		(start 138.9 186.3)
		(end 175.8 186.3)
		(width 0.1)
		(layer "In4.Cu")
		(net 683)
	)
	(segment
		(start 130.75 184.35)
		(end 131.1 184.35)
		(width 0.1)
		(layer "In4.Cu")
		(net 683)
	)
	(segment
		(start 130.15 183.376)
		(end 130.4 183.626)
		(width 0.1)
		(layer "In4.Cu")
		(net 683)
	)
	(segment
		(start 143.375501 171.302)
		(end 143.875001 170.8025)
		(width 0.256)
		(layer "F.Cu")
		(net 684)
	)
	(via
		(at 143.875001 170.8025)
		(size 0.45)
		(drill 0.1)
		(layers "F.Cu" "B.Cu")
		(net 684)
	)
	(segment
		(start 143.375001 171.3025)
		(end 143.875001 170.8025)
		(width 0.256)
		(layer "B.Cu")
		(net 684)
	)
	(segment
		(start 140.375501 170.302)
		(end 140.875001 169.8025)
		(width 0.256)
		(layer "F.Cu")
		(net 685)
	)
	(via
		(at 140.875001 169.8025)
		(size 0.45)
		(drill 0.1)
		(layers "F.Cu" "B.Cu")
		(net 685)
	)
	(segment
		(start 141.375001 170.3025)
		(end 140.875001 169.8025)
		(width 0.256)
		(layer "B.Cu")
		(net 685)
	)
	(segment
		(start 184.3 194.55)
		(end 184.294 194.556)
		(width 0.177)
		(layer "F.Cu")
		(net 686)
	)
	(segment
		(start 184.294 194.556)
		(end 183.027 194.556)
		(width 0.177)
		(layer "F.Cu")
		(net 686)
	)
	(segment
		(start 199.1765 151.8035)
		(end 198.1755 151.8035)
		(width 0.256)
		(layer "F.Cu")
		(net 686)
	)
	(segment
		(start 184.306 198.306)
		(end 183.027 198.306)
		(width 0.177)
		(layer "F.Cu")
		(net 686)
	)
	(segment
		(start 184.75 198.75)
		(end 184.306 198.306)
		(width 0.177)
		(layer "F.Cu")
		(net 686)
	)
	(via
		(at 198.1755 151.8035)
		(size 0.45)
		(drill 0.1)
		(layers "F.Cu" "B.Cu")
		(net 686)
	)
	(via
		(at 184.75 198.75)
		(size 0.45)
		(drill 0.1)
		(layers "F.Cu" "B.Cu")
		(net 686)
	)
	(via
		(at 184.3 194.55)
		(size 0.45)
		(drill 0.1)
		(layers "F.Cu" "B.Cu")
		(net 686)
	)
	(segment
		(start 202.65 192.4)
		(end 206.25 188.8)
		(width 0.15)
		(layer "B.Cu")
		(net 686)
	)
	(segment
		(start 199.179 150.8)
		(end 198.1755 151.8035)
		(width 0.15)
		(layer "B.Cu")
		(net 686)
	)
	(segment
		(start 198.1755 151.8035)
		(end 198.179 151.8)
		(width 0.15)
		(layer "B.Cu")
		(net 686)
	)
	(segment
		(start 184.771 198.771)
		(end 187.829 198.771)
		(width 0.15)
		(layer "B.Cu")
		(net 686)
	)
	(segment
		(start 191 195.6)
		(end 191 193.2)
		(width 0.15)
		(layer "B.Cu")
		(net 686)
	)
	(segment
		(start 191.8 192.4)
		(end 202.65 192.4)
		(width 0.15)
		(layer "B.Cu")
		(net 686)
	)
	(segment
		(start 197.435 151.8)
		(end 198.172 151.8)
		(width 0.4)
		(layer "B.Cu")
		(net 686)
	)
	(segment
		(start 187.829 198.771)
		(end 191 195.6)
		(width 0.15)
		(layer "B.Cu")
		(net 686)
	)
	(segment
		(start 203.4 150.8)
		(end 199.179 150.8)
		(width 0.15)
		(layer "B.Cu")
		(net 686)
	)
	(segment
		(start 191 193.2)
		(end 191.8 192.4)
		(width 0.15)
		(layer "B.Cu")
		(net 686)
	)
	(segment
		(start 204.65 152.05)
		(end 203.4 150.8)
		(width 0.15)
		(layer "B.Cu")
		(net 686)
	)
	(segment
		(start 198.179 151.8)
		(end 200.6 151.8)
		(width 0.15)
		(layer "B.Cu")
		(net 686)
	)
	(segment
		(start 206.25 157.85)
		(end 204.65 156.25)
		(width 0.15)
		(layer "B.Cu")
		(net 686)
	)
	(segment
		(start 206.25 188.8)
		(end 206.25 157.85)
		(width 0.15)
		(layer "B.Cu")
		(net 686)
	)
	(segment
		(start 184.75 198.75)
		(end 184.771 198.771)
		(width 0.15)
		(layer "B.Cu")
		(net 686)
	)
	(segment
		(start 198.172 151.8)
		(end 198.1755 151.8035)
		(width 0.4)
		(layer "B.Cu")
		(net 686)
	)
	(segment
		(start 204.65 156.25)
		(end 204.65 152.05)
		(width 0.15)
		(layer "B.Cu")
		(net 686)
	)
	(segment
		(start 184.3 198.3)
		(end 184.3 194.55)
		(width 0.15)
		(layer "In4.Cu")
		(net 686)
	)
	(segment
		(start 184.75 198.75)
		(end 184.3 198.3)
		(width 0.15)
		(layer "In4.Cu")
		(net 686)
	)
	(segment
		(start 183.794 198.807)
		(end 183.8 198.801)
		(width 0.177)
		(layer "F.Cu")
		(net 687)
	)
	(segment
		(start 199.1765 152.8035)
		(end 198.1755 152.8035)
		(width 0.256)
		(layer "F.Cu")
		(net 687)
	)
	(segment
		(start 183.027 195.057)
		(end 183.794 195.057)
		(width 0.177)
		(layer "F.Cu")
		(net 687)
	)
	(segment
		(start 183.794 195.057)
		(end 183.8 195.051)
		(width 0.177)
		(layer "F.Cu")
		(net 687)
	)
	(segment
		(start 183.027 198.807)
		(end 183.794 198.807)
		(width 0.177)
		(layer "F.Cu")
		(net 687)
	)
	(via
		(at 198.1755 152.8035)
		(size 0.45)
		(drill 0.1)
		(layers "F.Cu" "B.Cu")
		(net 687)
	)
	(via
		(at 183.8 198.801)
		(size 0.45)
		(drill 0.1)
		(layers "F.Cu" "B.Cu")
		(net 687)
	)
	(via
		(at 183.8 195.051)
		(size 0.45)
		(drill 0.1)
		(layers "F.Cu" "B.Cu")
		(net 687)
	)
	(segment
		(start 190.4 192.6)
		(end 190.4 195)
		(width 0.15)
		(layer "B.Cu")
		(net 687)
	)
	(segment
		(start 203 152.8035)
		(end 203.1 152.8035)
		(width 0.15)
		(layer "B.Cu")
		(net 687)
	)
	(segment
		(start 205.35 183.05)
		(end 205.35 188.45)
		(width 0.15)
		(layer "B.Cu")
		(net 687)
	)
	(segment
		(start 202.8 152.8)
		(end 202.7965 152.8035)
		(width 0.15)
		(layer "B.Cu")
		(net 687)
	)
	(segment
		(start 205.35 176.2)
		(end 205.05 176.5)
		(width 0.15)
		(layer "B.Cu")
		(net 687)
	)
	(segment
		(start 190.4 195)
		(end 187.475 197.925)
		(width 0.15)
		(layer "B.Cu")
		(net 687)
	)
	(segment
		(start 183.8 198.8)
		(end 183.8 198.801)
		(width 0.15)
		(layer "B.Cu")
		(net 687)
	)
	(segment
		(start 202.7965 152.8035)
		(end 198.1755 152.8035)
		(width 0.15)
		(layer "B.Cu")
		(net 687)
	)
	(segment
		(start 203.1 152.7)
		(end 203.1 152.7035)
		(width 0.15)
		(layer "B.Cu")
		(net 687)
	)
	(segment
		(start 205.05 182.75)
		(end 205.35 183.05)
		(width 0.15)
		(layer "B.Cu")
		(net 687)
	)
	(segment
		(start 204.075 157.525)
		(end 205 158.45)
		(width 0.15)
		(layer "B.Cu")
		(net 687)
	)
	(segment
		(start 205.35 188.45)
		(end 201.9 191.9)
		(width 0.15)
		(layer "B.Cu")
		(net 687)
	)
	(segment
		(start 204.075 153.775)
		(end 204.075 157.525)
		(width 0.15)
		(layer "B.Cu")
		(net 687)
	)
	(segment
		(start 197.488501 152.8035)
		(end 198.1755 152.8035)
		(width 0.4)
		(layer "B.Cu")
		(net 687)
	)
	(segment
		(start 191.1 191.9)
		(end 190.4 192.6)
		(width 0.15)
		(layer "B.Cu")
		(net 687)
	)
	(segment
		(start 205.05 176.5)
		(end 205.05 182.75)
		(width 0.15)
		(layer "B.Cu")
		(net 687)
	)
	(segment
		(start 201.9 191.9)
		(end 191.1 191.9)
		(width 0.15)
		(layer "B.Cu")
		(net 687)
	)
	(segment
		(start 203.1 151.8)
		(end 203.1 152.7)
		(width 0.15)
		(layer "B.Cu")
		(net 687)
	)
	(segment
		(start 203.1 152.7035)
		(end 203 152.8035)
		(width 0.15)
		(layer "B.Cu")
		(net 687)
	)
	(segment
		(start 203 152.8035)
		(end 202.8 152.8035)
		(width 0.15)
		(layer "B.Cu")
		(net 687)
	)
	(segment
		(start 203.1035 152.8035)
		(end 204.075 153.775)
		(width 0.15)
		(layer "B.Cu")
		(net 687)
	)
	(segment
		(start 205 168.075)
		(end 205.35 168.425)
		(width 0.15)
		(layer "B.Cu")
		(net 687)
	)
	(segment
		(start 187.475 197.925)
		(end 184.675 197.925)
		(width 0.15)
		(layer "B.Cu")
		(net 687)
	)
	(segment
		(start 205 158.45)
		(end 205 168.075)
		(width 0.15)
		(layer "B.Cu")
		(net 687)
	)
	(segment
		(start 205.35 168.425)
		(end 205.35 176.2)
		(width 0.15)
		(layer "B.Cu")
		(net 687)
	)
	(segment
		(start 203.1 152.7)
		(end 203.1 152.8035)
		(width 0.15)
		(layer "B.Cu")
		(net 687)
	)
	(segment
		(start 202.8 152.8035)
		(end 202.8 152.8)
		(width 0.15)
		(layer "B.Cu")
		(net 687)
	)
	(segment
		(start 184.675 197.925)
		(end 183.8 198.8)
		(width 0.15)
		(layer "B.Cu")
		(net 687)
	)
	(segment
		(start 203.1 152.8035)
		(end 203.1035 152.8035)
		(width 0.15)
		(layer "B.Cu")
		(net 687)
	)
	(segment
		(start 183.8 195.525)
		(end 184 195.725)
		(width 0.15)
		(layer "In4.Cu")
		(net 687)
	)
	(segment
		(start 183.8 198.801)
		(end 183.325 198.326)
		(width 0.15)
		(layer "In4.Cu")
		(net 687)
	)
	(segment
		(start 183.8 195.051)
		(end 183.8 195.525)
		(width 0.15)
		(layer "In4.Cu")
		(net 687)
	)
	(segment
		(start 183.325 197.4)
		(end 184 196.725)
		(width 0.15)
		(layer "In4.Cu")
		(net 687)
	)
	(segment
		(start 184 196.725)
		(end 184 195.725)
		(width 0.15)
		(layer "In4.Cu")
		(net 687)
	)
	(segment
		(start 183.325 198.326)
		(end 183.325 197.4)
		(width 0.15)
		(layer "In4.Cu")
		(net 687)
	)
	(segment
		(start 128.376501 181.301)
		(end 127.877001 181.8005)
		(width 0.256)
		(layer "F.Cu")
		(net 688)
	)
	(segment
		(start 179.511 197.806)
		(end 179.505 197.812)
		(width 0.177)
		(layer "F.Cu")
		(net 688)
	)
	(segment
		(start 180.278 197.806)
		(end 179.511 197.806)
		(width 0.177)
		(layer "F.Cu")
		(net 688)
	)
	(via
		(at 179.505 197.812)
		(size 0.45)
		(drill 0.1)
		(layers "F.Cu" "B.Cu")
		(net 688)
	)
	(via
		(at 127.877001 181.8005)
		(size 0.45)
		(drill 0.1)
		(layers "F.Cu" "B.Cu")
		(net 688)
	)
	(segment
		(start 179.917 197.4)
		(end 179.505 197.812)
		(width 0.177)
		(layer "B.Cu")
		(net 688)
	)
	(segment
		(start 180.315 198.4)
		(end 180.315 197.4)
		(width 0.15)
		(layer "B.Cu")
		(net 688)
	)
	(segment
		(start 180.315 197.4)
		(end 179.917 197.4)
		(width 0.177)
		(layer "B.Cu")
		(net 688)
	)
	(segment
		(start 177.8 184.6)
		(end 178.25 185.05)
		(width 0.1)
		(layer "In4.Cu")
		(net 688)
	)
	(segment
		(start 145.3 181.65)
		(end 145.5245 181.4255)
		(width 0.1)
		(layer "In4.Cu")
		(net 688)
	)
	(segment
		(start 179.95 192.8)
		(end 179.05 193.7)
		(width 0.1)
		(layer "In4.Cu")
		(net 688)
	)
	(segment
		(start 179.95 190.25)
		(end 179.95 192.8)
		(width 0.1)
		(layer "In4.Cu")
		(net 688)
	)
	(segment
		(start 127.877001 181.8005)
		(end 127.8995 181.8005)
		(width 0.1)
		(layer "In4.Cu")
		(net 688)
	)
	(segment
		(start 138.35 181.3)
		(end 139.35 182.3)
		(width 0.1)
		(layer "In4.Cu")
		(net 688)
	)
	(segment
		(start 148.2155 181.4255)
		(end 149.05 182.26)
		(width 0.1)
		(layer "In4.Cu")
		(net 688)
	)
	(segment
		(start 153.11 182.26)
		(end 155.45 184.6)
		(width 0.1)
		(layer "In4.Cu")
		(net 688)
	)
	(segment
		(start 127.8995 181.8005)
		(end 128.4 181.3)
		(width 0.1)
		(layer "In4.Cu")
		(net 688)
	)
	(segment
		(start 179.505 197.28367)
		(end 179.505 197.812)
		(width 0.1)
		(layer "In4.Cu")
		(net 688)
	)
	(segment
		(start 145 182.3)
		(end 145.3 182)
		(width 0.1)
		(layer "In4.Cu")
		(net 688)
	)
	(segment
		(start 178.25 185.05)
		(end 178.25 186.4)
		(width 0.1)
		(layer "In4.Cu")
		(net 688)
	)
	(segment
		(start 145.5245 181.4255)
		(end 148.2155 181.4255)
		(width 0.1)
		(layer "In4.Cu")
		(net 688)
	)
	(segment
		(start 155.45 184.6)
		(end 177.8 184.6)
		(width 0.1)
		(layer "In4.Cu")
		(net 688)
	)
	(segment
		(start 178.6 186.75)
		(end 178.6 188.9)
		(width 0.1)
		(layer "In4.Cu")
		(net 688)
	)
	(segment
		(start 139.35 182.3)
		(end 145 182.3)
		(width 0.1)
		(layer "In4.Cu")
		(net 688)
	)
	(segment
		(start 145.3 182)
		(end 145.3 181.65)
		(width 0.1)
		(layer "In4.Cu")
		(net 688)
	)
	(segment
		(start 179.05 196.82867)
		(end 179.505 197.28367)
		(width 0.1)
		(layer "In4.Cu")
		(net 688)
	)
	(segment
		(start 178.25 186.4)
		(end 178.6 186.75)
		(width 0.1)
		(layer "In4.Cu")
		(net 688)
	)
	(segment
		(start 178.6 188.9)
		(end 179.95 190.25)
		(width 0.1)
		(layer "In4.Cu")
		(net 688)
	)
	(segment
		(start 179.05 193.7)
		(end 179.05 196.82867)
		(width 0.1)
		(layer "In4.Cu")
		(net 688)
	)
	(segment
		(start 128.4 181.3)
		(end 138.35 181.3)
		(width 0.1)
		(layer "In4.Cu")
		(net 688)
	)
	(segment
		(start 149.05 182.26)
		(end 153.11 182.26)
		(width 0.1)
		(layer "In4.Cu")
		(net 688)
	)
	(segment
		(start 179.511 194.056)
		(end 179.505 194.062)
		(width 0.177)
		(layer "F.Cu")
		(net 689)
	)
	(segment
		(start 130.376501 180.301)
		(end 129.877001 180.8005)
		(width 0.256)
		(layer "F.Cu")
		(net 689)
	)
	(segment
		(start 180.278 194.056)
		(end 179.511 194.056)
		(width 0.177)
		(layer "F.Cu")
		(net 689)
	)
	(via
		(at 129.877001 180.8005)
		(size 0.45)
		(drill 0.1)
		(layers "F.Cu" "B.Cu")
		(net 689)
	)
	(via
		(at 179.505 194.062)
		(size 0.45)
		(drill 0.1)
		(layers "F.Cu" "B.Cu")
		(net 689)
	)
	(segment
		(start 180.315 194.05)
		(end 179.517 194.05)
		(width 0.177)
		(layer "B.Cu")
		(net 689)
	)
	(segment
		(start 179.517 194.05)
		(end 179.505 194.062)
		(width 0.177)
		(layer "B.Cu")
		(net 689)
	)
	(segment
		(start 180.315 193)
		(end 180.315 194.05)
		(width 0.15)
		(layer "B.Cu")
		(net 689)
	)
	(segment
		(start 145.3 181.2)
		(end 149.05 181.2)
		(width 0.1)
		(layer "In4.Cu")
		(net 689)
	)
	(segment
		(start 177.6 183.8)
		(end 179.29 185.49)
		(width 0.1)
		(layer "In4.Cu")
		(net 689)
	)
	(segment
		(start 130.252001 180.4255)
		(end 138.7755 180.4255)
		(width 0.1)
		(layer "In4.Cu")
		(net 689)
	)
	(segment
		(start 138.7755 180.4255)
		(end 139.75 181.4)
		(width 0.1)
		(layer "In4.Cu")
		(net 689)
	)
	(segment
		(start 179.29 185.49)
		(end 179.29 188.24)
		(width 0.1)
		(layer "In4.Cu")
		(net 689)
	)
	(segment
		(start 165.3 183.3)
		(end 168.9 183.3)
		(width 0.1)
		(layer "In4.Cu")
		(net 689)
	)
	(segment
		(start 139.75 181.4)
		(end 145.1 181.4)
		(width 0.1)
		(layer "In4.Cu")
		(net 689)
	)
	(segment
		(start 149.05 181.2)
		(end 149.6 181.75)
		(width 0.1)
		(layer "In4.Cu")
		(net 689)
	)
	(segment
		(start 179.29 188.24)
		(end 180.5 189.45)
		(width 0.1)
		(layer "In4.Cu")
		(net 689)
	)
	(segment
		(start 180.5 193.067)
		(end 179.505 194.062)
		(width 0.1)
		(layer "In4.Cu")
		(net 689)
	)
	(segment
		(start 155.4 183.8)
		(end 164.8 183.8)
		(width 0.1)
		(layer "In4.Cu")
		(net 689)
	)
	(segment
		(start 153.35 181.75)
		(end 155.4 183.8)
		(width 0.1)
		(layer "In4.Cu")
		(net 689)
	)
	(segment
		(start 164.8 183.8)
		(end 165.3 183.3)
		(width 0.1)
		(layer "In4.Cu")
		(net 689)
	)
	(segment
		(start 169.4 183.8)
		(end 177.6 183.8)
		(width 0.1)
		(layer "In4.Cu")
		(net 689)
	)
	(segment
		(start 145.1 181.4)
		(end 145.3 181.2)
		(width 0.1)
		(layer "In4.Cu")
		(net 689)
	)
	(segment
		(start 168.9 183.3)
		(end 169.4 183.8)
		(width 0.1)
		(layer "In4.Cu")
		(net 689)
	)
	(segment
		(start 180.5 189.45)
		(end 180.5 193.067)
		(width 0.1)
		(layer "In4.Cu")
		(net 689)
	)
	(segment
		(start 149.6 181.75)
		(end 153.35 181.75)
		(width 0.1)
		(layer "In4.Cu")
		(net 689)
	)
	(segment
		(start 129.877001 180.8005)
		(end 130.252001 180.4255)
		(width 0.1)
		(layer "In4.Cu")
		(net 689)
	)
	(segment
		(start 184.89 188.49)
		(end 184.9 188.5)
		(width 0.15)
		(layer "F.Cu")
		(net 690)
	)
	(segment
		(start 198.3 162.7)
		(end 198.321501 162.721501)
		(width 0.182)
		(layer "F.Cu")
		(net 690)
	)
	(segment
		(start 184.74 188.49)
		(end 184.89 188.49)
		(width 0.15)
		(layer "F.Cu")
		(net 690)
	)
	(segment
		(start 198.321501 162.721501)
		(end 198.321501 163.7215)
		(width 0.182)
		(layer "F.Cu")
		(net 690)
	)
	(segment
		(start 199.1765 153.8015)
		(end 198.1755 153.8015)
		(width 0.256)
		(layer "F.Cu")
		(net 690)
	)
	(segment
		(start 170.16 193.716501)
		(end 170.100501 193.776)
		(width 0.1)
		(layer "F.Cu")
		(net 690)
	)
	(segment
		(start 183.794 197.806)
		(end 183.8 197.8)
		(width 0.177)
		(layer "F.Cu")
		(net 690)
	)
	(segment
		(start 171.021501 193.716501)
		(end 170.16 193.716501)
		(width 0.201)
		(layer "F.Cu")
		(net 690)
	)
	(segment
		(start 183.027 197.806)
		(end 183.794 197.806)
		(width 0.177)
		(layer "F.Cu")
		(net 690)
	)
	(segment
		(start 198.348501 181.1725)
		(end 198.348501 180.1)
		(width 0.182)
		(layer "F.Cu")
		(net 690)
	)
	(via
		(at 170.100501 193.776)
		(size 0.45)
		(drill 0.1)
		(layers "F.Cu" "B.Cu")
		(free yes)
		(net 690)
	)
	(via
		(at 198.348501 180.1)
		(size 0.45)
		(drill 0.1)
		(layers "F.Cu" "B.Cu")
		(net 690)
	)
	(via
		(at 183.8 197.8)
		(size 0.45)
		(drill 0.1)
		(layers "F.Cu" "B.Cu")
		(net 690)
	)
	(via
		(at 198.1755 153.8015)
		(size 0.45)
		(drill 0.1)
		(layers "F.Cu" "B.Cu")
		(net 690)
	)
	(via
		(at 184.9 188.5)
		(size 0.45)
		(drill 0.1)
		(layers "F.Cu" "B.Cu")
		(net 690)
	)
	(via
		(at 198.3 162.7)
		(size 0.45)
		(drill 0.1)
		(layers "F.Cu" "B.Cu")
		(net 690)
	)
	(segment
		(start 183.8 197.8)
		(end 182.8 197.8)
		(width 0.1)
		(layer "B.Cu")
		(net 690)
	)
	(segment
		(start 198.9985 153.8015)
		(end 199 153.8)
		(width 0.15)
		(layer "B.Cu")
		(net 690)
	)
	(segment
		(start 181.285 198.4)
		(end 181.285 200.4)
		(width 0.15)
		(layer "B.Cu")
		(net 690)
	)
	(segment
		(start 182.2 198.4)
		(end 181.285 198.4)
		(width 0.1)
		(layer "B.Cu")
		(net 690)
	)
	(segment
		(start 199.5 154.3)
		(end 200.6 154.3)
		(width 0.15)
		(layer "B.Cu")
		(net 690)
	)
	(segment
		(start 184.85 188.5)
		(end 184.9 188.5)
		(width 0.198)
		(layer "B.Cu")
		(net 690)
	)
	(segment
		(start 184.36 188.99)
		(end 184.85 188.5)
		(width 0.198)
		(layer "B.Cu")
		(net 690)
	)
	(segment
		(start 182.8 197.8)
		(end 182.2 198.4)
		(width 0.1)
		(layer "B.Cu")
		(net 690)
	)
	(segment
		(start 198.1755 153.8015)
		(end 198.9985 153.8015)
		(width 0.15)
		(layer "B.Cu")
		(net 690)
	)
	(segment
		(start 199 153.8)
		(end 199.5 154.3)
		(width 0.15)
		(layer "B.Cu")
		(net 690)
	)
	(segment
		(start 184.25 188.99)
		(end 184.36 188.99)
		(width 0.198)
		(layer "B.Cu")
		(net 690)
	)
	(segment
		(start 198.348501 180.851499)
		(end 198.251499 180.948501)
		(width 0.1)
		(layer "In2.Cu")
		(net 690)
	)
	(segment
		(start 196.9485 153.8015)
		(end 194.5 156.25)
		(width 0.1)
		(layer "In2.Cu")
		(net 690)
	)
	(segment
		(start 168.9 192.15)
		(end 168.9 193.475)
		(width 0.1)
		(layer "In2.Cu")
		(net 690)
	)
	(segment
		(start 196.448501 180.948501)
		(end 195.9 180.4)
		(width 0.1)
		(layer "In2.Cu")
		(net 690)
	)
	(segment
		(start 183.025 197.525)
		(end 182.7 197.85)
		(width 0.1)
		(layer "In2.Cu")
		(net 690)
	)
	(segment
		(start 200.1 164.5)
		(end 199 163.4)
		(width 0.1)
		(layer "In2.Cu")
		(net 690)
	)
	(segment
		(start 176.75 193.45)
		(end 176.75 191.75)
		(width 0.1)
		(layer "In2.Cu")
		(net 690)
	)
	(segment
		(start 183.125 197.525)
		(end 183.4 197.8)
		(width 0.1)
		(layer "In2.Cu")
		(net 690)
	)
	(segment
		(start 195.8 163)
		(end 196.2 163.4)
		(width 0.1)
		(layer "In2.Cu")
		(net 690)
	)
	(segment
		(start 176 191)
		(end 170.05 191)
		(width 0.1)
		(layer "In2.Cu")
		(net 690)
	)
	(segment
		(start 168.9 193.475)
		(end 169.201 193.776)
		(width 0.1)
		(layer "In2.Cu")
		(net 690)
	)
	(segment
		(start 198.251499 180.948501)
		(end 198.201499 180.948501)
		(width 0.1)
		(layer "In2.Cu")
		(net 690)
	)
	(segment
		(start 196.2 163.4)
		(end 198.2 163.4)
		(width 0.1)
		(layer "In2.Cu")
		(net 690)
	)
	(segment
		(start 200.1 170.8)
		(end 200.1 164.5)
		(width 0.1)
		(layer "In2.Cu")
		(net 690)
	)
	(segment
		(start 194.5 159.6)
		(end 195.8 160.9)
		(width 0.1)
		(layer "In2.Cu")
		(net 690)
	)
	(segment
		(start 198.4 163.4)
		(end 199 163.4)
		(width 0.1)
		(layer "In2.Cu")
		(net 690)
	)
	(segment
		(start 194.5 156.25)
		(end 194.5 159.6)
		(width 0.1)
		(layer "In2.Cu")
		(net 690)
	)
	(segment
		(start 198.3 162.7)
		(end 198.3 163.2)
		(width 0.1)
		(layer "In2.Cu")
		(net 690)
	)
	(segment
		(start 183.125 197.425)
		(end 183.075 197.475)
		(width 0.1)
		(layer "In2.Cu")
		(net 690)
	)
	(segment
		(start 184.1 192.85)
		(end 183.125 193.825)
		(width 0.1)
		(layer "In2.Cu")
		(net 690)
	)
	(segment
		(start 197.15 191.2)
		(end 186.35 191.2)
		(width 0.1)
		(layer "In2.Cu")
		(net 690)
	)
	(segment
		(start 198.348501 180.848501)
		(end 198.348501 180.851499)
		(width 0.1)
		(layer "In2.Cu")
		(net 690)
	)
	(segment
		(start 185.5 189.1)
		(end 184.9 188.5)
		(width 0.1)
		(layer "In2.Cu")
		(net 690)
	)
	(segment
		(start 183.075 197.475)
		(end 183.025 197.525)
		(width 0.1)
		(layer "In2.Cu")
		(net 690)
	)
	(segment
		(start 183.125 197.425)
		(end 183.125 197.525)
		(width 0.1)
		(layer "In2.Cu")
		(net 690)
	)
	(segment
		(start 184.5 188.5)
		(end 184.1 188.9)
		(width 0.1)
		(layer "In2.Cu")
		(net 690)
	)
	(segment
		(start 198.3 163.3)
		(end 198.2 163.4)
		(width 0.1)
		(layer "In2.Cu")
		(net 690)
	)
	(segment
		(start 198.348501 180.948501)
		(end 198.201499 180.948501)
		(width 0.1)
		(layer "In2.Cu")
		(net 690)
	)
	(segment
		(start 170.05 191)
		(end 168.9 192.15)
		(width 0.1)
		(layer "In2.Cu")
		(net 690)
	)
	(segment
		(start 182.7 197.85)
		(end 181.15 197.85)
		(width 0.1)
		(layer "In2.Cu")
		(net 690)
	)
	(segment
		(start 198.1755 153.8015)
		(end 196.9485 153.8015)
		(width 0.1)
		(layer "In2.Cu")
		(net 690)
	)
	(segment
		(start 186.35 191.2)
		(end 185.5 190.35)
		(width 0.1)
		(layer "In2.Cu")
		(net 690)
	)
	(segment
		(start 176.75 191.75)
		(end 176 191)
		(width 0.1)
		(layer "In2.Cu")
		(net 690)
	)
	(segment
		(start 183.125 197.525)
		(end 183.025 197.525)
		(width 0.1)
		(layer "In2.Cu")
		(net 690)
	)
	(segment
		(start 198.2 163.4)
		(end 198.3 163.4)
		(width 0.1)
		(layer "In2.Cu")
		(net 690)
	)
	(segment
		(start 198.348501 180.848501)
		(end 198.348501 180.948501)
		(width 0.1)
		(layer "In2.Cu")
		(net 690)
	)
	(segment
		(start 184.9 188.5)
		(end 184.5 188.5)
		(width 0.1)
		(layer "In2.Cu")
		(net 690)
	)
	(segment
		(start 198.3 163.3)
		(end 198.4 163.4)
		(width 0.1)
		(layer "In2.Cu")
		(net 690)
	)
	(segment
		(start 185.5 190.35)
		(end 185.5 189.1)
		(width 0.1)
		(layer "In2.Cu")
		(net 690)
	)
	(segment
		(start 183.4 197.8)
		(end 183.8 197.8)
		(width 0.1)
		(layer "In2.Cu")
		(net 690)
	)
	(segment
		(start 195.9 173.4)
		(end 197.2 172.1)
		(width 0.1)
		(layer "In2.Cu")
		(net 690)
	)
	(segment
		(start 184.1 188.9)
		(end 184.1 192.85)
		(width 0.1)
		(layer "In2.Cu")
		(net 690)
	)
	(segment
		(start 198.3 163.2)
		(end 198.3 163.3)
		(width 0.1)
		(layer "In2.Cu")
		(net 690)
	)
	(segment
		(start 169.201 193.776)
		(end 170.100501 193.776)
		(width 0.1)
		(layer "In2.Cu")
		(net 690)
	)
	(segment
		(start 198.201499 180.948501)
		(end 196.448501 180.948501)
		(width 0.1)
		(layer "In2.Cu")
		(net 690)
	)
	(segment
		(start 195.8 160.9)
		(end 195.8 163)
		(width 0.1)
		(layer "In2.Cu")
		(net 690)
	)
	(segment
		(start 198.348501 180.948501)
		(end 200.6 183.2)
		(width 0.1)
		(layer "In2.Cu")
		(net 690)
	)
	(segment
		(start 200.6 187.75)
		(end 197.15 191.2)
		(width 0.1)
		(layer "In2.Cu")
		(net 690)
	)
	(segment
		(start 198.8 172.1)
		(end 200.1 170.8)
		(width 0.1)
		(layer "In2.Cu")
		(net 690)
	)
	(segment
		(start 197.2 172.1)
		(end 198.8 172.1)
		(width 0.1)
		(layer "In2.Cu")
		(net 690)
	)
	(segment
		(start 200.6 183.2)
		(end 200.6 187.75)
		(width 0.1)
		(layer "In2.Cu")
		(net 690)
	)
	(segment
		(start 183.075 197.475)
		(end 183.125 197.525)
		(width 0.1)
		(layer "In2.Cu")
		(net 690)
	)
	(segment
		(start 198.3 163.4)
		(end 198.4 163.4)
		(width 0.1)
		(layer "In2.Cu")
		(net 690)
	)
	(segment
		(start 181.15 197.85)
		(end 176.75 193.45)
		(width 0.1)
		(layer "In2.Cu")
		(net 690)
	)
	(segment
		(start 198.3 163.2)
		(end 198.3 163.4)
		(width 0.1)
		(layer "In2.Cu")
		(net 690)
	)
	(segment
		(start 183.125 193.825)
		(end 183.125 197.425)
		(width 0.1)
		(layer "In2.Cu")
		(net 690)
	)
	(segment
		(start 195.9 180.4)
		(end 195.9 173.4)
		(width 0.1)
		(layer "In2.Cu")
		(net 690)
	)
	(segment
		(start 198.348501 180.1)
		(end 198.348501 180.848501)
		(width 0.1)
		(layer "In2.Cu")
		(net 690)
	)
	(segment
		(start 197.695501 181.1725)
		(end 197.695501 180.104499)
		(width 0.182)
		(layer "F.Cu")
		(net 691)
	)
	(segment
		(start 171.021501 193.214501)
		(end 170.239501 193.214501)
		(width 0.201)
		(layer "F.Cu")
		(net 691)
	)
	(segment
		(start 183.027 194.056)
		(end 183.794 194.056)
		(width 0.177)
		(layer "F.Cu")
		(net 691)
	)
	(segment
		(start 199.1765 155.8025)
		(end 198.1755 155.8025)
		(width 0.256)
		(layer "F.Cu")
		(net 691)
	)
	(segment
		(start 170.239501 193.214501)
		(end 170.225 193.2)
		(width 0.201)
		(layer "F.Cu")
		(net 691)
	)
	(segment
		(start 197.695501 180.104499)
		(end 197.7 180.1)
		(width 0.182)
		(layer "F.Cu")
		(net 691)
	)
	(segment
		(start 199.1765 154.8025)
		(end 198.1755 154.8025)
		(width 0.256)
		(layer "F.Cu")
		(net 691)
	)
	(via
		(at 197.7 180.1)
		(size 0.45)
		(drill 0.1)
		(layers "F.Cu" "B.Cu")
		(net 691)
	)
	(via
		(at 198.1755 154.8025)
		(size 0.45)
		(drill 0.1)
		(layers "F.Cu" "B.Cu")
		(net 691)
	)
	(via
		(at 184.95 192.35)
		(size 0.45)
		(drill 0.1)
		(layers "F.Cu" "B.Cu")
		(net 691)
	)
	(via
		(at 183.794 194.056)
		(size 0.45)
		(drill 0.1)
		(layers "F.Cu" "B.Cu")
		(net 691)
	)
	(via
		(at 170.225 193.2)
		(size 0.45)
		(drill 0.1)
		(layers "F.Cu" "B.Cu")
		(net 691)
	)
	(via
		(at 198.1755 155.8025)
		(size 0.45)
		(drill 0.1)
		(layers "F.Cu" "B.Cu")
		(net 691)
	)
	(segment
		(start 184.65 192.3)
		(end 184.9 192.3)
		(width 0.198)
		(layer "B.Cu")
		(net 691)
	)
	(segment
		(start 184.31 191.96)
		(end 184.65 192.3)
		(width 0.198)
		(layer "B.Cu")
		(net 691)
	)
	(segment
		(start 184.9 192.3)
		(end 184.95 192.35)
		(width 0.198)
		(layer "B.Cu")
		(net 691)
	)
	(segment
		(start 201.5975 155.8025)
		(end 203.1 154.3)
		(width 0.15)
		(layer "B.Cu")
		(net 691)
	)
	(segment
		(start 181.285 193)
		(end 182.119 193)
		(width 0.15)
		(layer "B.Cu")
		(net 691)
	)
	(segment
		(start 198.1755 155.8025)
		(end 201.5975 155.8025)
		(width 0.15)
		(layer "B.Cu")
		(net 691)
	)
	(segment
		(start 182.119 193)
		(end 183.175 194.056)
		(width 0.15)
		(layer "B.Cu")
		(net 691)
	)
	(segment
		(start 181.285 193)
		(end 181.285 191)
		(width 0.15)
		(layer "B.Cu")
		(net 691)
	)
	(segment
		(start 184.25 191.96)
		(end 184.31 191.96)
		(width 0.198)
		(layer "B.Cu")
		(net 691)
	)
	(segment
		(start 183.175 194.056)
		(end 183.794 194.056)
		(width 0.15)
		(layer "B.Cu")
		(net 691)
	)
	(segment
		(start 198.4 176.45)
		(end 201.4 173.45)
		(width 0.1)
		(layer "In2.Cu")
		(net 691)
	)
	(segment
		(start 185.35 198.75)
		(end 184.924 199.176)
		(width 0.1)
		(layer "In2.Cu")
		(net 691)
	)
	(segment
		(start 198.8525 155.1025)
		(end 198.5525 154.8025)
		(width 0.1)
		(layer "In2.Cu")
		(net 691)
	)
	(segment
		(start 198.4 179.25)
		(end 198.55 179.4)
		(width 0.1)
		(layer "In2.Cu")
		(net 691)
	)
	(segment
		(start 185.35 194.6)
		(end 185.35 198.75)
		(width 0.1)
		(layer "In2.Cu")
		(net 691)
	)
	(segment
		(start 170 191.7)
		(end 169.5 192.2)
		(width 0.1)
		(layer "In2.Cu")
		(net 691)
	)
	(segment
		(start 184.924 199.176)
		(end 181.576 199.176)
		(width 0.1)
		(layer "In2.Cu")
		(net 691)
	)
	(segment
		(start 183.838 194.1)
		(end 183.794 194.056)
		(width 0.1)
		(layer "In2.Cu")
		(net 691)
	)
	(segment
		(start 169.5 192.85)
		(end 169.85 193.2)
		(width 0.1)
		(layer "In2.Cu")
		(net 691)
	)
	(segment
		(start 200.7525 155.8025)
		(end 198.9475 155.8025)
		(width 0.1)
		(layer "In2.Cu")
		(net 691)
	)
	(segment
		(start 198.4 179.25)
		(end 198.4 176.45)
		(width 0.1)
		(layer "In2.Cu")
		(net 691)
	)
	(segment
		(start 187.425 192.075)
		(end 185.225 192.075)
		(width 0.1)
		(layer "In2.Cu")
		(net 691)
	)
	(segment
		(start 198.7475 155.8025)
		(end 198.1755 155.8025)
		(width 0.1)
		(layer "In2.Cu")
		(net 691)
	)
	(segment
		(start 197.6 191.75)
		(end 187.75 191.75)
		(width 0.1)
		(layer "In2.Cu")
		(net 691)
	)
	(segment
		(start 187.75 191.75)
		(end 187.425 192.075)
		(width 0.1)
		(layer "In2.Cu")
		(net 691)
	)
	(segment
		(start 198.55 179.4)
		(end 198.4 179.4)
		(width 0.1)
		(layer "In2.Cu")
		(net 691)
	)
	(segment
		(start 176.2 193.8)
		(end 176.2 192.4)
		(width 0.1)
		(layer "In2.Cu")
		(net 691)
	)
	(segment
		(start 201.4 181.5)
		(end 201.4 187.95)
		(width 0.1)
		(layer "In2.Cu")
		(net 691)
	)
	(segment
		(start 201.4 187.95)
		(end 197.6 191.75)
		(width 0.1)
		(layer "In2.Cu")
		(net 691)
	)
	(segment
		(start 198.4 179.4)
		(end 197.7 180.1)
		(width 0.1)
		(layer "In2.Cu")
		(net 691)
	)
	(segment
		(start 198.8525 155.8025)
		(end 198.8525 155.6975)
		(width 0.1)
		(layer "In2.Cu")
		(net 691)
	)
	(segment
		(start 199.3 179.4)
		(end 201.4 181.5)
		(width 0.1)
		(layer "In2.Cu")
		(net 691)
	)
	(segment
		(start 198.8525 155.8025)
		(end 198.7475 155.8025)
		(width 0.1)
		(layer "In2.Cu")
		(net 691)
	)
	(segment
		(start 184.806 194.056)
		(end 185.35 194.6)
		(width 0.1)
		(layer "In2.Cu")
		(net 691)
	)
	(segment
		(start 198.8525 155.7075)
		(end 198.9475 155.8025)
		(width 0.1)
		(layer "In2.Cu")
		(net 691)
	)
	(segment
		(start 181.576 199.176)
		(end 176.2 193.8)
		(width 0.1)
		(layer "In2.Cu")
		(net 691)
	)
	(segment
		(start 198.8525 155.6975)
		(end 198.7475 155.8025)
		(width 0.1)
		(layer "In2.Cu")
		(net 691)
	)
	(segment
		(start 198.5525 154.8025)
		(end 198.1755 154.8025)
		(width 0.1)
		(layer "In2.Cu")
		(net 691)
	)
	(segment
		(start 183.794 194.056)
		(end 184.806 194.056)
		(width 0.1)
		(layer "In2.Cu")
		(net 691)
	)
	(segment
		(start 175.5 191.7)
		(end 170 191.7)
		(width 0.1)
		(layer "In2.Cu")
		(net 691)
	)
	(segment
		(start 198.55 179.4)
		(end 199.3 179.4)
		(width 0.1)
		(layer "In2.Cu")
		(net 691)
	)
	(segment
		(start 169.5 192.2)
		(end 169.5 192.85)
		(width 0.1)
		(layer "In2.Cu")
		(net 691)
	)
	(segment
		(start 184.95 192.35)
		(end 183.794 193.506)
		(width 0.1)
		(layer "In2.Cu")
		(net 691)
	)
	(segment
		(start 176.2 192.4)
		(end 175.5 191.7)
		(width 0.1)
		(layer "In2.Cu")
		(net 691)
	)
	(segment
		(start 198.8525 155.6975)
		(end 198.8525 155.1025)
		(width 0.1)
		(layer "In2.Cu")
		(net 691)
	)
	(segment
		(start 198.4 179.4)
		(end 198.4 179.25)
		(width 0.1)
		(layer "In2.Cu")
		(net 691)
	)
	(segment
		(start 185.225 192.075)
		(end 184.95 192.35)
		(width 0.1)
		(layer "In2.Cu")
		(net 691)
	)
	(segment
		(start 169.85 193.2)
		(end 170.225 193.2)
		(width 0.1)
		(layer "In2.Cu")
		(net 691)
	)
	(segment
		(start 183.794 193.506)
		(end 183.794 194.056)
		(width 0.1)
		(layer "In2.Cu")
		(net 691)
	)
	(segment
		(start 201.4 156.45)
		(end 200.7525 155.8025)
		(width 0.1)
		(layer "In2.Cu")
		(net 691)
	)
	(segment
		(start 198.8525 155.6975)
		(end 198.8525 155.7075)
		(width 0.1)
		(layer "In2.Cu")
		(net 691)
	)
	(segment
		(start 201.4 173.45)
		(end 201.4 156.45)
		(width 0.1)
		(layer "In2.Cu")
		(net 691)
	)
	(segment
		(start 198.9475 155.8025)
		(end 198.8525 155.8025)
		(width 0.1)
		(layer "In2.Cu")
		(net 691)
	)
	(segment
		(start 96.809501 179.191499)
		(end 96.801 179.2)
		(width 0.15)
		(layer "F.Cu")
		(net 692)
	)
	(segment
		(start 96.809501 178.323)
		(end 96.809501 179.191499)
		(width 0.15)
		(layer "F.Cu")
		(net 692)
	)
	(via
		(at 96.801 179.2)
		(size 0.45)
		(drill 0.1)
		(layers "F.Cu" "B.Cu")
		(net 692)
	)
	(segment
		(start 96.8 178.05)
		(end 96.8 179.199)
		(width 0.256)
		(layer "B.Cu")
		(net 692)
	)
	(segment
		(start 96.8 179.199)
		(end 96.801 179.2)
		(width 0.256)
		(layer "B.Cu")
		(net 692)
	)
	(segment
		(start 126.376501 163.302)
		(end 125.877001 162.8025)
		(width 0.256)
		(layer "F.Cu")
		(net 693)
	)
	(segment
		(start 119.650501 172.926)
		(end 120.150501 173.426)
		(width 0.256)
		(layer "F.Cu")
		(net 693)
	)
	(via
		(at 125.877001 162.8025)
		(size 0.45)
		(drill 0.1)
		(layers "F.Cu" "B.Cu")
		(net 693)
	)
	(via
		(at 120.150501 173.426)
		(size 0.45)
		(drill 0.1)
		(layers "F.Cu" "B.Cu")
		(net 693)
	)
	(segment
		(start 120.026501 169.3)
		(end 120.816055 169.3)
		(width 0.1)
		(layer "In6.Cu")
		(net 693)
	)
	(segment
		(start 124.084579 163.2025)
		(end 125.776001 163.2025)
		(width 0.1)
		(layer "In6.Cu")
		(net 693)
	)
	(segment
		(start 119.436947 169.3)
		(end 120.026501 169.3)
		(width 0.1)
		(layer "In6.Cu")
		(net 693)
	)
	(segment
		(start 119.436947 168.3)
		(end 120.026501 168.3)
		(width 0.1)
		(layer "In6.Cu")
		(net 693)
	)
	(segment
		(start 119.876501 172)
		(end 119.436947 172)
		(width 0.1)
		(layer "In6.Cu")
		(net 693)
	)
	(segment
		(start 120.150501 173.426)
		(end 120.150501 173.726)
		(width 0.1)
		(layer "In6.Cu")
		(net 693)
	)
	(segment
		(start 125.776001 163.2025)
		(end 125.877001 163.1015)
		(width 0.1)
		(layer "In6.Cu")
		(net 693)
	)
	(segment
		(start 120.226501 170)
		(end 119.436947 170)
		(width 0.1)
		(layer "In6.Cu")
		(net 693)
	)
	(segment
		(start 120.150501 173.726)
		(end 120.250501 173.826)
		(width 0.1)
		(layer "In6.Cu")
		(net 693)
	)
	(segment
		(start 120.250501 173.826)
		(end 120.432578 173.826)
		(width 0.1)
		(layer "In6.Cu")
		(net 693)
	)
	(segment
		(start 120.026501 167.260578)
		(end 124.084579 163.2025)
		(width 0.1)
		(layer "In6.Cu")
		(net 693)
	)
	(segment
		(start 120.026501 172.293422)
		(end 120.026501 172.15)
		(width 0.1)
		(layer "In6.Cu")
		(net 693)
	)
	(segment
		(start 119.436947 171.3)
		(end 119.876501 171.3)
		(width 0.1)
		(layer "In6.Cu")
		(net 693)
	)
	(segment
		(start 120.816055 168)
		(end 120.376501 168)
		(width 0.1)
		(layer "In6.Cu")
		(net 693)
	)
	(segment
		(start 120.026501 167.65)
		(end 120.026501 167.260578)
		(width 0.1)
		(layer "In6.Cu")
		(net 693)
	)
	(segment
		(start 119.876501 171.3)
		(end 120.816055 171.3)
		(width 0.1)
		(layer "In6.Cu")
		(net 693)
	)
	(segment
		(start 125.877001 163.1015)
		(end 125.877001 162.8025)
		(width 0.1)
		(layer "In6.Cu")
		(net 693)
	)
	(segment
		(start 120.6 172.866921)
		(end 120.026501 172.293422)
		(width 0.1)
		(layer "In6.Cu")
		(net 693)
	)
	(segment
		(start 120.226501 169)
		(end 119.436947 169)
		(width 0.1)
		(layer "In6.Cu")
		(net 693)
	)
	(segment
		(start 120.816055 169)
		(end 120.226501 169)
		(width 0.1)
		(layer "In6.Cu")
		(net 693)
	)
	(segment
		(start 120.026501 168.3)
		(end 120.816055 168.3)
		(width 0.1)
		(layer "In6.Cu")
		(net 693)
	)
	(segment
		(start 120.226501 171)
		(end 119.436947 171)
		(width 0.1)
		(layer "In6.Cu")
		(net 693)
	)
	(segment
		(start 120.6 173.658578)
		(end 120.6 172.866921)
		(width 0.1)
		(layer "In6.Cu")
		(net 693)
	)
	(segment
		(start 120.432578 173.826)
		(end 120.6 173.658578)
		(width 0.1)
		(layer "In6.Cu")
		(net 693)
	)
	(segment
		(start 119.436947 170.3)
		(end 120.026501 170.3)
		(width 0.1)
		(layer "In6.Cu")
		(net 693)
	)
	(segment
		(start 120.816055 170)
		(end 120.226501 170)
		(width 0.1)
		(layer "In6.Cu")
		(net 693)
	)
	(segment
		(start 120.816055 171)
		(end 120.226501 171)
		(width 0.1)
		(layer "In6.Cu")
		(net 693)
	)
	(segment
		(start 120.026501 170.3)
		(end 120.816055 170.3)
		(width 0.1)
		(layer "In6.Cu")
		(net 693)
	)
	(arc
		(start 119.436947 172)
		(mid 119.18946 171.897487)
		(end 119.086947 171.65)
		(width 0.1)
		(layer "In6.Cu")
		(net 693)
	)
	(arc
		(start 120.966055 170.15)
		(mid 120.922121 170.043934)
		(end 120.816055 170)
		(width 0.1)
		(layer "In6.Cu")
		(net 693)
	)
	(arc
		(start 120.816055 169.3)
		(mid 120.922121 169.256066)
		(end 120.966055 169.15)
		(width 0.1)
		(layer "In6.Cu")
		(net 693)
	)
	(arc
		(start 119.436947 170)
		(mid 119.18946 169.897487)
		(end 119.086947 169.65)
		(width 0.1)
		(layer "In6.Cu")
		(net 693)
	)
	(arc
		(start 119.436947 169)
		(mid 119.18946 168.897487)
		(end 119.086947 168.65)
		(width 0.1)
		(layer "In6.Cu")
		(net 693)
	)
	(arc
		(start 120.966055 171.15)
		(mid 120.922121 171.043934)
		(end 120.816055 171)
		(width 0.1)
		(layer "In6.Cu")
		(net 693)
	)
	(arc
		(start 119.086947 168.65)
		(mid 119.18946 168.402513)
		(end 119.436947 168.3)
		(width 0.1)
		(layer "In6.Cu")
		(net 693)
	)
	(arc
		(start 120.816055 168.3)
		(mid 120.922121 168.256066)
		(end 120.966055 168.15)
		(width 0.1)
		(layer "In6.Cu")
		(net 693)
	)
	(arc
		(start 120.966055 168.15)
		(mid 120.922121 168.043934)
		(end 120.816055 168)
		(width 0.1)
		(layer "In6.Cu")
		(net 693)
	)
	(arc
		(start 120.816055 171.3)
		(mid 120.922121 171.256066)
		(end 120.966055 171.15)
		(width 0.1)
		(layer "In6.Cu")
		(net 693)
	)
	(arc
		(start 119.086947 171.65)
		(mid 119.18946 171.402513)
		(end 119.436947 171.3)
		(width 0.1)
		(layer "In6.Cu")
		(net 693)
	)
	(arc
		(start 120.816055 170.3)
		(mid 120.922121 170.256066)
		(end 120.966055 170.15)
		(width 0.1)
		(layer "In6.Cu")
		(net 693)
	)
	(arc
		(start 120.376501 168)
		(mid 120.129014 167.897487)
		(end 120.026501 167.65)
		(width 0.1)
		(layer "In6.Cu")
		(net 693)
	)
	(arc
		(start 119.436947 171)
		(mid 119.18946 170.897487)
		(end 119.086947 170.65)
		(width 0.1)
		(layer "In6.Cu")
		(net 693)
	)
	(arc
		(start 119.086947 169.65)
		(mid 119.18946 169.402513)
		(end 119.436947 169.3)
		(width 0.1)
		(layer "In6.Cu")
		(net 693)
	)
	(arc
		(start 119.086947 170.65)
		(mid 119.18946 170.402513)
		(end 119.436947 170.3)
		(width 0.1)
		(layer "In6.Cu")
		(net 693)
	)
	(arc
		(start 120.026501 172.15)
		(mid 119.982567 172.043934)
		(end 119.876501 172)
		(width 0.1)
		(layer "In6.Cu")
		(net 693)
	)
	(arc
		(start 120.966055 169.15)
		(mid 120.922121 169.043934)
		(end 120.816055 169)
		(width 0.1)
		(layer "In6.Cu")
		(net 693)
	)
	(segment
		(start 126.376501 164.302001)
		(end 125.877001 163.8025)
		(width 0.256)
		(layer "F.Cu")
		(net 694)
	)
	(segment
		(start 119.650501 173.926)
		(end 120.150501 174.426)
		(width 0.256)
		(layer "F.Cu")
		(net 694)
	)
	(via
		(at 120.150501 174.426)
		(size 0.45)
		(drill 0.1)
		(layers "F.Cu" "B.Cu")
		(net 694)
	)
	(via
		(at 125.877001 163.8025)
		(size 0.45)
		(drill 0.1)
		(layers "F.Cu" "B.Cu")
		(net 694)
	)
	(segment
		(start 120.150501 174.426)
		(end 120.150501 174.126)
		(width 0.1)
		(layer "In6.Cu")
		(net 694)
	)
	(segment
		(start 119.436947 171.5)
		(end 119.876501 171.5)
		(width 0.1)
		(layer "In6.Cu")
		(net 694)
	)
	(segment
		(start 119.876501 171.8)
		(end 119.436947 171.8)
		(width 0.1)
		(layer "In6.Cu")
		(net 694)
	)
	(segment
		(start 120.226501 167.65)
		(end 120.226501 167.343422)
		(width 0.1)
		(layer "In6.Cu")
		(net 694)
	)
	(segment
		(start 120.250501 174.026)
		(end 120.515422 174.026)
		(width 0.1)
		(layer "In6.Cu")
		(net 694)
	)
	(segment
		(start 119.876501 171.5)
		(end 120.816055 171.5)
		(width 0.1)
		(layer "In6.Cu")
		(net 694)
	)
	(segment
		(start 124.167423 163.4025)
		(end 124.974001 163.4025)
		(width 0.1)
		(layer "In6.Cu")
		(net 694)
	)
	(segment
		(start 125.274001 163.502691)
		(end 125.274001 163.5025)
		(width 0.1)
		(layer "In6.Cu")
		(net 694)
	)
	(segment
		(start 120.226501 168.8)
		(end 119.436947 168.8)
		(width 0.1)
		(layer "In6.Cu")
		(net 694)
	)
	(segment
		(start 119.436947 169.5)
		(end 120.026501 169.5)
		(width 0.1)
		(layer "In6.Cu")
		(net 694)
	)
	(segment
		(start 120.816055 170.8)
		(end 120.226501 170.8)
		(width 0.1)
		(layer "In6.Cu")
		(net 694)
	)
	(segment
		(start 119.436947 168.5)
		(end 120.026501 168.5)
		(width 0.1)
		(layer "In6.Cu")
		(net 694)
	)
	(segment
		(start 125.374001 163.4025)
		(end 125.727001 163.4025)
		(width 0.1)
		(layer "In6.Cu")
		(net 694)
	)
	(segment
		(start 120.226501 169.8)
		(end 119.436947 169.8)
		(width 0.1)
		(layer "In6.Cu")
		(net 694)
	)
	(segment
		(start 120.026501 170.5)
		(end 120.816055 170.5)
		(width 0.1)
		(layer "In6.Cu")
		(net 694)
	)
	(segment
		(start 119.436947 170.5)
		(end 120.026501 170.5)
		(width 0.1)
		(layer "In6.Cu")
		(net 694)
	)
	(segment
		(start 120.226501 170.8)
		(end 119.436947 170.8)
		(width 0.1)
		(layer "In6.Cu")
		(net 694)
	)
	(segment
		(start 120.816055 167.8)
		(end 120.376501 167.8)
		(width 0.1)
		(layer "In6.Cu")
		(net 694)
	)
	(segment
		(start 120.226501 167.343422)
		(end 124.167423 163.4025)
		(width 0.1)
		(layer "In6.Cu")
		(net 694)
	)
	(segment
		(start 120.026501 169.5)
		(end 120.816055 169.5)
		(width 0.1)
		(layer "In6.Cu")
		(net 694)
	)
	(segment
		(start 120.026501 168.5)
		(end 120.816055 168.5)
		(width 0.1)
		(layer "In6.Cu")
		(net 694)
	)
	(segment
		(start 120.8 172.784077)
		(end 120.226501 172.210578)
		(width 0.1)
		(layer "In6.Cu")
		(net 694)
	)
	(segment
		(start 120.816055 169.8)
		(end 120.226501 169.8)
		(width 0.1)
		(layer "In6.Cu")
		(net 694)
	)
	(segment
		(start 120.150501 174.126)
		(end 120.250501 174.026)
		(width 0.1)
		(layer "In6.Cu")
		(net 694)
	)
	(segment
		(start 120.8 173.741422)
		(end 120.8 172.784077)
		(width 0.1)
		(layer "In6.Cu")
		(net 694)
	)
	(segment
		(start 120.515422 174.026)
		(end 120.8 173.741422)
		(width 0.1)
		(layer "In6.Cu")
		(net 694)
	)
	(segment
		(start 125.877001 163.5525)
		(end 125.877001 163.8025)
		(width 0.1)
		(layer "In6.Cu")
		(net 694)
	)
	(segment
		(start 120.226501 172.210578)
		(end 120.226501 172.15)
		(width 0.1)
		(layer "In6.Cu")
		(net 694)
	)
	(segment
		(start 125.074001 163.5025)
		(end 125.074001 163.502691)
		(width 0.1)
		(layer "In6.Cu")
		(net 694)
	)
	(segment
		(start 120.816055 168.8)
		(end 120.226501 168.8)
		(width 0.1)
		(layer "In6.Cu")
		(net 694)
	)
	(segment
		(start 125.727001 163.4025)
		(end 125.877001 163.5525)
		(width 0.1)
		(layer "In6.Cu")
		(net 694)
	)
	(arc
		(start 119.286947 170.65)
		(mid 119.330881 170.543934)
		(end 119.436947 170.5)
		(width 0.1)
		(layer "In6.Cu")
		(net 694)
	)
	(arc
		(start 125.074001 163.502691)
		(mid 125.10329 163.573402)
		(end 125.174001 163.602691)
		(width 0.1)
		(layer "In6.Cu")
		(net 694)
	)
	(arc
		(start 119.436947 168.8)
		(mid 119.330881 168.756066)
		(end 119.286947 168.65)
		(width 0.1)
		(layer "In6.Cu")
		(net 694)
	)
	(arc
		(start 120.816055 170.5)
		(mid 121.063542 170.397487)
		(end 121.166055 170.15)
		(width 0.1)
		(layer "In6.Cu")
		(net 694)
	)
	(arc
		(start 120.816055 169.5)
		(mid 121.063542 169.397487)
		(end 121.166055 169.15)
		(width 0.1)
		(layer "In6.Cu")
		(net 694)
	)
	(arc
		(start 119.436947 171.8)
		(mid 119.330881 171.756066)
		(end 119.286947 171.65)
		(width 0.1)
		(layer "In6.Cu")
		(net 694)
	)
	(arc
		(start 120.226501 172.15)
		(mid 120.123988 171.902513)
		(end 119.876501 171.8)
		(width 0.1)
		(layer "In6.Cu")
		(net 694)
	)
	(arc
		(start 120.816055 168.5)
		(mid 121.063542 168.397487)
		(end 121.166055 168.15)
		(width 0.1)
		(layer "In6.Cu")
		(net 694)
	)
	(arc
		(start 121.166055 170.15)
		(mid 121.063542 169.902513)
		(end 120.816055 169.8)
		(width 0.1)
		(layer "In6.Cu")
		(net 694)
	)
	(arc
		(start 125.274001 163.5025)
		(mid 125.30329 163.431789)
		(end 125.374001 163.4025)
		(width 0.1)
		(layer "In6.Cu")
		(net 694)
	)
	(arc
		(start 119.286947 171.65)
		(mid 119.330881 171.543934)
		(end 119.436947 171.5)
		(width 0.1)
		(layer "In6.Cu")
		(net 694)
	)
	(arc
		(start 119.436947 170.8)
		(mid 119.330881 170.756066)
		(end 119.286947 170.65)
		(width 0.1)
		(layer "In6.Cu")
		(net 694)
	)
	(arc
		(start 124.974001 163.4025)
		(mid 125.044712 163.431789)
		(end 125.074001 163.5025)
		(width 0.1)
		(layer "In6.Cu")
		(net 694)
	)
	(arc
		(start 121.166055 171.15)
		(mid 121.063542 170.902513)
		(end 120.816055 170.8)
		(width 0.1)
		(layer "In6.Cu")
		(net 694)
	)
	(arc
		(start 119.286947 169.65)
		(mid 119.330881 169.543934)
		(end 119.436947 169.5)
		(width 0.1)
		(layer "In6.Cu")
		(net 694)
	)
	(arc
		(start 121.166055 169.15)
		(mid 121.063542 168.902513)
		(end 120.816055 168.8)
		(width 0.1)
		(layer "In6.Cu")
		(net 694)
	)
	(arc
		(start 120.816055 171.5)
		(mid 121.063542 171.397487)
		(end 121.166055 171.15)
		(width 0.1)
		(layer "In6.Cu")
		(net 694)
	)
	(arc
		(start 121.166055 168.15)
		(mid 121.063542 167.902513)
		(end 120.816055 167.8)
		(width 0.1)
		(layer "In6.Cu")
		(net 694)
	)
	(arc
		(start 119.286947 168.65)
		(mid 119.330881 168.543934)
		(end 119.436947 168.5)
		(width 0.1)
		(layer "In6.Cu")
		(net 694)
	)
	(arc
		(start 125.174001 163.602691)
		(mid 125.244712 163.573402)
		(end 125.274001 163.502691)
		(width 0.1)
		(layer "In6.Cu")
		(net 694)
	)
	(arc
		(start 119.436947 169.8)
		(mid 119.330881 169.756066)
		(end 119.286947 169.65)
		(width 0.1)
		(layer "In6.Cu")
		(net 694)
	)
	(arc
		(start 120.376501 167.8)
		(mid 120.270435 167.756066)
		(end 120.226501 167.65)
		(width 0.1)
		(layer "In6.Cu")
		(net 694)
	)
	(segment
		(start 129.376501 164.302)
		(end 128.877001 163.8025)
		(width 0.256)
		(layer "F.Cu")
		(net 695)
	)
	(segment
		(start 118.650501 174.926)
		(end 118.150501 175.426)
		(width 0.256)
		(layer "F.Cu")
		(net 695)
	)
	(via
		(at 128.877001 163.8025)
		(size 0.45)
		(drill 0.1)
		(layers "F.Cu" "B.Cu")
		(net 695)
	)
	(via
		(at 118.150501 175.426)
		(size 0.45)
		(drill 0.1)
		(layers "F.Cu" "B.Cu")
		(net 695)
	)
	(segment
		(start 121.879504 168.101)
		(end 122.421498 168.101)
		(width 0.1)
		(layer "In6.Cu")
		(net 695)
	)
	(segment
		(start 122.325501 173.001)
		(end 122.421498 173.001)
		(width 0.1)
		(layer "In6.Cu")
		(net 695)
	)
	(segment
		(start 120.405501 175.873)
		(end 120.650501 175.628)
		(width 0.1)
		(layer "In6.Cu")
		(net 695)
	)
	(segment
		(start 121.879504 171.601)
		(end 122.421498 171.601)
		(width 0.1)
		(layer "In6.Cu")
		(net 695)
	)
	(segment
		(start 122.421498 168.451)
		(end 121.879504 168.451)
		(width 0.1)
		(layer "In6.Cu")
		(net 695)
	)
	(segment
		(start 122.421498 171.251)
		(end 121.879504 171.251)
		(width 0.1)
		(layer "In6.Cu")
		(net 695)
	)
	(segment
		(start 122.421498 171.951)
		(end 121.879504 171.951)
		(width 0.1)
		(layer "In6.Cu")
		(net 695)
	)
	(segment
		(start 122.421498 172.651)
		(end 121.879504 172.651)
		(width 0.1)
		(layer "In6.Cu")
		(net 695)
	)
	(segment
		(start 124.823001 164.276)
		(end 128.403501 164.276)
		(width 0.1)
		(layer "In6.Cu")
		(net 695)
	)
	(segment
		(start 118.150501 175.426)
		(end 119.100501 175.426)
		(width 0.1)
		(layer "In6.Cu")
		(net 695)
	)
	(segment
		(start 120.650501 174.926)
		(end 122.150501 173.426)
		(width 0.1)
		(layer "In6.Cu")
		(net 695)
	)
	(segment
		(start 121.879504 169.501)
		(end 122.421498 169.501)
		(width 0.1)
		(layer "In6.Cu")
		(net 695)
	)
	(segment
		(start 122.150501 166.9485)
		(end 124.823001 164.276)
		(width 0.1)
		(layer "In6.Cu")
		(net 695)
	)
	(segment
		(start 121.879504 170.201)
		(end 122.421498 170.201)
		(width 0.1)
		(layer "In6.Cu")
		(net 695)
	)
	(segment
		(start 122.150501 173.426)
		(end 122.150501 173.176)
		(width 0.1)
		(layer "In6.Cu")
		(net 695)
	)
	(segment
		(start 121.879504 172.301)
		(end 122.421498 172.301)
		(width 0.1)
		(layer "In6.Cu")
		(net 695)
	)
	(segment
		(start 122.421498 169.151)
		(end 121.879504 169.151)
		(width 0.1)
		(layer "In6.Cu")
		(net 695)
	)
	(segment
		(start 122.150501 167.226)
		(end 122.150501 166.9485)
		(width 0.1)
		(layer "In6.Cu")
		(net 695)
	)
	(segment
		(start 121.879504 170.901)
		(end 122.421498 170.901)
		(width 0.1)
		(layer "In6.Cu")
		(net 695)
	)
	(segment
		(start 120.650501 175.628)
		(end 120.650501 174.926)
		(width 0.1)
		(layer "In6.Cu")
		(net 695)
	)
	(segment
		(start 121.879504 167.401)
		(end 121.975501 167.401)
		(width 0.1)
		(layer "In6.Cu")
		(net 695)
	)
	(segment
		(start 122.421498 169.851)
		(end 121.879504 169.851)
		(width 0.1)
		(layer "In6.Cu")
		(net 695)
	)
	(segment
		(start 122.421498 170.551)
		(end 121.879504 170.551)
		(width 0.1)
		(layer "In6.Cu")
		(net 695)
	)
	(segment
		(start 122.421498 167.751)
		(end 121.879504 167.751)
		(width 0.1)
		(layer "In6.Cu")
		(net 695)
	)
	(segment
		(start 119.100501 175.426)
		(end 119.547501 175.873)
		(width 0.1)
		(layer "In6.Cu")
		(net 695)
	)
	(segment
		(start 128.403501 164.276)
		(end 128.877001 163.8025)
		(width 0.1)
		(layer "In6.Cu")
		(net 695)
	)
	(segment
		(start 121.879504 168.801)
		(end 122.421498 168.801)
		(width 0.1)
		(layer "In6.Cu")
		(net 695)
	)
	(segment
		(start 119.547501 175.873)
		(end 120.405501 175.873)
		(width 0.1)
		(layer "In6.Cu")
		(net 695)
	)
	(arc
		(start 121.704504 170.376)
		(mid 121.75576 170.252256)
		(end 121.879504 170.201)
		(width 0.1)
		(layer "In6.Cu")
		(net 695)
	)
	(arc
		(start 121.704504 169.676)
		(mid 121.75576 169.552256)
		(end 121.879504 169.501)
		(width 0.1)
		(layer "In6.Cu")
		(net 695)
	)
	(arc
		(start 122.596498 167.926)
		(mid 122.545242 167.802256)
		(end 122.421498 167.751)
		(width 0.1)
		(layer "In6.Cu")
		(net 695)
	)
	(arc
		(start 122.596498 169.326)
		(mid 122.545242 169.202256)
		(end 122.421498 169.151)
		(width 0.1)
		(layer "In6.Cu")
		(net 695)
	)
	(arc
		(start 122.150501 173.176)
		(mid 122.201757 173.052256)
		(end 122.325501 173.001)
		(width 0.1)
		(layer "In6.Cu")
		(net 695)
	)
	(arc
		(start 122.596498 168.626)
		(mid 122.545242 168.502256)
		(end 122.421498 168.451)
		(width 0.1)
		(layer "In6.Cu")
		(net 695)
	)
	(arc
		(start 122.421498 170.901)
		(mid 122.545242 170.849744)
		(end 122.596498 170.726)
		(width 0.1)
		(layer "In6.Cu")
		(net 695)
	)
	(arc
		(start 121.704504 171.076)
		(mid 121.75576 170.952256)
		(end 121.879504 170.901)
		(width 0.1)
		(layer "In6.Cu")
		(net 695)
	)
	(arc
		(start 122.421498 168.101)
		(mid 122.545242 168.049744)
		(end 122.596498 167.926)
		(width 0.1)
		(layer "In6.Cu")
		(net 695)
	)
	(arc
		(start 121.879504 168.451)
		(mid 121.75576 168.399744)
		(end 121.704504 168.276)
		(width 0.1)
		(layer "In6.Cu")
		(net 695)
	)
	(arc
		(start 121.704504 168.276)
		(mid 121.75576 168.152256)
		(end 121.879504 168.101)
		(width 0.1)
		(layer "In6.Cu")
		(net 695)
	)
	(arc
		(start 122.421498 170.201)
		(mid 122.545242 170.149744)
		(end 122.596498 170.026)
		(width 0.1)
		(layer "In6.Cu")
		(net 695)
	)
	(arc
		(start 121.704504 172.476)
		(mid 121.75576 172.352256)
		(end 121.879504 172.301)
		(width 0.1)
		(layer "In6.Cu")
		(net 695)
	)
	(arc
		(start 121.975501 167.401)
		(mid 122.099245 167.349744)
		(end 122.150501 167.226)
		(width 0.1)
		(layer "In6.Cu")
		(net 695)
	)
	(arc
		(start 121.879504 169.151)
		(mid 121.75576 169.099744)
		(end 121.704504 168.976)
		(width 0.1)
		(layer "In6.Cu")
		(net 695)
	)
	(arc
		(start 122.421498 173.001)
		(mid 122.545242 172.949744)
		(end 122.596498 172.826)
		(width 0.1)
		(layer "In6.Cu")
		(net 695)
	)
	(arc
		(start 122.421498 168.801)
		(mid 122.545242 168.749744)
		(end 122.596498 168.626)
		(width 0.1)
		(layer "In6.Cu")
		(net 695)
	)
	(arc
		(start 121.879504 169.851)
		(mid 121.75576 169.799744)
		(end 121.704504 169.676)
		(width 0.1)
		(layer "In6.Cu")
		(net 695)
	)
	(arc
		(start 121.879504 167.751)
		(mid 121.75576 167.699744)
		(end 121.704504 167.576)
		(width 0.1)
		(layer "In6.Cu")
		(net 695)
	)
	(arc
		(start 121.704504 168.976)
		(mid 121.75576 168.852256)
		(end 121.879504 168.801)
		(width 0.1)
		(layer "In6.Cu")
		(net 695)
	)
	(arc
		(start 122.596498 170.026)
		(mid 122.545242 169.902256)
		(end 122.421498 169.851)
		(width 0.1)
		(layer "In6.Cu")
		(net 695)
	)
	(arc
		(start 121.879504 172.651)
		(mid 121.75576 172.599744)
		(end 121.704504 172.476)
		(width 0.1)
		(layer "In6.Cu")
		(net 695)
	)
	(arc
		(start 122.596498 172.826)
		(mid 122.545242 172.702256)
		(end 122.421498 172.651)
		(width 0.1)
		(layer "In6.Cu")
		(net 695)
	)
	(arc
		(start 121.879504 171.251)
		(mid 121.75576 171.199744)
		(end 121.704504 171.076)
		(width 0.1)
		(layer "In6.Cu")
		(net 695)
	)
	(arc
		(start 122.421498 171.601)
		(mid 122.545242 171.549744)
		(end 122.596498 171.426)
		(width 0.1)
		(layer "In6.Cu")
		(net 695)
	)
	(arc
		(start 121.704504 167.576)
		(mid 121.75576 167.452256)
		(end 121.879504 167.401)
		(width 0.1)
		(layer "In6.Cu")
		(net 695)
	)
	(arc
		(start 122.421498 172.301)
		(mid 122.545242 172.249744)
		(end 122.596498 172.126)
		(width 0.1)
		(layer "In6.Cu")
		(net 695)
	)
	(arc
		(start 121.879504 170.551)
		(mid 121.75576 170.499744)
		(end 121.704504 170.376)
		(width 0.1)
		(layer "In6.Cu")
		(net 695)
	)
	(arc
		(start 122.421498 169.501)
		(mid 122.545242 169.449744)
		(end 122.596498 169.326)
		(width 0.1)
		(layer "In6.Cu")
		(net 695)
	)
	(arc
		(start 122.596498 172.126)
		(mid 122.545242 172.002256)
		(end 122.421498 171.951)
		(width 0.1)
		(layer "In6.Cu")
		(net 695)
	)
	(arc
		(start 121.879504 171.951)
		(mid 121.75576 171.899744)
		(end 121.704504 171.776)
		(width 0.1)
		(layer "In6.Cu")
		(net 695)
	)
	(arc
		(start 121.704504 171.776)
		(mid 121.75576 171.652256)
		(end 121.879504 171.601)
		(width 0.1)
		(layer "In6.Cu")
		(net 695)
	)
	(arc
		(start 122.596498 170.726)
		(mid 122.545242 170.602256)
		(end 122.421498 170.551)
		(width 0.1)
		(layer "In6.Cu")
		(net 695)
	)
	(arc
		(start 122.596498 171.426)
		(mid 122.545242 171.302256)
		(end 122.421498 171.251)
		(width 0.1)
		(layer "In6.Cu")
		(net 695)
	)
	(segment
		(start 128.376501 162.302)
		(end 127.877001 161.8025)
		(width 0.256)
		(layer "F.Cu")
		(net 696)
	)
	(segment
		(start 118.650501 175.926)
		(end 118.150501 176.426)
		(width 0.256)
		(layer "F.Cu")
		(net 696)
	)
	(via
		(at 127.877001 161.8025)
		(size 0.45)
		(drill 0.1)
		(layers "F.Cu" "B.Cu")
		(net 696)
	)
	(via
		(at 118.150501 176.426)
		(size 0.45)
		(drill 0.1)
		(layers "F.Cu" "B.Cu")
		(net 696)
	)
	(segment
		(start 127.447128 161.554595)
		(end 127.449723 161.551999)
		(width 0.1)
		(layer "In6.Cu")
		(net 696)
	)
	(segment
		(start 114.626501 174.802)
		(end 114.626501 167.123499)
		(width 0.1)
		(layer "In6.Cu")
		(net 696)
	)
	(segment
		(start 116.627501 176.052)
		(end 116.477501 175.902)
		(width 0.1)
		(layer "In6.Cu")
		(net 696)
	)
	(segment
		(start 127.449723 161.551999)
		(end 127.449724 161.551999)
		(width 0.1)
		(layer "In6.Cu")
		(net 696)
	)
	(segment
		(start 127.272947 161.375222)
		(end 127.270351 161.377817)
		(width 0.1)
		(layer "In6.Cu")
		(net 696)
	)
	(segment
		(start 127.626501 161.552)
		(end 127.877001 161.8025)
		(width 0.1)
		(layer "In6.Cu")
		(net 696)
	)
	(segment
		(start 127.270351 161.377817)
		(end 127.270351 161.377818)
		(width 0.1)
		(layer "In6.Cu")
		(net 696)
	)
	(segment
		(start 126.951501 160.877)
		(end 127.272946 161.198445)
		(width 0.1)
		(layer "In6.Cu")
		(net 696)
	)
	(segment
		(start 117.776501 176.052)
		(end 116.627501 176.052)
		(width 0.1)
		(layer "In6.Cu")
		(net 696)
	)
	(segment
		(start 114.626501 167.123499)
		(end 118.21425 163.53575)
		(width 0.1)
		(layer "In6.Cu")
		(net 696)
	)
	(segment
		(start 118.150501 176.426)
		(end 117.776501 176.052)
		(width 0.1)
		(layer "In6.Cu")
		(net 696)
	)
	(segment
		(start 118.21425 163.21425)
		(end 120.551501 160.877)
		(width 0.1)
		(layer "In6.Cu")
		(net 696)
	)
	(segment
		(start 118.21425 163.53575)
		(end 118.21425 163.21425)
		(width 0.1)
		(layer "In6.Cu")
		(net 696)
	)
	(segment
		(start 120.551501 160.877)
		(end 126.951501 160.877)
		(width 0.1)
		(layer "In6.Cu")
		(net 696)
	)
	(segment
		(start 127.270352 161.554595)
		(end 127.270351 161.554594)
		(width 0.1)
		(layer "In6.Cu")
		(net 696)
	)
	(segment
		(start 116.477501 175.902)
		(end 115.726501 175.902)
		(width 0.1)
		(layer "In6.Cu")
		(net 696)
	)
	(segment
		(start 115.726501 175.902)
		(end 114.626501 174.802)
		(width 0.1)
		(layer "In6.Cu")
		(net 696)
	)
	(arc
		(start 127.449724 161.551999)
		(mid 127.538113 161.515388)
		(end 127.626501 161.552)
		(width 0.1)
		(layer "In6.Cu")
		(net 696)
	)
	(arc
		(start 127.270351 161.377818)
		(mid 127.23374 161.466207)
		(end 127.270352 161.554595)
		(width 0.1)
		(layer "In6.Cu")
		(net 696)
	)
	(arc
		(start 127.272946 161.198445)
		(mid 127.309558 161.286833)
		(end 127.272947 161.375222)
		(width 0.1)
		(layer "In6.Cu")
		(net 696)
	)
	(arc
		(start 127.270351 161.554594)
		(mid 127.358739 161.591206)
		(end 127.447128 161.554595)
		(width 0.1)
		(layer "In6.Cu")
		(net 696)
	)
	(segment
		(start 127.3765 164.302)
		(end 126.877001 163.8025)
		(width 0.256)
		(layer "F.Cu")
		(net 697)
	)
	(segment
		(start 117.650501 173.926)
		(end 117.150501 174.426)
		(width 0.256)
		(layer "F.Cu")
		(net 697)
	)
	(via
		(at 126.877001 163.8025)
		(size 0.45)
		(drill 0.1)
		(layers "F.Cu" "B.Cu")
		(net 697)
	)
	(via
		(at 117.150501 174.426)
		(size 0.45)
		(drill 0.1)
		(layers "F.Cu" "B.Cu")
		(net 697)
	)
	(segment
		(start 119.23525 166.532848)
		(end 119.543653 166.84125)
		(width 0.1)
		(layer "In6.Cu")
		(net 697)
	)
	(segment
		(start 121.276063 165.108842)
		(end 121.276061 165.108843)
		(width 0.1)
		(layer "In6.Cu")
		(net 697)
	)
	(segment
		(start 121.616835 164.459666)
		(end 121.462634 164.305465)
		(width 0.1)
		(layer "In6.Cu")
		(net 697)
	)
	(segment
		(start 120.131913 165.944591)
		(end 120.131913 165.944588)
		(width 0.1)
		(layer "In6.Cu")
		(net 697)
	)
	(segment
		(start 119.296167 167.088738)
		(end 119.296165 167.088739)
		(width 0.1)
		(layer "In6.Cu")
		(net 697)
	)
	(segment
		(start 119.235251 166.28536)
		(end 119.23525 166.285361)
		(width 0.1)
		(layer "In6.Cu")
		(net 697)
	)
	(segment
		(start 121.276061 165.108843)
		(end 121.121861 164.954643)
		(width 0.1)
		(layer "In6.Cu")
		(net 697)
	)
	(segment
		(start 118.740276 167.027821)
		(end 118.740276 167.027822)
		(width 0.1)
		(layer "In6.Cu")
		(net 697)
	)
	(segment
		(start 119.730224 166.037874)
		(end 120.038627 166.346276)
		(width 0.1)
		(layer "In6.Cu")
		(net 697)
	)
	(segment
		(start 118.740277 166.780334)
		(end 118.740276 166.780335)
		(width 0.1)
		(layer "In6.Cu")
		(net 697)
	)
	(segment
		(start 121.215146 164.552952)
		(end 121.523549 164.861354)
		(width 0.1)
		(layer "In6.Cu")
		(net 697)
	)
	(segment
		(start 119.141965 166.934536)
		(end 118.987764 166.780335)
		(width 0.1)
		(layer "In6.Cu")
		(net 697)
	)
	(segment
		(start 126.252001 163.1775)
		(end 126.252001 162.647169)
		(width 0.1)
		(layer "In6.Cu")
		(net 697)
	)
	(segment
		(start 122.018524 164.613867)
		(end 122.018523 164.613868)
		(width 0.1)
		(layer "In6.Cu")
		(net 697)
	)
	(segment
		(start 120.626887 165.449617)
		(end 120.626887 165.449614)
		(width 0.1)
		(layer "In6.Cu")
		(net 697)
	)
	(segment
		(start 120.626887 165.449614)
		(end 120.472686 165.295413)
		(width 0.1)
		(layer "In6.Cu")
		(net 697)
	)
	(segment
		(start 120.781089 165.603816)
		(end 120.781087 165.603817)
		(width 0.1)
		(layer "In6.Cu")
		(net 697)
	)
	(segment
		(start 123.374501 162.702)
		(end 123.225501 162.851)
		(width 0.1)
		(layer "In6.Cu")
		(net 697)
	)
	(segment
		(start 119.730224 166.037873)
		(end 119.730224 166.037874)
		(width 0.1)
		(layer "In6.Cu")
		(net 697)
	)
	(segment
		(start 121.215146 164.552951)
		(end 121.215146 164.552952)
		(width 0.1)
		(layer "In6.Cu")
		(net 697)
	)
	(segment
		(start 118.252501 174.426)
		(end 117.150501 174.426)
		(width 0.1)
		(layer "In6.Cu")
		(net 697)
	)
	(segment
		(start 126.032332 162.4275)
		(end 125.376501 162.4275)
		(width 0.1)
		(layer "In6.Cu")
		(net 697)
	)
	(segment
		(start 121.121861 164.954643)
		(end 121.121861 164.95464)
		(width 0.1)
		(layer "In6.Cu")
		(net 697)
	)
	(segment
		(start 122.700068 162.820543)
		(end 122.700068 162.820542)
		(width 0.1)
		(layer "In6.Cu")
		(net 697)
	)
	(segment
		(start 121.121861 164.95464)
		(end 120.96766 164.800439)
		(width 0.1)
		(layer "In6.Cu")
		(net 697)
	)
	(segment
		(start 119.543654 167.088737)
		(end 119.543653 167.088738)
		(width 0.1)
		(layer "In6.Cu")
		(net 697)
	)
	(segment
		(start 120.720172 165.047925)
		(end 120.720172 165.047926)
		(width 0.1)
		(layer "In6.Cu")
		(net 697)
	)
	(segment
		(start 120.286113 166.098791)
		(end 120.131913 165.944591)
		(width 0.1)
		(layer "In6.Cu")
		(net 697)
	)
	(segment
		(start 121.771037 164.613868)
		(end 121.771035 164.613869)
		(width 0.1)
		(layer "In6.Cu")
		(net 697)
	)
	(segment
		(start 119.296165 167.088739)
		(end 119.141965 166.934539)
		(width 0.1)
		(layer "In6.Cu")
		(net 697)
	)
	(segment
		(start 125.376501 162.4275)
		(end 125.102001 162.702)
		(width 0.1)
		(layer "In6.Cu")
		(net 697)
	)
	(segment
		(start 126.252001 162.647169)
		(end 126.032332 162.4275)
		(width 0.1)
		(layer "In6.Cu")
		(net 697)
	)
	(segment
		(start 119.791139 166.593765)
		(end 119.636939 166.439565)
		(width 0.1)
		(layer "In6.Cu")
		(net 697)
	)
	(segment
		(start 121.028576 165.603815)
		(end 121.028575 165.603816)
		(width 0.1)
		(layer "In6.Cu")
		(net 697)
	)
	(segment
		(start 121.215147 164.305464)
		(end 121.215146 164.305465)
		(width 0.1)
		(layer "In6.Cu")
		(net 697)
	)
	(segment
		(start 122.266009 164.118895)
		(end 122.111809 163.964695)
		(width 0.1)
		(layer "In6.Cu")
		(net 697)
	)
	(segment
		(start 119.636939 166.439565)
		(end 119.636939 166.439562)
		(width 0.1)
		(layer "In6.Cu")
		(net 697)
	)
	(segment
		(start 122.760985 163.62392)
		(end 122.760983 163.623921)
		(width 0.1)
		(layer "In6.Cu")
		(net 697)
	)
	(segment
		(start 122.205095 163.315516)
		(end 122.205094 163.315517)
		(width 0.1)
		(layer "In6.Cu")
		(net 697)
	)
	(segment
		(start 121.52355 165.108841)
		(end 121.523549 165.108842)
		(width 0.1)
		(layer "In6.Cu")
		(net 697)
	)
	(segment
		(start 120.225198 165.542899)
		(end 120.225198 165.5429)
		(width 0.1)
		(layer "In6.Cu")
		(net 697)
	)
	(segment
		(start 121.71012 164.057978)
		(end 122.018523 164.36638)
		(width 0.1)
		(layer "In6.Cu")
		(net 697)
	)
	(segment
		(start 119.791141 166.593764)
		(end 119.791139 166.593765)
		(width 0.1)
		(layer "In6.Cu")
		(net 697)
	)
	(segment
		(start 121.771035 164.613869)
		(end 121.616835 164.459669)
		(width 0.1)
		(layer "In6.Cu")
		(net 697)
	)
	(segment
		(start 120.225199 165.295412)
		(end 120.225198 165.295413)
		(width 0.1)
		(layer "In6.Cu")
		(net 697)
	)
	(segment
		(start 120.720172 165.047926)
		(end 121.028575 165.356328)
		(width 0.1)
		(layer "In6.Cu")
		(net 697)
	)
	(segment
		(start 122.266011 164.118894)
		(end 122.266009 164.118895)
		(width 0.1)
		(layer "In6.Cu")
		(net 697)
	)
	(segment
		(start 122.205094 163.563004)
		(end 122.513497 163.871406)
		(width 0.1)
		(layer "In6.Cu")
		(net 697)
	)
	(segment
		(start 121.710121 163.81049)
		(end 121.71012 163.810491)
		(width 0.1)
		(layer "In6.Cu")
		(net 697)
	)
	(segment
		(start 120.781087 165.603817)
		(end 120.626887 165.449617)
		(width 0.1)
		(layer "In6.Cu")
		(net 697)
	)
	(segment
		(start 121.71012 164.057977)
		(end 121.71012 164.057978)
		(width 0.1)
		(layer "In6.Cu")
		(net 697)
	)
	(segment
		(start 122.760983 163.623921)
		(end 122.606783 163.469721)
		(width 0.1)
		(layer "In6.Cu")
		(net 697)
	)
	(segment
		(start 122.700068 163.068029)
		(end 123.008471 163.376432)
		(width 0.1)
		(layer "In6.Cu")
		(net 697)
	)
	(segment
		(start 119.636939 166.439562)
		(end 119.482738 166.285361)
		(width 0.1)
		(layer "In6.Cu")
		(net 697)
	)
	(segment
		(start 119.141965 166.934539)
		(end 119.141965 166.934536)
		(width 0.1)
		(layer "In6.Cu")
		(net 697)
	)
	(segment
		(start 123.008472 163.623919)
		(end 123.008471 163.62392)
		(width 0.1)
		(layer "In6.Cu")
		(net 697)
	)
	(segment
		(start 119.730225 165.790386)
		(end 119.730224 165.790387)
		(width 0.1)
		(layer "In6.Cu")
		(net 697)
	)
	(segment
		(start 122.205094 163.563003)
		(end 122.205094 163.563004)
		(width 0.1)
		(layer "In6.Cu")
		(net 697)
	)
	(segment
		(start 118.626501 174.052)
		(end 118.252501 174.426)
		(width 0.1)
		(layer "In6.Cu")
		(net 697)
	)
	(segment
		(start 120.225198 165.5429)
		(end 120.533601 165.851302)
		(width 0.1)
		(layer "In6.Cu")
		(net 697)
	)
	(segment
		(start 120.533602 166.098789)
		(end 120.533601 166.09879)
		(width 0.1)
		(layer "In6.Cu")
		(net 697)
	)
	(segment
		(start 120.038628 166.593763)
		(end 120.038627 166.593764)
		(width 0.1)
		(layer "In6.Cu")
		(net 697)
	)
	(segment
		(start 122.111809 163.964692)
		(end 121.957608 163.810491)
		(width 0.1)
		(layer "In6.Cu")
		(net 697)
	)
	(segment
		(start 118.770732 167.305766)
		(end 118.770733 167.305766)
		(width 0.1)
		(layer "In6.Cu")
		(net 697)
	)
	(segment
		(start 122.978013 162.851)
		(end 122.947555 162.820542)
		(width 0.1)
		(layer "In6.Cu")
		(net 697)
	)
	(segment
		(start 125.102001 162.702)
		(end 123.374501 162.702)
		(width 0.1)
		(layer "In6.Cu")
		(net 697)
	)
	(segment
		(start 119.23525 166.532847)
		(end 119.23525 166.532848)
		(width 0.1)
		(layer "In6.Cu")
		(net 697)
	)
	(segment
		(start 122.606783 163.469718)
		(end 122.452582 163.315517)
		(width 0.1)
		(layer "In6.Cu")
		(net 697)
	)
	(segment
		(start 120.131913 165.944588)
		(end 119.977712 165.790387)
		(width 0.1)
		(layer "In6.Cu")
		(net 697)
	)
	(segment
		(start 122.606783 163.469721)
		(end 122.606783 163.469718)
		(width 0.1)
		(layer "In6.Cu")
		(net 697)
	)
	(segment
		(start 121.616835 164.459669)
		(end 121.616835 164.459666)
		(width 0.1)
		(layer "In6.Cu")
		(net 697)
	)
	(segment
		(start 126.877001 163.8025)
		(end 126.252001 163.1775)
		(width 0.1)
		(layer "In6.Cu")
		(net 697)
	)
	(segment
		(start 118.770733 167.305766)
		(end 118.626501 167.45)
		(width 0.1)
		(layer "In6.Cu")
		(net 697)
	)
	(segment
		(start 120.286115 166.09879)
		(end 120.286113 166.098791)
		(width 0.1)
		(layer "In6.Cu")
		(net 697)
	)
	(segment
		(start 118.740276 167.027822)
		(end 118.770733 167.058279)
		(width 0.1)
		(layer "In6.Cu")
		(net 697)
	)
	(segment
		(start 122.700068 163.068028)
		(end 122.700068 163.068029)
		(width 0.1)
		(layer "In6.Cu")
		(net 697)
	)
	(segment
		(start 122.513498 164.118893)
		(end 122.513497 164.118894)
		(width 0.1)
		(layer "In6.Cu")
		(net 697)
	)
	(segment
		(start 118.626501 167.45)
		(end 118.626501 174.052)
		(width 0.1)
		(layer "In6.Cu")
		(net 697)
	)
	(segment
		(start 122.111809 163.964695)
		(end 122.111809 163.964692)
		(width 0.1)
		(layer "In6.Cu")
		(net 697)
	)
	(segment
		(start 120.720173 164.800438)
		(end 120.720172 164.800439)
		(width 0.1)
		(layer "In6.Cu")
		(net 697)
	)
	(arc
		(start 122.513497 163.871406)
		(mid 122.564754 163.995149)
		(end 122.513498 164.118893)
		(width 0.1)
		(layer "In6.Cu")
		(net 697)
	)
	(arc
		(start 118.987764 166.780335)
		(mid 118.864021 166.729078)
		(end 118.740277 166.780334)
		(width 0.1)
		(layer "In6.Cu")
		(net 697)
	)
	(arc
		(start 119.482738 166.285361)
		(mid 119.358995 166.234104)
		(end 119.235251 166.28536)
		(width 0.1)
		(layer "In6.Cu")
		(net 697)
	)
	(arc
		(start 121.71012 163.810491)
		(mid 121.658864 163.934234)
		(end 121.71012 164.057977)
		(width 0.1)
		(layer "In6.Cu")
		(net 697)
	)
	(arc
		(start 120.225198 165.295413)
		(mid 120.173942 165.419156)
		(end 120.225198 165.542899)
		(width 0.1)
		(layer "In6.Cu")
		(net 697)
	)
	(arc
		(start 119.543653 167.088738)
		(mid 119.419909 167.139995)
		(end 119.296167 167.088738)
		(width 0.1)
		(layer "In6.Cu")
		(net 697)
	)
	(arc
		(start 118.770733 167.058279)
		(mid 118.821989 167.182023)
		(end 118.770732 167.305766)
		(width 0.1)
		(layer "In6.Cu")
		(net 697)
	)
	(arc
		(start 121.523549 164.861354)
		(mid 121.574806 164.985097)
		(end 121.52355 165.108841)
		(width 0.1)
		(layer "In6.Cu")
		(net 697)
	)
	(arc
		(start 121.523549 165.108842)
		(mid 121.399805 165.160099)
		(end 121.276063 165.108842)
		(width 0.1)
		(layer "In6.Cu")
		(net 697)
	)
	(arc
		(start 120.038627 166.593764)
		(mid 119.914883 166.645021)
		(end 119.791141 166.593764)
		(width 0.1)
		(layer "In6.Cu")
		(net 697)
	)
	(arc
		(start 122.700068 162.820542)
		(mid 122.648812 162.944285)
		(end 122.700068 163.068028)
		(width 0.1)
		(layer "In6.Cu")
		(net 697)
	)
	(arc
		(start 120.472686 165.295413)
		(mid 120.348943 165.244156)
		(end 120.225199 165.295412)
		(width 0.1)
		(layer "In6.Cu")
		(net 697)
	)
	(arc
		(start 121.028575 165.603816)
		(mid 120.904831 165.655073)
		(end 120.781089 165.603816)
		(width 0.1)
		(layer "In6.Cu")
		(net 697)
	)
	(arc
		(start 120.038627 166.346276)
		(mid 120.089884 166.470019)
		(end 120.038628 166.593763)
		(width 0.1)
		(layer "In6.Cu")
		(net 697)
	)
	(arc
		(start 122.513497 164.118894)
		(mid 122.389753 164.170151)
		(end 122.266011 164.118894)
		(width 0.1)
		(layer "In6.Cu")
		(net 697)
	)
	(arc
		(start 123.008471 163.62392)
		(mid 122.884727 163.675177)
		(end 122.760985 163.62392)
		(width 0.1)
		(layer "In6.Cu")
		(net 697)
	)
	(arc
		(start 121.028575 165.356328)
		(mid 121.079832 165.480071)
		(end 121.028576 165.603815)
		(width 0.1)
		(layer "In6.Cu")
		(net 697)
	)
	(arc
		(start 122.947555 162.820542)
		(mid 122.823811 162.769286)
		(end 122.700068 162.820543)
		(width 0.1)
		(layer "In6.Cu")
		(net 697)
	)
	(arc
		(start 118.740276 166.780335)
		(mid 118.68902 166.904078)
		(end 118.740276 167.027821)
		(width 0.1)
		(layer "In6.Cu")
		(net 697)
	)
	(arc
		(start 121.957608 163.810491)
		(mid 121.833865 163.759234)
		(end 121.710121 163.81049)
		(width 0.1)
		(layer "In6.Cu")
		(net 697)
	)
	(arc
		(start 120.533601 166.09879)
		(mid 120.409857 166.150047)
		(end 120.286115 166.09879)
		(width 0.1)
		(layer "In6.Cu")
		(net 697)
	)
	(arc
		(start 123.008471 163.376432)
		(mid 123.059728 163.500175)
		(end 123.008472 163.623919)
		(width 0.1)
		(layer "In6.Cu")
		(net 697)
	)
	(arc
		(start 119.977712 165.790387)
		(mid 119.853969 165.73913)
		(end 119.730225 165.790386)
		(width 0.1)
		(layer "In6.Cu")
		(net 697)
	)
	(arc
		(start 120.533601 165.851302)
		(mid 120.584858 165.975045)
		(end 120.533602 166.098789)
		(width 0.1)
		(layer "In6.Cu")
		(net 697)
	)
	(arc
		(start 122.018523 164.613868)
		(mid 121.894779 164.665125)
		(end 121.771037 164.613868)
		(width 0.1)
		(layer "In6.Cu")
		(net 697)
	)
	(arc
		(start 122.018523 164.36638)
		(mid 122.06978 164.490123)
		(end 122.018524 164.613867)
		(width 0.1)
		(layer "In6.Cu")
		(net 697)
	)
	(arc
		(start 119.543653 166.84125)
		(mid 119.59491 166.964993)
		(end 119.543654 167.088737)
		(width 0.1)
		(layer "In6.Cu")
		(net 697)
	)
	(arc
		(start 123.225501 162.851)
		(mid 123.101757 162.902256)
		(end 122.978013 162.851)
		(width 0.1)
		(layer "In6.Cu")
		(net 697)
	)
	(arc
		(start 120.720172 164.800439)
		(mid 120.668916 164.924182)
		(end 120.720172 165.047925)
		(width 0.1)
		(layer "In6.Cu")
		(net 697)
	)
	(arc
		(start 120.96766 164.800439)
		(mid 120.843917 164.749182)
		(end 120.720173 164.800438)
		(width 0.1)
		(layer "In6.Cu")
		(net 697)
	)
	(arc
		(start 122.452582 163.315517)
		(mid 122.328839 163.26426)
		(end 122.205095 163.315516)
		(width 0.1)
		(layer "In6.Cu")
		(net 697)
	)
	(arc
		(start 121.462634 164.305465)
		(mid 121.338891 164.254208)
		(end 121.215147 164.305464)
		(width 0.1)
		(layer "In6.Cu")
		(net 697)
	)
	(arc
		(start 122.205094 163.315517)
		(mid 122.153838 163.43926)
		(end 122.205094 163.563003)
		(width 0.1)
		(layer "In6.Cu")
		(net 697)
	)
	(arc
		(start 119.730224 165.790387)
		(mid 119.678968 165.91413)
		(end 119.730224 166.037873)
		(width 0.1)
		(layer "In6.Cu")
		(net 697)
	)
	(arc
		(start 119.23525 166.285361)
		(mid 119.183994 166.409104)
		(end 119.23525 166.532847)
		(width 0.1)
		(layer "In6.Cu")
		(net 697)
	)
	(arc
		(start 121.215146 164.305465)
		(mid 121.16389 164.429208)
		(end 121.215146 164.552951)
		(width 0.1)
		(layer "In6.Cu")
		(net 697)
	)
	(segment
		(start 129.376501 163.302)
		(end 128.877002 162.8025)
		(width 0.256)
		(layer "F.Cu")
		(net 698)
	)
	(segment
		(start 117.650501 174.926)
		(end 117.150501 175.426)
		(width 0.256)
		(layer "F.Cu")
		(net 698)
	)
	(via
		(at 128.877002 162.8025)
		(size 0.45)
		(drill 0.1)
		(layers "F.Cu" "B.Cu")
		(net 698)
	)
	(via
		(at 117.150501 175.426)
		(size 0.45)
		(drill 0.1)
		(layers "F.Cu" "B.Cu")
		(net 698)
	)
	(segment
		(start 123.876501 168.2)
		(end 123.876501 167.802)
		(width 0.1)
		(layer "In6.Cu")
		(net 698)
	)
	(segment
		(start 124.068988 169.075)
		(end 123.684014 169.075)
		(width 0.1)
		(layer "In6.Cu")
		(net 698)
	)
	(segment
		(start 123.876501 176.427)
		(end 123.876501 170.65)
		(width 0.1)
		(layer "In6.Cu")
		(net 698)
	)
	(segment
		(start 123.876501 167.802)
		(end 125.253001 166.4255)
		(width 0.1)
		(layer "In6.Cu")
		(net 698)
	)
	(segment
		(start 125.253001 166.4255)
		(end 129.079501 166.4255)
		(width 0.1)
		(layer "In6.Cu")
		(net 698)
	)
	(segment
		(start 117.525501 175.801)
		(end 118.625501 175.801)
		(width 0.1)
		(layer "In6.Cu")
		(net 698)
	)
	(segment
		(start 123.251501 177.052)
		(end 123.876501 176.427)
		(width 0.1)
		(layer "In6.Cu")
		(net 698)
	)
	(segment
		(start 123.701501 170.475)
		(end 123.684014 170.475)
		(width 0.1)
		(layer "In6.Cu")
		(net 698)
	)
	(segment
		(start 129.252501 166.2525)
		(end 129.252501 163.175499)
		(width 0.1)
		(layer "In6.Cu")
		(net 698)
	)
	(segment
		(start 124.068988 169.775)
		(end 123.684014 169.775)
		(width 0.1)
		(layer "In6.Cu")
		(net 698)
	)
	(segment
		(start 118.625501 175.801)
		(end 119.876501 177.052)
		(width 0.1)
		(layer "In6.Cu")
		(net 698)
	)
	(segment
		(start 123.684014 169.425)
		(end 124.068988 169.425)
		(width 0.1)
		(layer "In6.Cu")
		(net 698)
	)
	(segment
		(start 129.250001 163.175499)
		(end 128.877002 162.8025)
		(width 0.1)
		(layer "In6.Cu")
		(net 698)
	)
	(segment
		(start 124.068988 168.375)
		(end 124.051501 168.375)
		(width 0.1)
		(layer "In6.Cu")
		(net 698)
	)
	(segment
		(start 119.876501 177.052)
		(end 123.251501 177.052)
		(width 0.1)
		(layer "In6.Cu")
		(net 698)
	)
	(segment
		(start 129.079501 166.4255)
		(end 129.252501 166.2525)
		(width 0.1)
		(layer "In6.Cu")
		(net 698)
	)
	(segment
		(start 117.150501 175.426)
		(end 117.525501 175.801)
		(width 0.1)
		(layer "In6.Cu")
		(net 698)
	)
	(segment
		(start 129.252501 163.175499)
		(end 129.250001 163.175499)
		(width 0.1)
		(layer "In6.Cu")
		(net 698)
	)
	(segment
		(start 123.684014 170.125)
		(end 124.068988 170.125)
		(width 0.1)
		(layer "In6.Cu")
		(net 698)
	)
	(segment
		(start 123.684014 168.725)
		(end 124.068988 168.725)
		(width 0.1)
		(layer "In6.Cu")
		(net 698)
	)
	(arc
		(start 124.051501 168.375)
		(mid 123.927757 168.323744)
		(end 123.876501 168.2)
		(width 0.1)
		(layer "In6.Cu")
		(net 698)
	)
	(arc
		(start 123.684014 169.075)
		(mid 123.56027 169.023744)
		(end 123.509014 168.9)
		(width 0.1)
		(layer "In6.Cu")
		(net 698)
	)
	(arc
		(start 124.068988 170.125)
		(mid 124.192732 170.073744)
		(end 124.243988 169.95)
		(width 0.1)
		(layer "In6.Cu")
		(net 698)
	)
	(arc
		(start 123.876501 170.65)
		(mid 123.825245 170.526256)
		(end 123.701501 170.475)
		(width 0.1)
		(layer "In6.Cu")
		(net 698)
	)
	(arc
		(start 123.509014 168.9)
		(mid 123.56027 168.776256)
		(end 123.684014 168.725)
		(width 0.1)
		(layer "In6.Cu")
		(net 698)
	)
	(arc
		(start 123.684014 170.475)
		(mid 123.56027 170.423744)
		(end 123.509014 170.3)
		(width 0.1)
		(layer "In6.Cu")
		(net 698)
	)
	(arc
		(start 124.243988 169.95)
		(mid 124.192732 169.826256)
		(end 124.068988 169.775)
		(width 0.1)
		(layer "In6.Cu")
		(net 698)
	)
	(arc
		(start 123.509014 170.3)
		(mid 123.56027 170.176256)
		(end 123.684014 170.125)
		(width 0.1)
		(layer "In6.Cu")
		(net 698)
	)
	(arc
		(start 124.068988 169.425)
		(mid 124.192732 169.373744)
		(end 124.243988 169.25)
		(width 0.1)
		(layer "In6.Cu")
		(net 698)
	)
	(arc
		(start 124.243988 168.55)
		(mid 124.192732 168.426256)
		(end 124.068988 168.375)
		(width 0.1)
		(layer "In6.Cu")
		(net 698)
	)
	(arc
		(start 123.684014 169.775)
		(mid 123.56027 169.723744)
		(end 123.509014 169.6)
		(width 0.1)
		(layer "In6.Cu")
		(net 698)
	)
	(arc
		(start 124.068988 168.725)
		(mid 124.192732 168.673744)
		(end 124.243988 168.55)
		(width 0.1)
		(layer "In6.Cu")
		(net 698)
	)
	(arc
		(start 124.243988 169.25)
		(mid 124.192732 169.126256)
		(end 124.068988 169.075)
		(width 0.1)
		(layer "In6.Cu")
		(net 698)
	)
	(arc
		(start 123.509014 169.6)
		(mid 123.56027 169.476256)
		(end 123.684014 169.425)
		(width 0.1)
		(layer "In6.Cu")
		(net 698)
	)
	(segment
		(start 117.650501 175.926)
		(end 117.149501 176.427)
		(width 0.256)
		(layer "F.Cu")
		(net 699)
	)
	(segment
		(start 130.376501 163.302)
		(end 129.877 162.8025)
		(width 0.256)
		(layer "F.Cu")
		(net 699)
	)
	(via
		(at 117.149501 176.427)
		(size 0.45)
		(drill 0.1)
		(layers "F.Cu" "B.Cu")
		(net 699)
	)
	(via
		(at 129.877 162.8025)
		(size 0.45)
		(drill 0.1)
		(layers "F.Cu" "B.Cu")
		(net 699)
	)
	(segment
		(start 124.834637 174.577)
		(end 124.626501 174.577)
		(width 0.1)
		(layer "In6.Cu")
		(net 699)
	)
	(segment
		(start 124.451501 175.627)
		(end 124.834637 175.627)
		(width 0.1)
		(layer "In6.Cu")
		(net 699)
	)
	(segment
		(start 124.418365 174.927)
		(end 124.626501 174.927)
		(width 0.1)
		(layer "In6.Cu")
		(net 699)
	)
	(segment
		(start 124.626501 172.302)
		(end 124.626501 171.590011)
		(width 0.1)
		(layer "In6.Cu")
		(net 699)
	)
	(segment
		(start 117.149501 176.427)
		(end 118.524501 177.802)
		(width 0.1)
		(layer "In6.Cu")
		(net 699)
	)
	(segment
		(start 123.376501 177.802)
		(end 124.626501 176.552)
		(width 0.1)
		(layer "In6.Cu")
		(net 699)
	)
	(segment
		(start 124.834637 172.477)
		(end 124.801501 172.477)
		(width 0.1)
		(layer "In6.Cu")
		(net 699)
	)
	(segment
		(start 124.626501 175.277)
		(end 124.418365 175.277)
		(width 0.1)
		(layer "In6.Cu")
		(net 699)
	)
	(segment
		(start 129.106167 167.2255)
		(end 129.501001 166.830666)
		(width 0.1)
		(layer "In6.Cu")
		(net 699)
	)
	(segment
		(start 124.834637 175.277)
		(end 124.626501 175.277)
		(width 0.1)
		(layer "In6.Cu")
		(net 699)
	)
	(segment
		(start 124.626501 174.227)
		(end 124.834637 174.227)
		(width 0.1)
		(layer "In6.Cu")
		(net 699)
	)
	(segment
		(start 124.834637 173.877)
		(end 124.626501 173.877)
		(width 0.1)
		(layer "In6.Cu")
		(net 699)
	)
	(segment
		(start 124.626501 174.577)
		(end 124.418365 174.577)
		(width 0.1)
		(layer "In6.Cu")
		(net 699)
	)
	(segment
		(start 129.501001 166.830666)
		(end 129.501001 163.176999)
		(width 0.1)
		(layer "In6.Cu")
		(net 699)
	)
	(segment
		(start 124.626501 171.590011)
		(end 124.626501 167.85)
		(width 0.1)
		(layer "In6.Cu")
		(net 699)
	)
	(segment
		(start 124.626501 174.927)
		(end 124.834637 174.927)
		(width 0.1)
		(layer "In6.Cu")
		(net 699)
	)
	(segment
		(start 124.418365 175.627)
		(end 124.451501 175.627)
		(width 0.1)
		(layer "In6.Cu")
		(net 699)
	)
	(segment
		(start 129.501001 163.176999)
		(end 129.502501 163.176999)
		(width 0.1)
		(layer "In6.Cu")
		(net 699)
	)
	(segment
		(start 124.418365 174.227)
		(end 124.626501 174.227)
		(width 0.1)
		(layer "In6.Cu")
		(net 699)
	)
	(segment
		(start 124.626501 167.85)
		(end 125.251001 167.2255)
		(width 0.1)
		(layer "In6.Cu")
		(net 699)
	)
	(segment
		(start 125.251001 167.2255)
		(end 129.106167 167.2255)
		(width 0.1)
		(layer "In6.Cu")
		(net 699)
	)
	(segment
		(start 129.502501 163.176999)
		(end 129.877 162.8025)
		(width 0.1)
		(layer "In6.Cu")
		(net 699)
	)
	(segment
		(start 124.834637 173.177)
		(end 124.626501 173.177)
		(width 0.1)
		(layer "In6.Cu")
		(net 699)
	)
	(segment
		(start 124.418365 172.827)
		(end 124.626501 172.827)
		(width 0.1)
		(layer "In6.Cu")
		(net 699)
	)
	(segment
		(start 118.524501 177.802)
		(end 123.376501 177.802)
		(width 0.1)
		(layer "In6.Cu")
		(net 699)
	)
	(segment
		(start 124.626501 173.877)
		(end 124.418365 173.877)
		(width 0.1)
		(layer "In6.Cu")
		(net 699)
	)
	(segment
		(start 124.626501 173.177)
		(end 124.418365 173.177)
		(width 0.1)
		(layer "In6.Cu")
		(net 699)
	)
	(segment
		(start 124.418365 173.527)
		(end 124.626501 173.527)
		(width 0.1)
		(layer "In6.Cu")
		(net 699)
	)
	(segment
		(start 124.626501 176.552)
		(end 124.626501 176.152)
		(width 0.1)
		(layer "In6.Cu")
		(net 699)
	)
	(segment
		(start 124.626501 173.527)
		(end 124.834637 173.527)
		(width 0.1)
		(layer "In6.Cu")
		(net 699)
	)
	(segment
		(start 124.451501 175.977)
		(end 124.418365 175.977)
		(width 0.1)
		(layer "In6.Cu")
		(net 699)
	)
	(segment
		(start 124.626501 172.827)
		(end 124.834637 172.827)
		(width 0.1)
		(layer "In6.Cu")
		(net 699)
	)
	(arc
		(start 125.009637 174.052)
		(mid 124.958381 173.928256)
		(end 124.834637 173.877)
		(width 0.1)
		(layer "In6.Cu")
		(net 699)
	)
	(arc
		(start 125.009637 173.352)
		(mid 124.958381 173.228256)
		(end 124.834637 173.177)
		(width 0.1)
		(layer "In6.Cu")
		(net 699)
	)
	(arc
		(start 124.418365 173.177)
		(mid 124.294621 173.125744)
		(end 124.243365 173.002)
		(width 0.1)
		(layer "In6.Cu")
		(net 699)
	)
	(arc
		(start 125.009637 175.452)
		(mid 124.958381 175.328256)
		(end 124.834637 175.277)
		(width 0.1)
		(layer "In6.Cu")
		(net 699)
	)
	(arc
		(start 124.243365 175.102)
		(mid 124.294621 174.978256)
		(end 124.418365 174.927)
		(width 0.1)
		(layer "In6.Cu")
		(net 699)
	)
	(arc
		(start 124.418365 174.577)
		(mid 124.294621 174.525744)
		(end 124.243365 174.402)
		(width 0.1)
		(layer "In6.Cu")
		(net 699)
	)
	(arc
		(start 124.418365 173.877)
		(mid 124.294621 173.825744)
		(end 124.243365 173.702)
		(width 0.1)
		(layer "In6.Cu")
		(net 699)
	)
	(arc
		(start 125.009637 172.652)
		(mid 124.958381 172.528256)
		(end 124.834637 172.477)
		(width 0.1)
		(layer "In6.Cu")
		(net 699)
	)
	(arc
		(start 124.834637 175.627)
		(mid 124.958381 175.575744)
		(end 125.009637 175.452)
		(width 0.1)
		(layer "In6.Cu")
		(net 699)
	)
	(arc
		(start 124.834637 174.227)
		(mid 124.958381 174.175744)
		(end 125.009637 174.052)
		(width 0.1)
		(layer "In6.Cu")
		(net 699)
	)
	(arc
		(start 124.243365 173.002)
		(mid 124.294621 172.878256)
		(end 124.418365 172.827)
		(width 0.1)
		(layer "In6.Cu")
		(net 699)
	)
	(arc
		(start 124.834637 174.927)
		(mid 124.958381 174.875744)
		(end 125.009637 174.752)
		(width 0.1)
		(layer "In6.Cu")
		(net 699)
	)
	(arc
		(start 124.801501 172.477)
		(mid 124.677757 172.425744)
		(end 124.626501 172.302)
		(width 0.1)
		(layer "In6.Cu")
		(net 699)
	)
	(arc
		(start 124.834637 173.527)
		(mid 124.958381 173.475744)
		(end 125.009637 173.352)
		(width 0.1)
		(layer "In6.Cu")
		(net 699)
	)
	(arc
		(start 124.243365 174.402)
		(mid 124.294621 174.278256)
		(end 124.418365 174.227)
		(width 0.1)
		(layer "In6.Cu")
		(net 699)
	)
	(arc
		(start 124.243365 173.702)
		(mid 124.294621 173.578256)
		(end 124.418365 173.527)
		(width 0.1)
		(layer "In6.Cu")
		(net 699)
	)
	(arc
		(start 125.009637 174.752)
		(mid 124.958381 174.628256)
		(end 124.834637 174.577)
		(width 0.1)
		(layer "In6.Cu")
		(net 699)
	)
	(arc
		(start 124.418365 175.977)
		(mid 124.294621 175.925744)
		(end 124.243365 175.802)
		(width 0.1)
		(layer "In6.Cu")
		(net 699)
	)
	(arc
		(start 124.243365 175.802)
		(mid 124.294621 175.678256)
		(end 124.418365 175.627)
		(width 0.1)
		(layer "In6.Cu")
		(net 699)
	)
	(arc
		(start 124.834637 172.827)
		(mid 124.958381 172.775744)
		(end 125.009637 172.652)
		(width 0.1)
		(layer "In6.Cu")
		(net 699)
	)
	(arc
		(start 124.626501 176.152)
		(mid 124.575245 176.028256)
		(end 124.451501 175.977)
		(width 0.1)
		(layer "In6.Cu")
		(net 699)
	)
	(arc
		(start 124.418365 175.277)
		(mid 124.294621 175.225744)
		(end 124.243365 175.102)
		(width 0.1)
		(layer "In6.Cu")
		(net 699)
	)
	(segment
		(start 117.651501 176.926)
		(end 117.150501 177.427)
		(width 0.256)
		(layer "F.Cu")
		(net 700)
	)
	(segment
		(start 129.3765 162.302)
		(end 128.877001 161.8025)
		(width 0.256)
		(layer "F.Cu")
		(net 700)
	)
	(via
		(at 117.150501 177.427)
		(size 0.45)
		(drill 0.1)
		(layers "F.Cu" "B.Cu")
		(net 700)
	)
	(via
		(at 128.877001 161.8025)
		(size 0.45)
		(drill 0.1)
		(layers "F.Cu" "B.Cu")
		(net 700)
	)
	(segment
		(start 127.226501 160.552)
		(end 128.477001 161.8025)
		(width 0.1)
		(layer "In6.Cu")
		(net 700)
	)
	(segment
		(start 128.477001 161.8025)
		(end 128.877001 161.8025)
		(width 0.1)
		(layer "In6.Cu")
		(net 700)
	)
	(segment
		(start 114.126501 166.802)
		(end 120.376501 160.552)
		(width 0.1)
		(layer "In6.Cu")
		(net 700)
	)
	(segment
		(start 115.976501 176.902)
		(end 114.126501 175.052)
		(width 0.1)
		(layer "In6.Cu")
		(net 700)
	)
	(segment
		(start 114.126501 175.052)
		(end 114.126501 166.802)
		(width 0.1)
		(layer "In6.Cu")
		(net 700)
	)
	(segment
		(start 117.150501 177.427)
		(end 116.625501 176.902)
		(width 0.1)
		(layer "In6.Cu")
		(net 700)
	)
	(segment
		(start 120.376501 160.552)
		(end 127.226501 160.552)
		(width 0.1)
		(layer "In6.Cu")
		(net 700)
	)
	(segment
		(start 116.625501 176.902)
		(end 115.976501 176.902)
		(width 0.1)
		(layer "In6.Cu")
		(net 700)
	)
	(segment
		(start 116.650501 172.926)
		(end 116.150501 173.426)
		(width 0.256)
		(layer "F.Cu")
		(net 701)
	)
	(segment
		(start 128.376501 164.302)
		(end 127.877001 163.8025)
		(width 0.256)
		(layer "F.Cu")
		(net 701)
	)
	(via
		(at 127.877001 163.8025)
		(size 0.45)
		(drill 0.1)
		(layers "F.Cu" "B.Cu")
		(net 701)
	)
	(via
		(at 116.150501 173.426)
		(size 0.45)
		(drill 0.1)
		(layers "F.Cu" "B.Cu")
		(net 701)
	)
	(segment
		(start 116.150501 173.426)
		(end 117.126501 172.45)
		(width 0.1)
		(layer "In6.Cu")
		(net 701)
	)
	(segment
		(start 117.126501 170.225)
		(end 117.675318 170.225)
		(width 0.1)
		(layer "In6.Cu")
		(net 701)
	)
	(segment
		(start 127.376501 163.302)
		(end 127.877001 163.8025)
		(width 0.1)
		(layer "In6.Cu")
		(net 701)
	)
	(segment
		(start 117.126501 172.45)
		(end 117.126501 172.15)
		(width 0.1)
		(layer "In6.Cu")
		(net 701)
	)
	(segment
		(start 117.126501 169.175)
		(end 116.577684 169.175)
		(width 0.1)
		(layer "In6.Cu")
		(net 701)
	)
	(segment
		(start 117.126501 167.98762)
		(end 117.126501 167.802)
		(width 0.1)
		(layer "In6.Cu")
		(net 701)
	)
	(segment
		(start 116.951501 171.975)
		(end 116.577684 171.975)
		(width 0.1)
		(layer "In6.Cu")
		(net 701)
	)
	(segment
		(start 116.951501 171.625)
		(end 117.675318 171.625)
		(width 0.1)
		(layer "In6.Cu")
		(net 701)
	)
	(segment
		(start 117.126501 171.275)
		(end 116.577684 171.275)
		(width 0.1)
		(layer "In6.Cu")
		(net 701)
	)
	(segment
		(start 117.675318 169.875)
		(end 117.126501 169.875)
		(width 0.1)
		(layer "In6.Cu")
		(net 701)
	)
	(segment
		(start 126.676501 163.302)
		(end 127.376501 163.302)
		(width 0.1)
		(layer "In6.Cu")
		(net 701)
	)
	(segment
		(start 122.751001 162.1775)
		(end 126.227001 162.1775)
		(width 0.1)
		(layer "In6.Cu")
		(net 701)
	)
	(segment
		(start 116.577684 168.825)
		(end 116.951501 168.825)
		(width 0.1)
		(layer "In6.Cu")
		(net 701)
	)
	(segment
		(start 126.227001 162.1775)
		(end 126.502001 162.4525)
		(width 0.1)
		(layer "In6.Cu")
		(net 701)
	)
	(segment
		(start 126.502001 163.1275)
		(end 126.676501 163.302)
		(width 0.1)
		(layer "In6.Cu")
		(net 701)
	)
	(segment
		(start 117.675318 170.575)
		(end 117.126501 170.575)
		(width 0.1)
		(layer "In6.Cu")
		(net 701)
	)
	(segment
		(start 117.126501 170.575)
		(end 116.577684 170.575)
		(width 0.1)
		(layer "In6.Cu")
		(net 701)
	)
	(segment
		(start 117.675318 171.275)
		(end 117.126501 171.275)
		(width 0.1)
		(layer "In6.Cu")
		(net 701)
	)
	(segment
		(start 126.502001 162.4525)
		(end 126.502001 163.1275)
		(width 0.1)
		(layer "In6.Cu")
		(net 701)
	)
	(segment
		(start 116.577684 170.225)
		(end 117.126501 170.225)
		(width 0.1)
		(layer "In6.Cu")
		(net 701)
	)
	(segment
		(start 117.126501 167.802)
		(end 122.751001 162.1775)
		(width 0.1)
		(layer "In6.Cu")
		(net 701)
	)
	(segment
		(start 116.577684 170.925)
		(end 117.126501 170.925)
		(width 0.1)
		(layer "In6.Cu")
		(net 701)
	)
	(segment
		(start 117.126501 168.65)
		(end 117.126501 167.98762)
		(width 0.1)
		(layer "In6.Cu")
		(net 701)
	)
	(segment
		(start 116.577684 171.625)
		(end 116.951501 171.625)
		(width 0.1)
		(layer "In6.Cu")
		(net 701)
	)
	(segment
		(start 117.126501 169.525)
		(end 117.675318 169.525)
		(width 0.1)
		(layer "In6.Cu")
		(net 701)
	)
	(segment
		(start 117.126501 170.925)
		(end 117.675318 170.925)
		(width 0.1)
		(layer "In6.Cu")
		(net 701)
	)
	(segment
		(start 117.126501 169.875)
		(end 116.577684 169.875)
		(width 0.1)
		(layer "In6.Cu")
		(net 701)
	)
	(segment
		(start 117.675318 169.175)
		(end 117.126501 169.175)
		(width 0.1)
		(layer "In6.Cu")
		(net 701)
	)
	(segment
		(start 116.577684 169.525)
		(end 117.126501 169.525)
		(width 0.1)
		(layer "In6.Cu")
		(net 701)
	)
	(arc
		(start 116.402684 169)
		(mid 116.45394 168.876256)
		(end 116.577684 168.825)
		(width 0.1)
		(layer "In6.Cu")
		(net 701)
	)
	(arc
		(start 116.402684 171.1)
		(mid 116.45394 170.976256)
		(end 116.577684 170.925)
		(width 0.1)
		(layer "In6.Cu")
		(net 701)
	)
	(arc
		(start 116.577684 171.275)
		(mid 116.45394 171.223744)
		(end 116.402684 171.1)
		(width 0.1)
		(layer "In6.Cu")
		(net 701)
	)
	(arc
		(start 117.850318 170.75)
		(mid 117.799062 170.626256)
		(end 117.675318 170.575)
		(width 0.1)
		(layer "In6.Cu")
		(net 701)
	)
	(arc
		(start 116.402684 170.4)
		(mid 116.45394 170.276256)
		(end 116.577684 170.225)
		(width 0.1)
		(layer "In6.Cu")
		(net 701)
	)
	(arc
		(start 117.675318 170.925)
		(mid 117.799062 170.873744)
		(end 117.850318 170.75)
		(width 0.1)
		(layer "In6.Cu")
		(net 701)
	)
	(arc
		(start 117.675318 170.225)
		(mid 117.799062 170.173744)
		(end 117.850318 170.05)
		(width 0.1)
		(layer "In6.Cu")
		(net 701)
	)
	(arc
		(start 117.675318 171.625)
		(mid 117.799062 171.573744)
		(end 117.850318 171.45)
		(width 0.1)
		(layer "In6.Cu")
		(net 701)
	)
	(arc
		(start 117.675318 169.525)
		(mid 117.799062 169.473744)
		(end 117.850318 169.35)
		(width 0.1)
		(layer "In6.Cu")
		(net 701)
	)
	(arc
		(start 116.577684 171.975)
		(mid 116.45394 171.923744)
		(end 116.402684 171.8)
		(width 0.1)
		(layer "In6.Cu")
		(net 701)
	)
	(arc
		(start 116.402684 171.8)
		(mid 116.45394 171.676256)
		(end 116.577684 171.625)
		(width 0.1)
		(layer "In6.Cu")
		(net 701)
	)
	(arc
		(start 116.951501 168.825)
		(mid 117.075245 168.773744)
		(end 117.126501 168.65)
		(width 0.1)
		(layer "In6.Cu")
		(net 701)
	)
	(arc
		(start 116.402684 169.7)
		(mid 116.45394 169.576256)
		(end 116.577684 169.525)
		(width 0.1)
		(layer "In6.Cu")
		(net 701)
	)
	(arc
		(start 117.126501 172.15)
		(mid 117.075245 172.026256)
		(end 116.951501 171.975)
		(width 0.1)
		(layer "In6.Cu")
		(net 701)
	)
	(arc
		(start 117.850318 170.05)
		(mid 117.799062 169.926256)
		(end 117.675318 169.875)
		(width 0.1)
		(layer "In6.Cu")
		(net 701)
	)
	(arc
		(start 117.850318 169.35)
		(mid 117.799062 169.226256)
		(end 117.675318 169.175)
		(width 0.1)
		(layer "In6.Cu")
		(net 701)
	)
	(arc
		(start 117.850318 171.45)
		(mid 117.799062 171.326256)
		(end 117.675318 171.275)
		(width 0.1)
		(layer "In6.Cu")
		(net 701)
	)
	(arc
		(start 116.577684 170.575)
		(mid 116.45394 170.523744)
		(end 116.402684 170.4)
		(width 0.1)
		(layer "In6.Cu")
		(net 701)
	)
	(arc
		(start 116.577684 169.175)
		(mid 116.45394 169.123744)
		(end 116.402684 169)
		(width 0.1)
		(layer "In6.Cu")
		(net 701)
	)
	(arc
		(start 116.577684 169.875)
		(mid 116.45394 169.823744)
		(end 116.402684 169.7)
		(width 0.1)
		(layer "In6.Cu")
		(net 701)
	)
	(segment
		(start 116.650501 173.926)
		(end 116.150501 174.426)
		(width 0.256)
		(layer "F.Cu")
		(net 702)
	)
	(segment
		(start 127.376501 163.302)
		(end 126.877001 162.8025)
		(width 0.256)
		(layer "F.Cu")
		(net 702)
	)
	(via
		(at 126.877001 162.8025)
		(size 0.45)
		(drill 0.1)
		(layers "F.Cu" "B.Cu")
		(net 702)
	)
	(via
		(at 116.150501 174.426)
		(size 0.45)
		(drill 0.1)
		(layers "F.Cu" "B.Cu")
		(net 702)
	)
	(segment
		(start 117.460174 166.218324)
		(end 117.194449 165.952598)
		(width 0.1)
		(layer "In6.Cu")
		(net 702)
	)
	(segment
		(start 116.717712 166.960792)
		(end 116.983438 167.226517)
		(width 0.1)
		(layer "In6.Cu")
		(net 702)
	)
	(segment
		(start 116.699473 166.200088)
		(end 116.699473 166.200087)
		(width 0.1)
		(layer "In6.Cu")
		(net 702)
	)
	(segment
		(start 117.707666 165.970838)
		(end 117.973392 166.236563)
		(width 0.1)
		(layer "In6.Cu")
		(net 702)
	)
	(segment
		(start 117.230925 166.979029)
		(end 116.965197 166.713301)
		(width 0.1)
		(layer "In6.Cu")
		(net 702)
	)
	(segment
		(start 115.626501 168.052)
		(end 115.851501 167.827)
		(width 0.1)
		(layer "In6.Cu")
		(net 702)
	)
	(segment
		(start 117.212689 166.465815)
		(end 117.478415 166.73154)
		(width 0.1)
		(layer "In6.Cu")
		(net 702)
	)
	(segment
		(start 116.47022 167.208278)
		(end 116.204495 166.942552)
		(width 0.1)
		(layer "In6.Cu")
		(net 702)
	)
	(segment
		(start 116.204496 166.695065)
		(end 116.204496 166.695064)
		(width 0.1)
		(layer "In6.Cu")
		(net 702)
	)
	(segment
		(start 116.735948 167.474006)
		(end 116.47022 167.208278)
		(width 0.1)
		(layer "In6.Cu")
		(net 702)
	)
	(segment
		(start 116.150501 174.426)
		(end 115.626501 173.902)
		(width 0.1)
		(layer "In6.Cu")
		(net 702)
	)
	(segment
		(start 117.19445 165.705111)
		(end 117.19445 165.70511)
		(width 0.1)
		(layer "In6.Cu")
		(net 702)
	)
	(segment
		(start 126.877001 162.4025)
		(end 126.877001 162.8025)
		(width 0.1)
		(layer "In6.Cu")
		(net 702)
	)
	(segment
		(start 116.946961 166.200087)
		(end 117.212689 166.465815)
		(width 0.1)
		(layer "In6.Cu")
		(net 702)
	)
	(segment
		(start 117.955151 165.723347)
		(end 117.689426 165.457621)
		(width 0.1)
		(layer "In6.Cu")
		(net 702)
	)
	(segment
		(start 115.626501 173.902)
		(end 115.626501 168.052)
		(width 0.1)
		(layer "In6.Cu")
		(net 702)
	)
	(segment
		(start 115.851502 167.579512)
		(end 115.709519 167.437529)
		(width 0.1)
		(layer "In6.Cu")
		(net 702)
	)
	(segment
		(start 115.709519 167.190041)
		(end 115.709518 167.190043)
		(width 0.1)
		(layer "In6.Cu")
		(net 702)
	)
	(segment
		(start 118.220879 166.236562)
		(end 118.220879 166.236563)
		(width 0.1)
		(layer "In6.Cu")
		(net 702)
	)
	(segment
		(start 118.326385 165.352118)
		(end 121.976501 161.702)
		(width 0.1)
		(layer "In6.Cu")
		(net 702)
	)
	(segment
		(start 115.957006 167.190043)
		(end 116.09899 167.332027)
		(width 0.1)
		(layer "In6.Cu")
		(net 702)
	)
	(segment
		(start 117.725902 166.484052)
		(end 117.460174 166.218324)
		(width 0.1)
		(layer "In6.Cu")
		(net 702)
	)
	(segment
		(start 125.401001 161.4275)
		(end 126.102001 161.4275)
		(width 0.1)
		(layer "In6.Cu")
		(net 702)
	)
	(segment
		(start 121.976501 161.702)
		(end 125.126501 161.702)
		(width 0.1)
		(layer "In6.Cu")
		(net 702)
	)
	(segment
		(start 116.222734 167.455771)
		(end 116.222734 167.455767)
		(width 0.1)
		(layer "In6.Cu")
		(net 702)
	)
	(segment
		(start 126.426501 161.752)
		(end 126.426501 161.952)
		(width 0.1)
		(layer "In6.Cu")
		(net 702)
	)
	(segment
		(start 118.326387 165.352117)
		(end 118.326385 165.352118)
		(width 0.1)
		(layer "In6.Cu")
		(net 702)
	)
	(segment
		(start 116.09899 167.332027)
		(end 116.222734 167.455771)
		(width 0.1)
		(layer "In6.Cu")
		(net 702)
	)
	(segment
		(start 117.441938 165.70511)
		(end 117.707666 165.970838)
		(width 0.1)
		(layer "In6.Cu")
		(net 702)
	)
	(segment
		(start 116.735948 167.721493)
		(end 116.735948 167.721494)
		(width 0.1)
		(layer "In6.Cu")
		(net 702)
	)
	(segment
		(start 116.451984 166.695064)
		(end 116.717712 166.960792)
		(width 0.1)
		(layer "In6.Cu")
		(net 702)
	)
	(segment
		(start 126.102001 161.4275)
		(end 126.426501 161.752)
		(width 0.1)
		(layer "In6.Cu")
		(net 702)
	)
	(segment
		(start 117.689427 165.210134)
		(end 117.689427 165.210133)
		(width 0.1)
		(layer "In6.Cu")
		(net 702)
	)
	(segment
		(start 117.725902 166.731539)
		(end 117.725902 166.73154)
		(width 0.1)
		(layer "In6.Cu")
		(net 702)
	)
	(segment
		(start 118.220879 165.989075)
		(end 117.955151 165.723347)
		(width 0.1)
		(layer "In6.Cu")
		(net 702)
	)
	(segment
		(start 117.230925 167.226516)
		(end 117.230925 167.226517)
		(width 0.1)
		(layer "In6.Cu")
		(net 702)
	)
	(segment
		(start 116.222734 167.455767)
		(end 116.488461 167.721494)
		(width 0.1)
		(layer "In6.Cu")
		(net 702)
	)
	(segment
		(start 117.936915 165.210133)
		(end 118.078899 165.352117)
		(width 0.1)
		(layer "In6.Cu")
		(net 702)
	)
	(segment
		(start 116.965197 166.713301)
		(end 116.699472 166.447575)
		(width 0.1)
		(layer "In6.Cu")
		(net 702)
	)
	(segment
		(start 115.851501 167.579514)
		(end 115.851502 167.579512)
		(width 0.1)
		(layer "In6.Cu")
		(net 702)
	)
	(segment
		(start 126.426501 161.952)
		(end 126.877001 162.4025)
		(width 0.1)
		(layer "In6.Cu")
		(net 702)
	)
	(segment
		(start 125.126501 161.702)
		(end 125.401001 161.4275)
		(width 0.1)
		(layer "In6.Cu")
		(net 702)
	)
	(arc
		(start 117.194449 165.952598)
		(mid 117.143193 165.828854)
		(end 117.19445 165.705111)
		(width 0.1)
		(layer "In6.Cu")
		(net 702)
	)
	(arc
		(start 115.709518 167.190043)
		(mid 115.833262 167.138787)
		(end 115.957006 167.190043)
		(width 0.1)
		(layer "In6.Cu")
		(net 702)
	)
	(arc
		(start 117.230925 167.226517)
		(mid 117.282181 167.102773)
		(end 117.230925 166.979029)
		(width 0.1)
		(layer "In6.Cu")
		(net 702)
	)
	(arc
		(start 116.699472 166.447575)
		(mid 116.648216 166.323831)
		(end 116.699473 166.200088)
		(width 0.1)
		(layer "In6.Cu")
		(net 702)
	)
	(arc
		(start 116.699473 166.200087)
		(mid 116.823217 166.148831)
		(end 116.946961 166.200087)
		(width 0.1)
		(layer "In6.Cu")
		(net 702)
	)
	(arc
		(start 115.709519 167.437529)
		(mid 115.658263 167.313785)
		(end 115.709519 167.190041)
		(width 0.1)
		(layer "In6.Cu")
		(net 702)
	)
	(arc
		(start 118.078899 165.352117)
		(mid 118.202643 165.403373)
		(end 118.326387 165.352117)
		(width 0.1)
		(layer "In6.Cu")
		(net 702)
	)
	(arc
		(start 116.983438 167.226517)
		(mid 117.107182 167.277773)
		(end 117.230925 167.226516)
		(width 0.1)
		(layer "In6.Cu")
		(net 702)
	)
	(arc
		(start 117.973392 166.236563)
		(mid 118.097136 166.287819)
		(end 118.220879 166.236562)
		(width 0.1)
		(layer "In6.Cu")
		(net 702)
	)
	(arc
		(start 117.689427 165.210133)
		(mid 117.813171 165.158877)
		(end 117.936915 165.210133)
		(width 0.1)
		(layer "In6.Cu")
		(net 702)
	)
	(arc
		(start 116.488461 167.721494)
		(mid 116.612205 167.77275)
		(end 116.735948 167.721493)
		(width 0.1)
		(layer "In6.Cu")
		(net 702)
	)
	(arc
		(start 117.689426 165.457621)
		(mid 117.63817 165.333877)
		(end 117.689427 165.210134)
		(width 0.1)
		(layer "In6.Cu")
		(net 702)
	)
	(arc
		(start 117.725902 166.73154)
		(mid 117.777158 166.607796)
		(end 117.725902 166.484052)
		(width 0.1)
		(layer "In6.Cu")
		(net 702)
	)
	(arc
		(start 117.478415 166.73154)
		(mid 117.602159 166.782796)
		(end 117.725902 166.731539)
		(width 0.1)
		(layer "In6.Cu")
		(net 702)
	)
	(arc
		(start 116.735948 167.721494)
		(mid 116.787204 167.59775)
		(end 116.735948 167.474006)
		(width 0.1)
		(layer "In6.Cu")
		(net 702)
	)
	(arc
		(start 115.851501 167.827)
		(mid 115.902758 167.703256)
		(end 115.851501 167.579514)
		(width 0.1)
		(layer "In6.Cu")
		(net 702)
	)
	(arc
		(start 117.19445 165.70511)
		(mid 117.318194 165.653854)
		(end 117.441938 165.70511)
		(width 0.1)
		(layer "In6.Cu")
		(net 702)
	)
	(arc
		(start 116.204495 166.942552)
		(mid 116.153239 166.818808)
		(end 116.204496 166.695065)
		(width 0.1)
		(layer "In6.Cu")
		(net 702)
	)
	(arc
		(start 116.204496 166.695064)
		(mid 116.32824 166.643808)
		(end 116.451984 166.695064)
		(width 0.1)
		(layer "In6.Cu")
		(net 702)
	)
	(arc
		(start 118.220879 166.236563)
		(mid 118.272135 166.112819)
		(end 118.220879 165.989075)
		(width 0.1)
		(layer "In6.Cu")
		(net 702)
	)
	(segment
		(start 127.376501 162.302)
		(end 126.877001 161.8025)
		(width 0.256)
		(layer "F.Cu")
		(net 703)
	)
	(segment
		(start 116.201001 175.3765)
		(end 116.651501 174.926)
		(width 0.256)
		(layer "F.Cu")
		(net 703)
	)
	(via
		(at 116.201001 175.3765)
		(size 0.45)
		(drill 0.1)
		(layers "F.Cu" "B.Cu")
		(net 703)
	)
	(via
		(at 126.877001 161.8025)
		(size 0.45)
		(drill 0.1)
		(layers "F.Cu" "B.Cu")
		(net 703)
	)
	(segment
		(start 120.470174 162.206335)
		(end 120.222166 161.958327)
		(width 0.1)
		(layer "In6.Cu")
		(net 703)
	)
	(segment
		(start 115.951001 175.3765)
		(end 116.201001 175.3765)
		(width 0.1)
		(layer "In6.Cu")
		(net 703)
	)
	(segment
		(start 118.755179 163.67332)
		(end 117.845671 164.58283)
		(width 0.1)
		(layer "In6.Cu")
		(net 703)
	)
	(segment
		(start 119.197382 163.479127)
		(end 118.949374 163.231119)
		(width 0.1)
		(layer "In6.Cu")
		(net 703)
	)
	(segment
		(start 125.126501 161.102)
		(end 124.976501 161.252)
		(width 0.1)
		(layer "In6.Cu")
		(net 703)
	)
	(segment
		(start 120.04591 162.630599)
		(end 119.797902 162.382591)
		(width 0.1)
		(layer "In6.Cu")
		(net 703)
	)
	(segment
		(start 120.010034 162.170459)
		(end 120.258042 162.418467)
		(width 0.1)
		(layer "In6.Cu")
		(net 703)
	)
	(segment
		(start 119.58577 162.594723)
		(end 119.833778 162.842731)
		(width 0.1)
		(layer "In6.Cu")
		(net 703)
	)
	(segment
		(start 115.126501 174.552)
		(end 115.951001 175.3765)
		(width 0.1)
		(layer "In6.Cu")
		(net 703)
	)
	(segment
		(start 117.845671 164.58283)
		(end 115.126501 167.302)
		(width 0.1)
		(layer "In6.Cu")
		(net 703)
	)
	(segment
		(start 119.621646 163.054863)
		(end 119.373638 162.806855)
		(width 0.1)
		(layer "In6.Cu")
		(net 703)
	)
	(segment
		(start 124.976501 161.252)
		(end 121.176501 161.252)
		(width 0.1)
		(layer "In6.Cu")
		(net 703)
	)
	(segment
		(start 120.452235 161.764131)
		(end 120.682306 161.994203)
		(width 0.1)
		(layer "In6.Cu")
		(net 703)
	)
	(segment
		(start 120.664368 161.552)
		(end 120.64643 161.534062)
		(width 0.1)
		(layer "In6.Cu")
		(net 703)
	)
	(segment
		(start 118.737242 163.443251)
		(end 118.755179 163.461188)
		(width 0.1)
		(layer "In6.Cu")
		(net 703)
	)
	(segment
		(start 115.126501 167.302)
		(end 115.126501 174.552)
		(width 0.1)
		(layer "In6.Cu")
		(net 703)
	)
	(segment
		(start 121.176501 161.252)
		(end 120.876501 161.552)
		(width 0.1)
		(layer "In6.Cu")
		(net 703)
	)
	(segment
		(start 120.664367 161.552)
		(end 120.664368 161.552)
		(width 0.1)
		(layer "In6.Cu")
		(net 703)
	)
	(segment
		(start 126.176501 161.102)
		(end 125.126501 161.102)
		(width 0.1)
		(layer "In6.Cu")
		(net 703)
	)
	(segment
		(start 119.161506 163.018987)
		(end 119.409514 163.266995)
		(width 0.1)
		(layer "In6.Cu")
		(net 703)
	)
	(segment
		(start 126.877001 161.8025)
		(end 126.176501 161.102)
		(width 0.1)
		(layer "In6.Cu")
		(net 703)
	)
	(segment
		(start 120.434298 161.746194)
		(end 120.452235 161.764131)
		(width 0.1)
		(layer "In6.Cu")
		(net 703)
	)
	(arc
		(start 119.409514 163.266995)
		(mid 119.453448 163.373061)
		(end 119.409514 163.479127)
		(width 0.1)
		(layer "In6.Cu")
		(net 703)
	)
	(arc
		(start 119.373638 162.806855)
		(mid 119.267572 162.762921)
		(end 119.161506 162.806855)
		(width 0.1)
		(layer "In6.Cu")
		(net 703)
	)
	(arc
		(start 119.161506 162.806855)
		(mid 119.117572 162.912921)
		(end 119.161506 163.018987)
		(width 0.1)
		(layer "In6.Cu")
		(net 703)
	)
	(arc
		(start 119.797902 162.382591)
		(mid 119.691836 162.338657)
		(end 119.58577 162.382591)
		(width 0.1)
		(layer "In6.Cu")
		(net 703)
	)
	(arc
		(start 120.682306 162.206335)
		(mid 120.57624 162.250269)
		(end 120.470174 162.206335)
		(width 0.1)
		(layer "In6.Cu")
		(net 703)
	)
	(arc
		(start 120.258042 162.418467)
		(mid 120.301976 162.524533)
		(end 120.258042 162.630599)
		(width 0.1)
		(layer "In6.Cu")
		(net 703)
	)
	(arc
		(start 120.64643 161.534062)
		(mid 120.540364 161.490128)
		(end 120.434298 161.534062)
		(width 0.1)
		(layer "In6.Cu")
		(net 703)
	)
	(arc
		(start 118.755179 163.461188)
		(mid 118.799113 163.567254)
		(end 118.755179 163.67332)
		(width 0.1)
		(layer "In6.Cu")
		(net 703)
	)
	(arc
		(start 120.682306 161.994203)
		(mid 120.72624 162.100269)
		(end 120.682306 162.206335)
		(width 0.1)
		(layer "In6.Cu")
		(net 703)
	)
	(arc
		(start 120.258042 162.630599)
		(mid 120.151976 162.674533)
		(end 120.04591 162.630599)
		(width 0.1)
		(layer "In6.Cu")
		(net 703)
	)
	(arc
		(start 118.737242 163.231119)
		(mid 118.693308 163.337185)
		(end 118.737242 163.443251)
		(width 0.1)
		(layer "In6.Cu")
		(net 703)
	)
	(arc
		(start 119.833778 163.054863)
		(mid 119.727712 163.098797)
		(end 119.621646 163.054863)
		(width 0.1)
		(layer "In6.Cu")
		(net 703)
	)
	(arc
		(start 120.876501 161.552)
		(mid 120.770434 161.595934)
		(end 120.664367 161.552)
		(width 0.1)
		(layer "In6.Cu")
		(net 703)
	)
	(arc
		(start 118.949374 163.231119)
		(mid 118.843308 163.187185)
		(end 118.737242 163.231119)
		(width 0.1)
		(layer "In6.Cu")
		(net 703)
	)
	(arc
		(start 120.222166 161.958327)
		(mid 120.1161 161.914393)
		(end 120.010034 161.958327)
		(width 0.1)
		(layer "In6.Cu")
		(net 703)
	)
	(arc
		(start 119.58577 162.382591)
		(mid 119.541836 162.488657)
		(end 119.58577 162.594723)
		(width 0.1)
		(layer "In6.Cu")
		(net 703)
	)
	(arc
		(start 120.434298 161.534062)
		(mid 120.390364 161.640128)
		(end 120.434298 161.746194)
		(width 0.1)
		(layer "In6.Cu")
		(net 703)
	)
	(arc
		(start 120.010034 161.958327)
		(mid 119.9661 162.064393)
		(end 120.010034 162.170459)
		(width 0.1)
		(layer "In6.Cu")
		(net 703)
	)
	(arc
		(start 119.833778 162.842731)
		(mid 119.877712 162.948797)
		(end 119.833778 163.054863)
		(width 0.1)
		(layer "In6.Cu")
		(net 703)
	)
	(arc
		(start 119.409514 163.479127)
		(mid 119.303448 163.523061)
		(end 119.197382 163.479127)
		(width 0.1)
		(layer "In6.Cu")
		(net 703)
	)
	(segment
		(start 89.320493 157.546008)
		(end 90.11468 157.546008)
		(width 0.256)
		(layer "F.Cu")
		(net 704)
	)
	(segment
		(start 128.376501 167.302)
		(end 127.877001 166.8025)
		(width 0.256)
		(layer "F.Cu")
		(net 704)
	)
	(via
		(at 89.320493 157.546008)
		(size 0.45)
		(drill 0.1)
		(layers "F.Cu" "B.Cu")
		(net 704)
	)
	(via
		(at 127.877001 166.8025)
		(size 0.45)
		(drill 0.1)
		(layers "F.Cu" "B.Cu")
		(net 704)
	)
	(segment
		(start 89.320493 157.546008)
		(end 89.343344 157.568859)
		(width 0.1)
		(layer "In9.Cu")
		(net 704)
	)
	(segment
		(start 115.921859 161.743356)
		(end 116.268358 161.396862)
		(width 0.1)
		(layer "In9.Cu")
		(net 704)
	)
	(segment
		(start 89.343344 157.568859)
		(end 95.91336 157.568859)
		(width 0.1)
		(layer "In9.Cu")
		(net 704)
	)
	(segment
		(start 117.053235 162.874732)
		(end 117.399734 162.528238)
		(width 0.1)
		(layer "In9.Cu")
		(net 704)
	)
	(segment
		(start 104.9 158.3)
		(end 112.825 158.3)
		(width 0.1)
		(layer "In9.Cu")
		(net 704)
	)
	(segment
		(start 116.551201 161.396862)
		(end 116.5512 161.396861)
		(width 0.1)
		(layer "In9.Cu")
		(net 704)
	)
	(segment
		(start 114.854137 159.98264)
		(end 114.507642 160.329138)
		(width 0.1)
		(layer "In9.Cu")
		(net 704)
	)
	(segment
		(start 114.571294 159.699798)
		(end 114.571294 159.699797)
		(width 0.1)
		(layer "In9.Cu")
		(net 704)
	)
	(segment
		(start 114.224795 160.046292)
		(end 114.571294 159.699798)
		(width 0.1)
		(layer "In9.Cu")
		(net 704)
	)
	(segment
		(start 127.252001 166.1775)
		(end 127.877001 166.8025)
		(width 0.1)
		(layer "In9.Cu")
		(net 704)
	)
	(segment
		(start 115.639017 161.743356)
		(end 115.639016 161.743355)
		(width 0.1)
		(layer "In9.Cu")
		(net 704)
	)
	(segment
		(start 116.487547 162.309044)
		(end 116.834046 161.96255)
		(width 0.1)
		(layer "In9.Cu")
		(net 704)
	)
	(segment
		(start 112.825 158.3)
		(end 113.408092 158.883091)
		(width 0.1)
		(layer "In9.Cu")
		(net 704)
	)
	(segment
		(start 114.288449 159.416952)
		(end 113.941954 159.76345)
		(width 0.1)
		(layer "In9.Cu")
		(net 704)
	)
	(segment
		(start 116.770393 162.874732)
		(end 116.770392 162.874731)
		(width 0.1)
		(layer "In9.Cu")
		(net 704)
	)
	(segment
		(start 116.204706 162.026202)
		(end 116.204704 162.026201)
		(width 0.1)
		(layer "In9.Cu")
		(net 704)
	)
	(segment
		(start 117.682577 162.811081)
		(end 117.650751 162.842908)
		(width 0.1)
		(layer "In9.Cu")
		(net 704)
	)
	(segment
		(start 115.985513 161.114016)
		(end 115.639018 161.460514)
		(width 0.1)
		(layer "In9.Cu")
		(net 704)
	)
	(segment
		(start 97.605501 159.261)
		(end 103.939 159.261)
		(width 0.1)
		(layer "In9.Cu")
		(net 704)
	)
	(segment
		(start 113.659107 159.480604)
		(end 114.005606 159.13411)
		(width 0.1)
		(layer "In9.Cu")
		(net 704)
	)
	(segment
		(start 115.419825 160.548328)
		(end 115.07333 160.894826)
		(width 0.1)
		(layer "In9.Cu")
		(net 704)
	)
	(segment
		(start 116.551201 161.679704)
		(end 116.204706 162.026202)
		(width 0.1)
		(layer "In9.Cu")
		(net 704)
	)
	(segment
		(start 113.376266 159.197762)
		(end 113.376264 159.197761)
		(width 0.1)
		(layer "In9.Cu")
		(net 704)
	)
	(segment
		(start 113.376265 159.480604)
		(end 113.376264 159.480603)
		(width 0.1)
		(layer "In9.Cu")
		(net 704)
	)
	(segment
		(start 115.073329 161.177668)
		(end 115.073328 161.177667)
		(width 0.1)
		(layer "In9.Cu")
		(net 704)
	)
	(segment
		(start 103.939 159.261)
		(end 104.9 158.3)
		(width 0.1)
		(layer "In9.Cu")
		(net 704)
	)
	(segment
		(start 117.650751 163.125751)
		(end 117.925 163.4)
		(width 0.1)
		(layer "In9.Cu")
		(net 704)
	)
	(segment
		(start 116.204705 162.309044)
		(end 116.204704 162.309043)
		(width 0.1)
		(layer "In9.Cu")
		(net 704)
	)
	(segment
		(start 117.925 163.4)
		(end 122.65 163.4)
		(width 0.1)
		(layer "In9.Cu")
		(net 704)
	)
	(segment
		(start 117.116889 161.96255)
		(end 117.116888 161.962549)
		(width 0.1)
		(layer "In9.Cu")
		(net 704)
	)
	(segment
		(start 114.288449 159.13411)
		(end 114.288448 159.134109)
		(width 0.1)
		(layer "In9.Cu")
		(net 704)
	)
	(segment
		(start 113.941953 160.046292)
		(end 113.941952 160.046291)
		(width 0.1)
		(layer "In9.Cu")
		(net 704)
	)
	(segment
		(start 114.507642 160.329138)
		(end 114.50764 160.329137)
		(width 0.1)
		(layer "In9.Cu")
		(net 704)
	)
	(segment
		(start 115.136982 160.265486)
		(end 115.136982 160.265485)
		(width 0.1)
		(layer "In9.Cu")
		(net 704)
	)
	(segment
		(start 122.65 163.4)
		(end 125.4275 166.1775)
		(width 0.1)
		(layer "In9.Cu")
		(net 704)
	)
	(segment
		(start 117.650751 162.842908)
		(end 117.65075 162.842908)
		(width 0.1)
		(layer "In9.Cu")
		(net 704)
	)
	(segment
		(start 125.4275 166.1775)
		(end 127.252001 166.1775)
		(width 0.1)
		(layer "In9.Cu")
		(net 704)
	)
	(segment
		(start 115.639018 161.460514)
		(end 115.639016 161.460513)
		(width 0.1)
		(layer "In9.Cu")
		(net 704)
	)
	(segment
		(start 114.507641 160.61198)
		(end 114.50764 160.611979)
		(width 0.1)
		(layer "In9.Cu")
		(net 704)
	)
	(segment
		(start 117.682577 162.528238)
		(end 117.682578 162.528238)
		(width 0.1)
		(layer "In9.Cu")
		(net 704)
	)
	(segment
		(start 117.116889 162.245392)
		(end 116.770394 162.59189)
		(width 0.1)
		(layer "In9.Cu")
		(net 704)
	)
	(segment
		(start 113.408091 159.165934)
		(end 113.376266 159.197762)
		(width 0.1)
		(layer "In9.Cu")
		(net 704)
	)
	(segment
		(start 113.941954 159.76345)
		(end 113.941952 159.763449)
		(width 0.1)
		(layer "In9.Cu")
		(net 704)
	)
	(segment
		(start 116.268358 161.396862)
		(end 116.268358 161.396861)
		(width 0.1)
		(layer "In9.Cu")
		(net 704)
	)
	(segment
		(start 95.91336 157.568859)
		(end 97.605501 159.261)
		(width 0.1)
		(layer "In9.Cu")
		(net 704)
	)
	(segment
		(start 115.07333 160.894826)
		(end 115.073328 160.894825)
		(width 0.1)
		(layer "In9.Cu")
		(net 704)
	)
	(segment
		(start 115.985513 160.831174)
		(end 115.985512 160.831173)
		(width 0.1)
		(layer "In9.Cu")
		(net 704)
	)
	(segment
		(start 116.834046 161.96255)
		(end 116.834046 161.962549)
		(width 0.1)
		(layer "In9.Cu")
		(net 704)
	)
	(segment
		(start 117.399734 162.528238)
		(end 117.399734 162.528237)
		(width 0.1)
		(layer "In9.Cu")
		(net 704)
	)
	(segment
		(start 114.790483 160.61198)
		(end 115.136982 160.265486)
		(width 0.1)
		(layer "In9.Cu")
		(net 704)
	)
	(segment
		(start 114.005606 159.13411)
		(end 114.005606 159.134109)
		(width 0.1)
		(layer "In9.Cu")
		(net 704)
	)
	(segment
		(start 114.854137 159.699798)
		(end 114.854136 159.699797)
		(width 0.1)
		(layer "In9.Cu")
		(net 704)
	)
	(segment
		(start 116.770394 162.59189)
		(end 116.770392 162.591889)
		(width 0.1)
		(layer "In9.Cu")
		(net 704)
	)
	(segment
		(start 115.419825 160.265486)
		(end 115.419824 160.265485)
		(width 0.1)
		(layer "In9.Cu")
		(net 704)
	)
	(segment
		(start 115.356171 161.177668)
		(end 115.70267 160.831174)
		(width 0.1)
		(layer "In9.Cu")
		(net 704)
	)
	(segment
		(start 115.70267 160.831174)
		(end 115.70267 160.831173)
		(width 0.1)
		(layer "In9.Cu")
		(net 704)
	)
	(arc
		(start 114.50764 160.611979)
		(mid 114.649061 160.670558)
		(end 114.790483 160.61198)
		(width 0.1)
		(layer "In9.Cu")
		(net 704)
	)
	(arc
		(start 115.073328 161.177667)
		(mid 115.214749 161.236246)
		(end 115.356171 161.177668)
		(width 0.1)
		(layer "In9.Cu")
		(net 704)
	)
	(arc
		(start 113.408092 158.883091)
		(mid 113.46667 159.024513)
		(end 113.408091 159.165934)
		(width 0.1)
		(layer "In9.Cu")
		(net 704)
	)
	(arc
		(start 116.5512 161.396861)
		(mid 116.609779 161.538282)
		(end 116.551201 161.679704)
		(width 0.1)
		(layer "In9.Cu")
		(net 704)
	)
	(arc
		(start 116.204704 162.309043)
		(mid 116.346125 162.367622)
		(end 116.487547 162.309044)
		(width 0.1)
		(layer "In9.Cu")
		(net 704)
	)
	(arc
		(start 115.639016 161.743355)
		(mid 115.780437 161.801934)
		(end 115.921859 161.743356)
		(width 0.1)
		(layer "In9.Cu")
		(net 704)
	)
	(arc
		(start 115.70267 160.831173)
		(mid 115.844092 160.772595)
		(end 115.985513 160.831174)
		(width 0.1)
		(layer "In9.Cu")
		(net 704)
	)
	(arc
		(start 117.682578 162.528238)
		(mid 117.741156 162.66966)
		(end 117.682577 162.811081)
		(width 0.1)
		(layer "In9.Cu")
		(net 704)
	)
	(arc
		(start 116.770392 162.874731)
		(mid 116.911813 162.93331)
		(end 117.053235 162.874732)
		(width 0.1)
		(layer "In9.Cu")
		(net 704)
	)
	(arc
		(start 115.136982 160.265485)
		(mid 115.278404 160.206907)
		(end 115.419825 160.265486)
		(width 0.1)
		(layer "In9.Cu")
		(net 704)
	)
	(arc
		(start 117.65075 162.842908)
		(mid 117.592172 162.98433)
		(end 117.650751 163.125751)
		(width 0.1)
		(layer "In9.Cu")
		(net 704)
	)
	(arc
		(start 114.288448 159.134109)
		(mid 114.347027 159.27553)
		(end 114.288449 159.416952)
		(width 0.1)
		(layer "In9.Cu")
		(net 704)
	)
	(arc
		(start 116.204704 162.026201)
		(mid 116.146126 162.167623)
		(end 116.204705 162.309044)
		(width 0.1)
		(layer "In9.Cu")
		(net 704)
	)
	(arc
		(start 114.854136 159.699797)
		(mid 114.912715 159.841218)
		(end 114.854137 159.98264)
		(width 0.1)
		(layer "In9.Cu")
		(net 704)
	)
	(arc
		(start 117.116888 161.962549)
		(mid 117.175467 162.10397)
		(end 117.116889 162.245392)
		(width 0.1)
		(layer "In9.Cu")
		(net 704)
	)
	(arc
		(start 115.985512 160.831173)
		(mid 116.044091 160.972594)
		(end 115.985513 161.114016)
		(width 0.1)
		(layer "In9.Cu")
		(net 704)
	)
	(arc
		(start 114.50764 160.329137)
		(mid 114.449062 160.470559)
		(end 114.507641 160.61198)
		(width 0.1)
		(layer "In9.Cu")
		(net 704)
	)
	(arc
		(start 113.376264 159.197761)
		(mid 113.317686 159.339183)
		(end 113.376265 159.480604)
		(width 0.1)
		(layer "In9.Cu")
		(net 704)
	)
	(arc
		(start 116.268358 161.396861)
		(mid 116.40978 161.338283)
		(end 116.551201 161.396862)
		(width 0.1)
		(layer "In9.Cu")
		(net 704)
	)
	(arc
		(start 115.639016 161.460513)
		(mid 115.580438 161.601935)
		(end 115.639017 161.743356)
		(width 0.1)
		(layer "In9.Cu")
		(net 704)
	)
	(arc
		(start 114.571294 159.699797)
		(mid 114.712716 159.641219)
		(end 114.854137 159.699798)
		(width 0.1)
		(layer "In9.Cu")
		(net 704)
	)
	(arc
		(start 113.941952 159.763449)
		(mid 113.883374 159.904871)
		(end 113.941953 160.046292)
		(width 0.1)
		(layer "In9.Cu")
		(net 704)
	)
	(arc
		(start 114.005606 159.134109)
		(mid 114.147028 159.075531)
		(end 114.288449 159.13411)
		(width 0.1)
		(layer "In9.Cu")
		(net 704)
	)
	(arc
		(start 117.399734 162.528237)
		(mid 117.541156 162.469659)
		(end 117.682577 162.528238)
		(width 0.1)
		(layer "In9.Cu")
		(net 704)
	)
	(arc
		(start 115.419824 160.265485)
		(mid 115.478403 160.406906)
		(end 115.419825 160.548328)
		(width 0.1)
		(layer "In9.Cu")
		(net 704)
	)
	(arc
		(start 115.073328 160.894825)
		(mid 115.01475 161.036247)
		(end 115.073329 161.177668)
		(width 0.1)
		(layer "In9.Cu")
		(net 704)
	)
	(arc
		(start 116.834046 161.962549)
		(mid 116.975468 161.903971)
		(end 117.116889 161.96255)
		(width 0.1)
		(layer "In9.Cu")
		(net 704)
	)
	(arc
		(start 113.941952 160.046291)
		(mid 114.083373 160.10487)
		(end 114.224795 160.046292)
		(width 0.1)
		(layer "In9.Cu")
		(net 704)
	)
	(arc
		(start 116.770392 162.591889)
		(mid 116.711814 162.733311)
		(end 116.770393 162.874732)
		(width 0.1)
		(layer "In9.Cu")
		(net 704)
	)
	(arc
		(start 113.376264 159.480603)
		(mid 113.517685 159.539182)
		(end 113.659107 159.480604)
		(width 0.1)
		(layer "In9.Cu")
		(net 704)
	)
	(segment
		(start 96.300501 158.701)
		(end 96.675501 159.076)
		(width 0.256)
		(layer "F.Cu")
		(net 705)
	)
	(segment
		(start 127.376501 167.302)
		(end 126.877001 166.8025)
		(width 0.256)
		(layer "F.Cu")
		(net 705)
	)
	(segment
		(start 96.300501 158.285)
		(end 96.300501 158.701)
		(width 0.256)
		(layer "F.Cu")
		(net 705)
	)
	(via
		(at 96.675501 159.076)
		(size 0.45)
		(drill 0.1)
		(layers "F.Cu" "B.Cu")
		(net 705)
	)
	(via
		(at 126.877001 166.8025)
		(size 0.45)
		(drill 0.1)
		(layers "F.Cu" "B.Cu")
		(net 705)
	)
	(segment
		(start 116.724501 164.2)
		(end 122.249 164.2)
		(width 0.1)
		(layer "In9.Cu")
		(net 705)
	)
	(segment
		(start 97.199501 159.6)
		(end 104.5 159.6)
		(width 0.1)
		(layer "In9.Cu")
		(net 705)
	)
	(segment
		(start 96.675501 159.076)
		(end 97.199501 159.6)
		(width 0.1)
		(layer "In9.Cu")
		(net 705)
	)
	(segment
		(start 126.500501 166.426)
		(end 126.877001 166.8025)
		(width 0.1)
		(layer "In9.Cu")
		(net 705)
	)
	(segment
		(start 111.650501 159.126)
		(end 116.724501 164.2)
		(width 0.1)
		(layer "In9.Cu")
		(net 705)
	)
	(segment
		(start 124.475 166.426)
		(end 126.500501 166.426)
		(width 0.1)
		(layer "In9.Cu")
		(net 705)
	)
	(segment
		(start 104.974 159.126)
		(end 111.650501 159.126)
		(width 0.1)
		(layer "In9.Cu")
		(net 705)
	)
	(segment
		(start 104.5 159.6)
		(end 104.974 159.126)
		(width 0.1)
		(layer "In9.Cu")
		(net 705)
	)
	(segment
		(start 122.249 164.2)
		(end 124.475 166.426)
		(width 0.1)
		(layer "In9.Cu")
		(net 705)
	)
	(segment
		(start 137.892 189.176)
		(end 136.269 190.799)
		(width 0.256)
		(layer "F.Cu")
		(net 706)
	)
	(segment
		(start 140.875001 185.8005)
		(end 140.875001 188.6015)
		(width 0.256)
		(layer "F.Cu")
		(net 706)
	)
	(segment
		(start 140.300501 189.176)
		(end 137.892 189.176)
		(width 0.256)
		(layer "F.Cu")
		(net 706)
	)
	(segment
		(start 140.875001 188.6015)
		(end 140.300501 189.176)
		(width 0.256)
		(layer "F.Cu")
		(net 706)
	)
	(segment
		(start 140.375501 185.301)
		(end 140.875001 185.8005)
		(width 0.256)
		(layer "F.Cu")
		(net 706)
	)
	(segment
		(start 92.351 162.801)
		(end 95.400501 162.801)
		(width 0.256)
		(layer "F.Cu")
		(net 732)
	)
	(segment
		(start 126.376501 171.302)
		(end 125.877001 170.8025)
		(width 0.256)
		(layer "F.Cu")
		(net 732)
	)
	(segment
		(start 90.801501 158.285)
		(end 90.801501 161.251501)
		(width 0.256)
		(layer "F.Cu")
		(net 732)
	)
	(segment
		(start 90.801501 161.251501)
		(end 92.351 162.801)
		(width 0.256)
		(layer "F.Cu")
		(net 732)
	)
	(via
		(at 125.877001 170.8025)
		(size 0.45)
		(drill 0.1)
		(layers "F.Cu" "B.Cu")
		(net 732)
	)
	(via
		(at 95.400501 162.801)
		(size 0.45)
		(drill 0.1)
		(layers "F.Cu" "B.Cu")
		(net 732)
	)
	(segment
		(start 102.824501 165.9)
		(end 109.624501 172.7)
		(width 0.1)
		(layer "In9.Cu")
		(net 732)
	)
	(segment
		(start 95.400501 162.801)
		(end 95.950501 163.351)
		(width 0.1)
		(layer "In9.Cu")
		(net 732)
	)
	(segment
		(start 123.976501 172.7)
		(end 125.875501 170.801)
		(width 0.1)
		(layer "In9.Cu")
		(net 732)
	)
	(segment
		(start 97.324501 165.9)
		(end 102.824501 165.9)
		(width 0.1)
		(layer "In9.Cu")
		(net 732)
	)
	(segment
		(start 95.950501 164.526)
		(end 97.324501 165.9)
		(width 0.1)
		(layer "In9.Cu")
		(net 732)
	)
	(segment
		(start 109.624501 172.7)
		(end 123.976501 172.7)
		(width 0.1)
		(layer "In9.Cu")
		(net 732)
	)
	(segment
		(start 95.950501 163.351)
		(end 95.950501 164.526)
		(width 0.1)
		(layer "In9.Cu")
		(net 732)
	)
	(segment
		(start 89.154746 154.986074)
		(end 89.154746 154.957657)
		(width 0.15)
		(layer "F.Cu")
		(net 733)
	)
	(segment
		(start 89.231089 155.034)
		(end 90.051501 155.034)
		(width 0.256)
		(layer "F.Cu")
		(net 733)
	)
	(segment
		(start 89.21468 155.046008)
		(end 89.154746 154.986074)
		(width 0.15)
		(layer "F.Cu")
		(net 733)
	)
	(segment
		(start 89.154746 154.957657)
		(end 89.231089 155.034)
		(width 0.256)
		(layer "F.Cu")
		(net 733)
	)
	(segment
		(start 128.376501 169.302)
		(end 127.877001 168.8025)
		(width 0.256)
		(layer "F.Cu")
		(net 733)
	)
	(via
		(at 89.154746 154.957657)
		(size 0.45)
		(drill 0.1)
		(layers "F.Cu" "B.Cu")
		(net 733)
	)
	(via
		(at 127.877001 168.8025)
		(size 0.45)
		(drill 0.1)
		(layers "F.Cu" "B.Cu")
		(net 733)
	)
	(segment
		(start 124.472501 169.427499)
		(end 127.252002 169.427499)
		(width 0.1)
		(layer "In9.Cu")
		(net 733)
	)
	(segment
		(start 127.877001 168.8025)
		(end 127.252002 169.427499)
		(width 0.1)
		(layer "In9.Cu")
		(net 733)
	)
	(segment
		(start 87.708844 154.957657)
		(end 86.715501 155.951)
		(width 0.1)
		(layer "In9.Cu")
		(net 733)
	)
	(segment
		(start 110.6 170.2)
		(end 123.7 170.2)
		(width 0.1)
		(layer "In9.Cu")
		(net 733)
	)
	(segment
		(start 97.671501 162.1)
		(end 97.950501 162.379)
		(width 0.1)
		(layer "In9.Cu")
		(net 733)
	)
	(segment
		(start 97.950501 163.701)
		(end 99.149501 164.9)
		(width 0.1)
		(layer "In9.Cu")
		(net 733)
	)
	(segment
		(start 99.149501 164.9)
		(end 105.3 164.9)
		(width 0.1)
		(layer "In9.Cu")
		(net 733)
	)
	(segment
		(start 123.7 170.2)
		(end 124.472501 169.427499)
		(width 0.1)
		(layer "In9.Cu")
		(net 733)
	)
	(segment
		(start 89.154746 154.957657)
		(end 87.708844 154.957657)
		(width 0.1)
		(layer "In9.Cu")
		(net 733)
	)
	(segment
		(start 90 162.1)
		(end 97.671501 162.1)
		(width 0.1)
		(layer "In9.Cu")
		(net 733)
	)
	(segment
		(start 105.3 164.9)
		(end 110.6 170.2)
		(width 0.1)
		(layer "In9.Cu")
		(net 733)
	)
	(segment
		(start 97.950501 162.379)
		(end 97.950501 163.701)
		(width 0.1)
		(layer "In9.Cu")
		(net 733)
	)
	(segment
		(start 86.715501 155.951)
		(end 86.715501 158.815501)
		(width 0.1)
		(layer "In9.Cu")
		(net 733)
	)
	(segment
		(start 86.715501 158.815501)
		(end 90 162.1)
		(width 0.1)
		(layer "In9.Cu")
		(net 733)
	)
	(segment
		(start 98.169501 157.035)
		(end 97.050501 157.035)
		(width 0.256)
		(layer "F.Cu")
		(net 734)
	)
	(segment
		(start 132.376501 168.302)
		(end 131.877001 167.8025)
		(width 0.256)
		(layer "F.Cu")
		(net 734)
	)
	(segment
		(start 98.210501 157.076)
		(end 98.169501 157.035)
		(width 0.256)
		(layer "F.Cu")
		(net 734)
	)
	(via
		(at 131.877001 167.8025)
		(size 0.45)
		(drill 0.1)
		(layers "F.Cu" "B.Cu")
		(net 734)
	)
	(via
		(at 98.210501 157.076)
		(size 0.45)
		(drill 0.1)
		(layers "F.Cu" "B.Cu")
		(net 734)
	)
	(segment
		(start 98.210501 157.076)
		(end 99.886501 155.4)
		(width 0.1)
		(layer "In9.Cu")
		(net 734)
	)
	(segment
		(start 126.45 164.002915)
		(end 126.697085 164.25)
		(width 0.1)
		(layer "In9.Cu")
		(net 734)
	)
	(segment
		(start 128.45 165.90583)
		(end 128.89417 166.35)
		(width 0.1)
		(layer "In9.Cu")
		(net 734)
	)
	(segment
		(start 126.697085 164.25)
		(end 128.15 164.25)
		(width 0.1)
		(layer "In9.Cu")
		(net 734)
	)
	(segment
		(start 129.721669 167.1775)
		(end 131.252001 167.1775)
		(width 0.1)
		(layer "In9.Cu")
		(net 734)
	)
	(segment
		(start 128.15 164.25)
		(end 128.45 164.55)
		(width 0.1)
		(layer "In9.Cu")
		(net 734)
	)
	(segment
		(start 119.950501 161.326)
		(end 123.676 161.326)
		(width 0.1)
		(layer "In9.Cu")
		(net 734)
	)
	(segment
		(start 128.89417 166.35)
		(end 129.20625 166.35)
		(width 0.1)
		(layer "In9.Cu")
		(net 734)
	)
	(segment
		(start 131.252001 167.1775)
		(end 131.877001 167.8025)
		(width 0.1)
		(layer "In9.Cu")
		(net 734)
	)
	(segment
		(start 123.676 161.326)
		(end 125.65 163.3)
		(width 0.1)
		(layer "In9.Cu")
		(net 734)
	)
	(segment
		(start 114.024501 155.4)
		(end 119.950501 161.326)
		(width 0.1)
		(layer "In9.Cu")
		(net 734)
	)
	(segment
		(start 99.886501 155.4)
		(end 114.024501 155.4)
		(width 0.1)
		(layer "In9.Cu")
		(net 734)
	)
	(segment
		(start 129.4 166.54375)
		(end 129.4 166.855831)
		(width 0.1)
		(layer "In9.Cu")
		(net 734)
	)
	(segment
		(start 128.45 164.55)
		(end 128.45 165.90583)
		(width 0.1)
		(layer "In9.Cu")
		(net 734)
	)
	(segment
		(start 126.45 163.55)
		(end 126.45 164.002915)
		(width 0.1)
		(layer "In9.Cu")
		(net 734)
	)
	(segment
		(start 125.65 163.3)
		(end 126.2 163.3)
		(width 0.1)
		(layer "In9.Cu")
		(net 734)
	)
	(segment
		(start 126.2 163.3)
		(end 126.45 163.55)
		(width 0.1)
		(layer "In9.Cu")
		(net 734)
	)
	(segment
		(start 129.20625 166.35)
		(end 129.4 166.54375)
		(width 0.1)
		(layer "In9.Cu")
		(net 734)
	)
	(segment
		(start 129.4 166.855831)
		(end 129.721669 167.1775)
		(width 0.1)
		(layer "In9.Cu")
		(net 734)
	)
	(segment
		(start 131.376501 168.302)
		(end 130.877001 167.8025)
		(width 0.256)
		(layer "F.Cu")
		(net 735)
	)
	(segment
		(start 88.519501 156.535)
		(end 88.095501 156.111)
		(width 0.256)
		(layer "F.Cu")
		(net 735)
	)
	(segment
		(start 88.095501 156.111)
		(end 87.435501 156.111)
		(width 0.256)
		(layer "F.Cu")
		(net 735)
	)
	(segment
		(start 90.051501 156.535)
		(end 88.519501 156.535)
		(width 0.256)
		(layer "F.Cu")
		(net 735)
	)
	(via
		(at 87.435501 156.111)
		(size 0.45)
		(drill 0.1)
		(layers "F.Cu" "B.Cu")
		(net 735)
	)
	(via
		(at 130.877001 167.8025)
		(size 0.45)
		(drill 0.1)
		(layers "F.Cu" "B.Cu")
		(net 735)
	)
	(segment
		(start 104.850501 162.855885)
		(end 104.850501 163.396115)
		(width 0.1)
		(layer "In9.Cu")
		(net 735)
	)
	(segment
		(start 87.435501 156.111)
		(end 87.435501 158.335501)
		(width 0.1)
		(layer "In9.Cu")
		(net 735)
	)
	(segment
		(start 102.574 163.926)
		(end 103.374 163.126)
		(width 0.1)
		(layer "In9.Cu")
		(net 735)
	)
	(segment
		(start 100.600501 163.926)
		(end 102.574 163.926)
		(width 0.1)
		(layer "In9.Cu")
		(net 735)
	)
	(segment
		(start 113.026 168.026)
		(end 121.238869 168.026)
		(width 0.1)
		(layer "In9.Cu")
		(net 735)
	)
	(segment
		(start 100.050501 162.251)
		(end 100.050501 163.376)
		(width 0.1)
		(layer "In9.Cu")
		(net 735)
	)
	(segment
		(start 104.450501 163.396115)
		(end 104.450501 162.855885)
		(width 0.1)
		(layer "In9.Cu")
		(net 735)
	)
	(segment
		(start 99.299501 161.5)
		(end 100.050501 162.251)
		(width 0.1)
		(layer "In9.Cu")
		(net 735)
	)
	(segment
		(start 90.6 161.5)
		(end 99.299501 161.5)
		(width 0.1)
		(layer "In9.Cu")
		(net 735)
	)
	(segment
		(start 105.850501 163.126)
		(end 108.126 163.126)
		(width 0.1)
		(layer "In9.Cu")
		(net 735)
	)
	(segment
		(start 104.050501 163.326)
		(end 104.050501 163.396115)
		(width 0.1)
		(layer "In9.Cu")
		(net 735)
	)
	(segment
		(start 87.435501 158.335501)
		(end 90.6 161.5)
		(width 0.1)
		(layer "In9.Cu")
		(net 735)
	)
	(segment
		(start 121.238869 168.026)
		(end 121.640369 168.4275)
		(width 0.1)
		(layer "In9.Cu")
		(net 735)
	)
	(segment
		(start 130.252001 168.4275)
		(end 130.877001 167.8025)
		(width 0.1)
		(layer "In9.Cu")
		(net 735)
	)
	(segment
		(start 108.126 163.126)
		(end 113.026 168.026)
		(width 0.1)
		(layer "In9.Cu")
		(net 735)
	)
	(segment
		(start 100.050501 163.376)
		(end 100.600501 163.926)
		(width 0.1)
		(layer "In9.Cu")
		(net 735)
	)
	(segment
		(start 105.650501 162.855885)
		(end 105.650501 162.926)
		(width 0.1)
		(layer "In9.Cu")
		(net 735)
	)
	(segment
		(start 121.640369 168.4275)
		(end 130.252001 168.4275)
		(width 0.1)
		(layer "In9.Cu")
		(net 735)
	)
	(segment
		(start 105.250501 163.396115)
		(end 105.250501 162.855885)
		(width 0.1)
		(layer "In9.Cu")
		(net 735)
	)
	(segment
		(start 103.374 163.126)
		(end 103.850501 163.126)
		(width 0.1)
		(layer "In9.Cu")
		(net 735)
	)
	(arc
		(start 105.050501 163.596115)
		(mid 105.191922 163.537536)
		(end 105.250501 163.396115)
		(width 0.1)
		(layer "In9.Cu")
		(net 735)
	)
	(arc
		(start 104.850501 163.396115)
		(mid 104.90908 163.537536)
		(end 105.050501 163.596115)
		(width 0.1)
		(layer "In9.Cu")
		(net 735)
	)
	(arc
		(start 104.650501 162.655885)
		(mid 104.791922 162.714464)
		(end 104.850501 162.855885)
		(width 0.1)
		(layer "In9.Cu")
		(net 735)
	)
	(arc
		(start 104.050501 163.396115)
		(mid 104.10908 163.537536)
		(end 104.250501 163.596115)
		(width 0.1)
		(layer "In9.Cu")
		(net 735)
	)
	(arc
		(start 104.450501 162.855885)
		(mid 104.50908 162.714464)
		(end 104.650501 162.655885)
		(width 0.1)
		(layer "In9.Cu")
		(net 735)
	)
	(arc
		(start 105.650501 162.926)
		(mid 105.70908 163.067421)
		(end 105.850501 163.126)
		(width 0.1)
		(layer "In9.Cu")
		(net 735)
	)
	(arc
		(start 105.450501 162.655885)
		(mid 105.591922 162.714464)
		(end 105.650501 162.855885)
		(width 0.1)
		(layer "In9.Cu")
		(net 735)
	)
	(arc
		(start 104.250501 163.596115)
		(mid 104.391922 163.537536)
		(end 104.450501 163.396115)
		(width 0.1)
		(layer "In9.Cu")
		(net 735)
	)
	(arc
		(start 105.250501 162.855885)
		(mid 105.30908 162.714464)
		(end 105.450501 162.655885)
		(width 0.1)
		(layer "In9.Cu")
		(net 735)
	)
	(arc
		(start 103.850501 163.126)
		(mid 103.991922 163.184579)
		(end 104.050501 163.326)
		(width 0.1)
		(layer "In9.Cu")
		(net 735)
	)
	(segment
		(start 130.376501 168.302)
		(end 129.877 167.8025)
		(width 0.256)
		(layer "F.Cu")
		(net 736)
	)
	(segment
		(start 89.125687 156.035)
		(end 90.051501 156.035)
		(width 0.256)
		(layer "F.Cu")
		(net 736)
	)
	(via
		(at 89.125687 156.035)
		(size 0.45)
		(drill 0.1)
		(layers "F.Cu" "B.Cu")
		(net 736)
	)
	(via
		(at 129.877 167.8025)
		(size 0.45)
		(drill 0.1)
		(layers "F.Cu" "B.Cu")
		(net 736)
	)
	(segment
		(start 121.550501 165.426)
		(end 121.550501 165.459811)
		(width 0.1)
		(layer "In9.Cu")
		(net 736)
	)
	(segment
		(start 88.745501 156.415186)
		(end 89.125687 156.035)
		(width 0.1)
		(layer "In9.Cu")
		(net 736)
	)
	(segment
		(start 121.150501 165.459811)
		(end 121.150501 165.426)
		(width 0.1)
		(layer "In9.Cu")
		(net 736)
	)
	(segment
		(start 100.0705 160.6705)
		(end 99.6 160.2)
		(width 0.1)
		(layer "In9.Cu")
		(net 736)
	)
	(segment
		(start 99.6 160.2)
		(end 96.934358 160.2)
		(width 0.1)
		(layer "In9.Cu")
		(net 736)
	)
	(segment
		(start 118.750501 165.459811)
		(end 118.750501 165.226)
		(width 0.1)
		(layer "In9.Cu")
		(net 736)
	)
	(segment
		(start 111.25 160)
		(end 102.5 160)
		(width 0.1)
		(layer "In9.Cu")
		(net 736)
	)
	(segment
		(start 116.572719 165.226)
		(end 116.476 165.226)
		(width 0.1)
		(layer "In9.Cu")
		(net 736)
	)
	(segment
		(start 119.950501 165.226)
		(end 119.950501 165.459811)
		(width 0.1)
		(layer "In9.Cu")
		(net 736)
	)
	(segment
		(start 117.950501 165.459811)
		(end 117.950501 165.226)
		(width 0.1)
		(layer "In9.Cu")
		(net 736)
	)
	(segment
		(start 94.815358 158.081)
		(end 89.115501 158.081)
		(width 0.1)
		(layer "In9.Cu")
		(net 736)
	)
	(segment
		(start 120.350501 165.459811)
		(end 120.350501 165.226)
		(width 0.1)
		(layer "In9.Cu")
		(net 736)
	)
	(segment
		(start 118.350501 165.226)
		(end 118.350501 165.459811)
		(width 0.1)
		(layer "In9.Cu")
		(net 736)
	)
	(segment
		(start 129.252 167.1775)
		(end 125.599585 167.1775)
		(width 0.1)
		(layer "In9.Cu")
		(net 736)
	)
	(segment
		(start 89.115501 158.081)
		(end 88.745501 157.711)
		(width 0.1)
		(layer "In9.Cu")
		(net 736)
	)
	(segment
		(start 88.745501 157.711)
		(end 88.745501 156.415186)
		(width 0.1)
		(layer "In9.Cu")
		(net 736)
	)
	(segment
		(start 117.350501 165.226)
		(end 116.572719 165.226)
		(width 0.1)
		(layer "In9.Cu")
		(net 736)
	)
	(segment
		(start 121.150501 165.426)
		(end 121.150501 164.992189)
		(width 0.1)
		(layer "In9.Cu")
		(net 736)
	)
	(segment
		(start 120.750501 164.992189)
		(end 120.750501 165.226)
		(width 0.1)
		(layer "In9.Cu")
		(net 736)
	)
	(segment
		(start 116.476 165.226)
		(end 111.25 160)
		(width 0.1)
		(layer "In9.Cu")
		(net 736)
	)
	(segment
		(start 122.176 165.226)
		(end 121.750501 165.226)
		(width 0.1)
		(layer "In9.Cu")
		(net 736)
	)
	(segment
		(start 117.950501 165.226)
		(end 117.950501 164.992189)
		(width 0.1)
		(layer "In9.Cu")
		(net 736)
	)
	(segment
		(start 125.599585 167.1775)
		(end 125.322085 166.9)
		(width 0.1)
		(layer "In9.Cu")
		(net 736)
	)
	(segment
		(start 118.350501 164.992189)
		(end 118.350501 165.226)
		(width 0.1)
		(layer "In9.Cu")
		(net 736)
	)
	(segment
		(start 119.150501 165.226)
		(end 119.150501 165.459811)
		(width 0.1)
		(layer "In9.Cu")
		(net 736)
	)
	(segment
		(start 102.5 160)
		(end 101.8295 160.6705)
		(width 0.1)
		(layer "In9.Cu")
		(net 736)
	)
	(segment
		(start 119.950501 164.992189)
		(end 119.950501 165.226)
		(width 0.1)
		(layer "In9.Cu")
		(net 736)
	)
	(segment
		(start 96.934358 160.2)
		(end 94.815358 158.081)
		(width 0.1)
		(layer "In9.Cu")
		(net 736)
	)
	(segment
		(start 125.322085 166.9)
		(end 123.85 166.9)
		(width 0.1)
		(layer "In9.Cu")
		(net 736)
	)
	(segment
		(start 119.550501 165.459811)
		(end 119.550501 165.226)
		(width 0.1)
		(layer "In9.Cu")
		(net 736)
	)
	(segment
		(start 117.550501 164.992189)
		(end 117.550501 165.026)
		(width 0.1)
		(layer "In9.Cu")
		(net 736)
	)
	(segment
		(start 119.550501 165.226)
		(end 119.550501 164.992189)
		(width 0.1)
		(layer "In9.Cu")
		(net 736)
	)
	(segment
		(start 120.350501 165.226)
		(end 120.350501 164.992189)
		(width 0.1)
		(layer "In9.Cu")
		(net 736)
	)
	(segment
		(start 101.8295 160.6705)
		(end 100.0705 160.6705)
		(width 0.1)
		(layer "In9.Cu")
		(net 736)
	)
	(segment
		(start 119.150501 164.992189)
		(end 119.150501 165.226)
		(width 0.1)
		(layer "In9.Cu")
		(net 736)
	)
	(segment
		(start 120.750501 165.226)
		(end 120.750501 165.459811)
		(width 0.1)
		(layer "In9.Cu")
		(net 736)
	)
	(segment
		(start 129.877 167.8025)
		(end 129.252 167.1775)
		(width 0.1)
		(layer "In9.Cu")
		(net 736)
	)
	(segment
		(start 118.750501 165.226)
		(end 118.750501 164.992189)
		(width 0.1)
		(layer "In9.Cu")
		(net 736)
	)
	(segment
		(start 123.85 166.9)
		(end 122.176 165.226)
		(width 0.1)
		(layer "In9.Cu")
		(net 736)
	)
	(arc
		(start 120.150501 164.792189)
		(mid 120.00908 164.850768)
		(end 119.950501 164.992189)
		(width 0.1)
		(layer "In9.Cu")
		(net 736)
	)
	(arc
		(start 119.350501 164.792189)
		(mid 119.20908 164.850768)
		(end 119.150501 164.992189)
		(width 0.1)
		(layer "In9.Cu")
		(net 736)
	)
	(arc
		(start 119.550501 164.992189)
		(mid 119.491922 164.850768)
		(end 119.350501 164.792189)
		(width 0.1)
		(layer "In9.Cu")
		(net 736)
	)
	(arc
		(start 120.550501 165.659811)
		(mid 120.40908 165.601232)
		(end 120.350501 165.459811)
		(width 0.1)
		(layer "In9.Cu")
		(net 736)
	)
	(arc
		(start 120.350501 164.992189)
		(mid 120.291922 164.850768)
		(end 120.150501 164.792189)
		(width 0.1)
		(layer "In9.Cu")
		(net 736)
	)
	(arc
		(start 121.150501 164.992189)
		(mid 121.091922 164.850768)
		(end 120.950501 164.792189)
		(width 0.1)
		(layer "In9.Cu")
		(net 736)
	)
	(arc
		(start 119.750501 165.659811)
		(mid 119.60908 165.601232)
		(end 119.550501 165.459811)
		(width 0.1)
		(layer "In9.Cu")
		(net 736)
	)
	(arc
		(start 118.150501 165.659811)
		(mid 118.00908 165.601232)
		(end 117.950501 165.459811)
		(width 0.1)
		(layer "In9.Cu")
		(net 736)
	)
	(arc
		(start 118.550501 164.792189)
		(mid 118.40908 164.850768)
		(end 118.350501 164.992189)
		(width 0.1)
		(layer "In9.Cu")
		(net 736)
	)
	(arc
		(start 118.950501 165.659811)
		(mid 118.80908 165.601232)
		(end 118.750501 165.459811)
		(width 0.1)
		(layer "In9.Cu")
		(net 736)
	)
	(arc
		(start 117.550501 165.026)
		(mid 117.491922 165.167421)
		(end 117.350501 165.226)
		(width 0.1)
		(layer "In9.Cu")
		(net 736)
	)
	(arc
		(start 120.950501 164.792189)
		(mid 120.80908 164.850768)
		(end 120.750501 164.992189)
		(width 0.1)
		(layer "In9.Cu")
		(net 736)
	)
	(arc
		(start 121.550501 165.459811)
		(mid 121.491922 165.601232)
		(end 121.350501 165.659811)
		(width 0.1)
		(layer "In9.Cu")
		(net 736)
	)
	(arc
		(start 117.750501 164.792189)
		(mid 117.60908 164.850768)
		(end 117.550501 164.992189)
		(width 0.1)
		(layer "In9.Cu")
		(net 736)
	)
	(arc
		(start 118.750501 164.992189)
		(mid 118.691922 164.850768)
		(end 118.550501 164.792189)
		(width 0.1)
		(layer "In9.Cu")
		(net 736)
	)
	(arc
		(start 121.350501 165.659811)
		(mid 121.20908 165.601232)
		(end 121.150501 165.459811)
		(width 0.1)
		(layer "In9.Cu")
		(net 736)
	)
	(arc
		(start 118.350501 165.459811)
		(mid 118.291922 165.601232)
		(end 118.150501 165.659811)
		(width 0.1)
		(layer "In9.Cu")
		(net 736)
	)
	(arc
		(start 121.750501 165.226)
		(mid 121.60908 165.284579)
		(end 121.550501 165.426)
		(width 0.1)
		(layer "In9.Cu")
		(net 736)
	)
	(arc
		(start 119.150501 165.459811)
		(mid 119.091922 165.601232)
		(end 118.950501 165.659811)
		(width 0.1)
		(layer "In9.Cu")
		(net 736)
	)
	(arc
		(start 119.950501 165.459811)
		(mid 119.891922 165.601232)
		(end 119.750501 165.659811)
		(width 0.1)
		(layer "In9.Cu")
		(net 736)
	)
	(arc
		(start 120.750501 165.459811)
		(mid 120.691922 165.601232)
		(end 120.550501 165.659811)
		(width 0.1)
		(layer "In9.Cu")
		(net 736)
	)
	(arc
		(start 117.950501 164.992189)
		(mid 117.891922 164.850768)
		(end 117.750501 164.792189)
		(width 0.1)
		(layer "In9.Cu")
		(net 736)
	)
	(segment
		(start 88.61468 155.546008)
		(end 88.591829 155.568859)
		(width 0.15)
		(layer "F.Cu")
		(net 737)
	)
	(segment
		(start 90.051501 155.534)
		(end 88.626688 155.534)
		(width 0.256)
		(layer "F.Cu")
		(net 737)
	)
	(segment
		(start 88.626688 155.534)
		(end 88.591829 155.568859)
		(width 0.256)
		(layer "F.Cu")
		(net 737)
	)
	(segment
		(start 126.376501 168.302)
		(end 125.877001 167.8025)
		(width 0.256)
		(layer "F.Cu")
		(net 737)
	)
	(via
		(at 88.591829 155.568859)
		(size 0.45)
		(drill 0.1)
		(layers "F.Cu" "B.Cu")
		(net 737)
	)
	(via
		(at 125.877001 167.8025)
		(size 0.45)
		(drill 0.1)
		(layers "F.Cu" "B.Cu")
		(net 737)
	)
	(segment
		(start 105.424501 161.835245)
		(end 105.424501 161.364755)
		(width 0.1)
		(layer "In9.Cu")
		(net 737)
	)
	(segment
		(start 104.224501 161.8)
		(end 104.224501 161.835245)
		(width 0.1)
		(layer "In9.Cu")
		(net 737)
	)
	(segment
		(start 121.684579 166.626)
		(end 122.858579 167.8)
		(width 0.1)
		(layer "In9.Cu")
		(net 737)
	)
	(segment
		(start 106.224501 161.835245)
		(end 106.224501 161.8)
		(width 0.1)
		(layer "In9.Cu")
		(net 737)
	)
	(segment
		(start 109.6 161.6)
		(end 114.626 166.626)
		(width 0.1)
		(layer "In9.Cu")
		(net 737)
	)
	(segment
		(start 122.858579 167.8)
		(end 125.874501 167.8)
		(width 0.1)
		(layer "In9.Cu")
		(net 737)
	)
	(segment
		(start 105.024501 161.364755)
		(end 105.024501 161.835245)
		(width 0.1)
		(layer "In9.Cu")
		(net 737)
	)
	(segment
		(start 125.874501 167.8)
		(end 125.877001 167.8025)
		(width 0.1)
		(layer "In9.Cu")
		(net 737)
	)
	(segment
		(start 90.915501 160.821)
		(end 99.421 160.821)
		(width 0.1)
		(layer "In9.Cu")
		(net 737)
	)
	(segment
		(start 99.421 160.821)
		(end 101.100501 162.500501)
		(width 0.1)
		(layer "In9.Cu")
		(net 737)
	)
	(segment
		(start 103.4 161.6)
		(end 104.024501 161.6)
		(width 0.1)
		(layer "In9.Cu")
		(net 737)
	)
	(segment
		(start 114.626 166.626)
		(end 121.684579 166.626)
		(width 0.1)
		(layer "In9.Cu")
		(net 737)
	)
	(segment
		(start 88.005501 157.911)
		(end 90.915501 160.821)
		(width 0.1)
		(layer "In9.Cu")
		(net 737)
	)
	(segment
		(start 88.591829 155.568859)
		(end 88.005501 156.155187)
		(width 0.1)
		(layer "In9.Cu")
		(net 737)
	)
	(segment
		(start 104.624501 161.835245)
		(end 104.624501 161.364755)
		(width 0.1)
		(layer "In9.Cu")
		(net 737)
	)
	(segment
		(start 101.300501 163.226)
		(end 101.774 163.226)
		(width 0.1)
		(layer "In9.Cu")
		(net 737)
	)
	(segment
		(start 101.774 163.226)
		(end 103.4 161.6)
		(width 0.1)
		(layer "In9.Cu")
		(net 737)
	)
	(segment
		(start 105.824501 161.364755)
		(end 105.824501 161.835245)
		(width 0.1)
		(layer "In9.Cu")
		(net 737)
	)
	(segment
		(start 106.424501 161.6)
		(end 109.6 161.6)
		(width 0.1)
		(layer "In9.Cu")
		(net 737)
	)
	(segment
		(start 101.100501 162.500501)
		(end 101.100501 163.026)
		(width 0.1)
		(layer "In9.Cu")
		(net 737)
	)
	(segment
		(start 88.005501 156.155187)
		(end 88.005501 157.911)
		(width 0.1)
		(layer "In9.Cu")
		(net 737)
	)
	(segment
		(start 101.100501 163.026)
		(end 101.300501 163.226)
		(width 0.1)
		(layer "In9.Cu")
		(net 737)
	)
	(arc
		(start 105.024501 161.835245)
		(mid 105.08308 161.976666)
		(end 105.224501 162.035245)
		(width 0.1)
		(layer "In9.Cu")
		(net 737)
	)
	(arc
		(start 104.024501 161.6)
		(mid 104.165922 161.658579)
		(end 104.224501 161.8)
		(width 0.1)
		(layer "In9.Cu")
		(net 737)
	)
	(arc
		(start 104.424501 162.035245)
		(mid 104.565922 161.976666)
		(end 104.624501 161.835245)
		(width 0.1)
		(layer "In9.Cu")
		(net 737)
	)
	(arc
		(start 104.624501 161.364755)
		(mid 104.68308 161.223334)
		(end 104.824501 161.164755)
		(width 0.1)
		(layer "In9.Cu")
		(net 737)
	)
	(arc
		(start 105.424501 161.364755)
		(mid 105.48308 161.223334)
		(end 105.624501 161.164755)
		(width 0.1)
		(layer "In9.Cu")
		(net 737)
	)
	(arc
		(start 106.024501 162.035245)
		(mid 106.165922 161.976666)
		(end 106.224501 161.835245)
		(width 0.1)
		(layer "In9.Cu")
		(net 737)
	)
	(arc
		(start 106.224501 161.8)
		(mid 106.28308 161.658579)
		(end 106.424501 161.6)
		(width 0.1)
		(layer "In9.Cu")
		(net 737)
	)
	(arc
		(start 105.224501 162.035245)
		(mid 105.365922 161.976666)
		(end 105.424501 161.835245)
		(width 0.1)
		(layer "In9.Cu")
		(net 737)
	)
	(arc
		(start 105.824501 161.835245)
		(mid 105.88308 161.976666)
		(end 106.024501 162.035245)
		(width 0.1)
		(layer "In9.Cu")
		(net 737)
	)
	(arc
		(start 104.224501 161.835245)
		(mid 104.28308 161.976666)
		(end 104.424501 162.035245)
		(width 0.1)
		(layer "In9.Cu")
		(net 737)
	)
	(arc
		(start 104.824501 161.164755)
		(mid 104.965922 161.223334)
		(end 105.024501 161.364755)
		(width 0.1)
		(layer "In9.Cu")
		(net 737)
	)
	(arc
		(start 105.624501 161.164755)
		(mid 105.765922 161.223334)
		(end 105.824501 161.364755)
		(width 0.1)
		(layer "In9.Cu")
		(net 737)
	)
	(segment
		(start 94.621501 171.136)
		(end 94.336 171.136)
		(width 0.15)
		(layer "F.Cu")
		(net 738)
	)
	(segment
		(start 93.95 170.75)
		(end 93.95 170.45)
		(width 0.15)
		(layer "F.Cu")
		(net 738)
	)
	(segment
		(start 96.447 191.25)
		(end 96.8245 191.25)
		(width 0.201)
		(layer "F.Cu")
		(net 738)
	)
	(segment
		(start 94.336 171.136)
		(end 93.95 170.75)
		(width 0.15)
		(layer "F.Cu")
		(net 738)
	)
	(segment
		(start 96.8245 191.25)
		(end 97 191.0745)
		(width 0.201)
		(layer "F.Cu")
		(net 738)
	)
	(via
		(at 97 191.0745)
		(size 0.45)
		(drill 0.1)
		(layers "F.Cu" "B.Cu")
		(net 738)
	)
	(via
		(at 93.95 170.45)
		(size 0.45)
		(drill 0.1)
		(layers "F.Cu" "B.Cu")
		(net 738)
	)
	(segment
		(start 98.2 193.5)
		(end 98.5 193.2)
		(width 0.15)
		(layer "In2.Cu")
		(net 738)
	)
	(segment
		(start 97.865686 191.5)
		(end 97.4255 191.5)
		(width 0.15)
		(layer "In2.Cu")
		(net 738)
	)
	(segment
		(start 94 190.6)
		(end 96.9 193.5)
		(width 0.15)
		(layer "In2.Cu")
		(net 738)
	)
	(segment
		(start 97.4255 191.5)
		(end 97 191.0745)
		(width 0.15)
		(layer "In2.Cu")
		(net 738)
	)
	(segment
		(start 92.7 183.5)
		(end 94 184.8)
		(width 0.15)
		(layer "In2.Cu")
		(net 738)
	)
	(segment
		(start 93.95 171.45)
		(end 92.7 172.7)
		(width 0.15)
		(layer "In2.Cu")
		(net 738)
	)
	(segment
		(start 98.5 193.2)
		(end 98.5 192.134314)
		(width 0.15)
		(layer "In2.Cu")
		(net 738)
	)
	(segment
		(start 98.5 192.134314)
		(end 97.865686 191.5)
		(width 0.15)
		(layer "In2.Cu")
		(net 738)
	)
	(segment
		(start 96.9 193.5)
		(end 98.2 193.5)
		(width 0.15)
		(layer "In2.Cu")
		(net 738)
	)
	(segment
		(start 93.95 170.45)
		(end 93.95 171.45)
		(width 0.15)
		(layer "In2.Cu")
		(net 738)
	)
	(segment
		(start 94 184.8)
		(end 94 190.6)
		(width 0.15)
		(layer "In2.Cu")
		(net 738)
	)
	(segment
		(start 92.7 172.7)
		(end 92.7 183.5)
		(width 0.15)
		(layer "In2.Cu")
		(net 738)
	)
	(segment
		(start 93.715 176.635)
		(end 93.7 176.65)
		(width 0.15)
		(layer "F.Cu")
		(net 739)
	)
	(segment
		(start 94.621501 176.635)
		(end 93.715 176.635)
		(width 0.15)
		(layer "F.Cu")
		(net 739)
	)
	(segment
		(start 94.4 180.45)
		(end 94.4 179.15)
		(width 0.15)
		(layer "F.Cu")
		(net 739)
	)
	(via
		(at 94.4 179.15)
		(size 0.45)
		(drill 0.1)
		(layers "F.Cu" "B.Cu")
		(net 739)
	)
	(via
		(at 93.7 176.65)
		(size 0.45)
		(drill 0.1)
		(layers "F.Cu" "B.Cu")
		(net 739)
	)
	(segment
		(start 93.7 176.65)
		(end 94.4 177.35)
		(width 0.15)
		(layer "B.Cu")
		(net 739)
	)
	(segment
		(start 94.4 177.35)
		(end 94.4 179.15)
		(width 0.15)
		(layer "B.Cu")
		(net 739)
	)
	(segment
		(start 93.665 177.135)
		(end 93.35 177.45)
		(width 0.15)
		(layer "F.Cu")
		(net 740)
	)
	(segment
		(start 94.621501 177.135)
		(end 93.665 177.135)
		(width 0.15)
		(layer "F.Cu")
		(net 740)
	)
	(segment
		(start 93.9 179.55)
		(end 93.9 180.45)
		(width 0.15)
		(layer "F.Cu")
		(net 740)
	)
	(via
		(at 93.9 179.55)
		(size 0.45)
		(drill 0.1)
		(layers "F.Cu" "B.Cu")
		(net 740)
	)
	(via
		(at 93.35 177.45)
		(size 0.45)
		(drill 0.1)
		(layers "F.Cu" "B.Cu")
		(net 740)
	)
	(segment
		(start 93.9 178)
		(end 93.9 179.55)
		(width 0.15)
		(layer "B.Cu")
		(net 740)
	)
	(segment
		(start 93.35 177.45)
		(end 93.9 178)
		(width 0.15)
		(layer "B.Cu")
		(net 740)
	)
	(segment
		(start 94.621501 177.635)
		(end 94.015 177.635)
		(width 0.15)
		(layer "F.Cu")
		(net 741)
	)
	(segment
		(start 93.406 178.244)
		(end 93.406 180.45)
		(width 0.15)
		(layer "F.Cu")
		(net 741)
	)
	(segment
		(start 94.015 177.635)
		(end 93.406 178.244)
		(width 0.15)
		(layer "F.Cu")
		(net 741)
	)
	(segment
		(start 95.309501 179.190499)
		(end 94.9 179.6)
		(width 0.15)
		(layer "F.Cu")
		(net 742)
	)
	(segment
		(start 94.9 179.6)
		(end 94.9 180.45)
		(width 0.15)
		(layer "F.Cu")
		(net 742)
	)
	(segment
		(start 95.309501 178.323)
		(end 95.309501 179.190499)
		(width 0.15)
		(layer "F.Cu")
		(net 742)
	)
	(segment
		(start 95.809501 169.409501)
		(end 95.45 169.05)
		(width 0.15)
		(layer "F.Cu")
		(net 744)
	)
	(segment
		(start 95.499 190.699)
		(end 95.499 189.701)
		(width 0.201)
		(layer "F.Cu")
		(net 744)
	)
	(segment
		(start 95.809501 170.448)
		(end 95.809501 169.409501)
		(width 0.15)
		(layer "F.Cu")
		(net 744)
	)
	(segment
		(start 95.499 189.701)
		(end 95.5 189.7)
		(width 0.201)
		(layer "F.Cu")
		(net 744)
	)
	(via
		(at 95.5 189.7)
		(size 0.45)
		(drill 0.1)
		(layers "F.Cu" "B.Cu")
		(net 744)
	)
	(via
		(at 95.45 169.05)
		(size 0.45)
		(drill 0.1)
		(layers "F.Cu" "B.Cu")
		(net 744)
	)
	(segment
		(start 96.1 188.1)
		(end 95.5 188.7)
		(width 0.15)
		(layer "In2.Cu")
		(net 744)
	)
	(segment
		(start 95.7 184.5)
		(end 96.1 184.9)
		(width 0.15)
		(layer "In2.Cu")
		(net 744)
	)
	(segment
		(start 95.5 188.7)
		(end 95.5 189.7)
		(width 0.15)
		(layer "In2.Cu")
		(net 744)
	)
	(segment
		(start 95.7 170)
		(end 95.7 184.5)
		(width 0.15)
		(layer "In2.Cu")
		(net 744)
	)
	(segment
		(start 95.45 169.75)
		(end 95.7 170)
		(width 0.15)
		(layer "In2.Cu")
		(net 744)
	)
	(segment
		(start 95.45 169.05)
		(end 95.45 169.75)
		(width 0.15)
		(layer "In2.Cu")
		(net 744)
	)
	(segment
		(start 96.1 184.9)
		(end 96.1 188.1)
		(width 0.15)
		(layer "In2.Cu")
		(net 744)
	)
	(segment
		(start 96.447 191.647)
		(end 97.247 191.647)
		(width 0.201)
		(layer "F.Cu")
		(net 745)
	)
	(segment
		(start 97.247 191.647)
		(end 98 192.4)
		(width 0.201)
		(layer "F.Cu")
		(net 745)
	)
	(segment
		(start 95.1 169.6)
		(end 94.75 169.6)
		(width 0.15)
		(layer "F.Cu")
		(net 745)
	)
	(segment
		(start 95.309501 170.448)
		(end 95.309501 169.809501)
		(width 0.15)
		(layer "F.Cu")
		(net 745)
	)
	(segment
		(start 95.309501 169.809501)
		(end 95.1 169.6)
		(width 0.15)
		(layer "F.Cu")
		(net 745)
	)
	(via
		(at 94.75 169.6)
		(size 0.45)
		(drill 0.1)
		(layers "F.Cu" "B.Cu")
		(net 745)
	)
	(via
		(at 98 192.4)
		(size 0.45)
		(drill 0.1)
		(layers "F.Cu" "B.Cu")
		(net 745)
	)
	(segment
		(start 95 170.4)
		(end 95 189.972088)
		(width 0.15)
		(layer "In2.Cu")
		(net 745)
	)
	(segment
		(start 97.031113 192.003201)
		(end 97.603201 192.003201)
		(width 0.15)
		(layer "In2.Cu")
		(net 745)
	)
	(segment
		(start 97.603201 192.003201)
		(end 98 192.4)
		(width 0.15)
		(layer "In2.Cu")
		(net 745)
	)
	(segment
		(start 95 189.972088)
		(end 97.031113 192.003201)
		(width 0.15)
		(layer "In2.Cu")
		(net 745)
	)
	(segment
		(start 94.75 169.6)
		(end 94.75 170.15)
		(width 0.15)
		(layer "In2.Cu")
		(net 745)
	)
	(segment
		(start 94.75 170.15)
		(end 95 170.4)
		(width 0.15)
		(layer "In2.Cu")
		(net 745)
	)
	(segment
		(start 105.24 175.36)
		(end 105.95 175.36)
		(width 0.15)
		(layer "F.Cu")
		(net 746)
	)
	(segment
		(start 105.95 175.36)
		(end 106.29 175.02)
		(width 0.15)
		(layer "F.Cu")
		(net 746)
	)
	(segment
		(start 105.955 175.71)
		(end 106.29 176.045)
		(width 0.15)
		(layer "F.Cu")
		(net 747)
	)
	(segment
		(start 105.24 175.71)
		(end 105.955 175.71)
		(width 0.15)
		(layer "F.Cu")
		(net 747)
	)
	(segment
		(start 105.24 171.66)
		(end 105.895 171.66)
		(width 0.15)
		(layer "F.Cu")
		(net 748)
	)
	(segment
		(start 105.895 171.66)
		(end 106.295 171.26)
		(width 0.15)
		(layer "F.Cu")
		(net 748)
	)
	(segment
		(start 106.045 172.01)
		(end 106.295 172.26)
		(width 0.15)
		(layer "F.Cu")
		(net 749)
	)
	(segment
		(start 105.24 172.01)
		(end 106.045 172.01)
		(width 0.15)
		(layer "F.Cu")
		(net 749)
	)
	(segment
		(start 144.375501 164.302001)
		(end 144.875001 163.8025)
		(width 0.256)
		(layer "F.Cu")
		(net 750)
	)
	(via
		(at 144.875001 163.8025)
		(size 0.45)
		(drill 0.1)
		(layers "F.Cu" "B.Cu")
		(net 750)
	)
	(segment
		(start 142.375501 163.302)
		(end 142.875001 162.8025)
		(width 0.256)
		(layer "F.Cu")
		(net 751)
	)
	(via
		(at 142.875001 162.8025)
		(size 0.45)
		(drill 0.1)
		(layers "F.Cu" "B.Cu")
		(net 751)
	)
	(segment
		(start 74.781501 140.785)
		(end 74.083501 141.483)
		(width 0.256)
		(layer "B.Cu")
		(net 757)
	)
	(segment
		(start 74.083501 141.483)
		(end 74.083501 141.612487)
		(width 0.256)
		(layer "B.Cu")
		(net 757)
	)
	(segment
		(start 75.75 140.785)
		(end 74.781501 140.785)
		(width 0.256)
		(layer "B.Cu")
		(net 757)
	)
	(segment
		(start 75.770501 133.401)
		(end 75.770501 132.609488)
		(width 0.256)
		(layer "B.Cu")
		(net 758)
	)
	(segment
		(start 75.770501 132.609488)
		(end 74.0325 130.871487)
		(width 0.256)
		(layer "B.Cu")
		(net 758)
	)
	(segment
		(start 178.951 189.35)
		(end 179.05 189.251)
		(width 0.25)
		(layer "F.Cu")
		(net 759)
	)
	(segment
		(start 178.15 189.35)
		(end 178.15 190.65)
		(width 0.25)
		(layer "F.Cu")
		(net 759)
	)
	(segment
		(start 180.3 189.251)
		(end 179.05 189.251)
		(width 0.25)
		(layer "F.Cu")
		(net 759)
	)
	(segment
		(start 178.15 189.35)
		(end 178.951 189.35)
		(width 0.25)
		(layer "F.Cu")
		(net 759)
	)
	(segment
		(start 176.75 190.525)
		(end 176.125 189.9)
		(width 0.256)
		(layer "F.Cu")
		(net 760)
	)
	(segment
		(start 176.75 190.65)
		(end 176.75 190.525)
		(width 0.256)
		(layer "F.Cu")
		(net 760)
	)
	(segment
		(start 176.125 189.9)
		(end 176.125 189.807064)
		(width 0.256)
		(layer "F.Cu")
		(net 760)
	)
	(via
		(at 176.125 189.807064)
		(size 0.45)
		(drill 0.1)
		(layers "F.Cu" "B.Cu")
		(net 760)
	)
	(segment
		(start 176.125 189.807064)
		(end 176.125 188.225)
		(width 0.15)
		(layer "B.Cu")
		(net 760)
	)
	(segment
		(start 176.125 188.225)
		(end 172.3 184.4)
		(width 0.15)
		(layer "B.Cu")
		(net 760)
	)
	(segment
		(start 183.001 189.251)
		(end 184.751 189.251)
		(width 0.198)
		(layer "F.Cu")
		(net 761)
	)
	(segment
		(start 184.751 189.251)
		(end 184.95 189.45)
		(width 0.198)
		(layer "F.Cu")
		(net 761)
	)
	(via
		(at 184.95 189.45)
		(size 0.45)
		(drill 0.1)
		(layers "F.Cu" "B.Cu")
		(net 761)
	)
	(segment
		(start 174.9 189.5)
		(end 173.9 189.5)
		(width 0.15)
		(layer "B.Cu")
		(net 761)
	)
	(segment
		(start 182.25 188.6)
		(end 178.3 188.6)
		(width 0.15)
		(layer "B.Cu")
		(net 761)
	)
	(segment
		(start 178.3 188.6)
		(end 176.5 190.4)
		(width 0.15)
		(layer "B.Cu")
		(net 761)
	)
	(segment
		(start 182.25 188.6)
		(end 183.6 189.95)
		(width 0.15)
		(layer "B.Cu")
		(net 761)
	)
	(segment
		(start 184.25 189.95)
		(end 184.4 189.95)
		(width 0.198)
		(layer "B.Cu")
		(net 761)
	)
	(segment
		(start 176.5 190.4)
		(end 175.8 190.4)
		(width 0.15)
		(layer "B.Cu")
		(net 761)
	)
	(segment
		(start 183.6 189.95)
		(end 184.25 189.95)
		(width 0.15)
		(layer "B.Cu")
		(net 761)
	)
	(segment
		(start 184.9 189.45)
		(end 184.95 189.45)
		(width 0.198)
		(layer "B.Cu")
		(net 761)
	)
	(segment
		(start 175.8 190.4)
		(end 174.9 189.5)
		(width 0.15)
		(layer "B.Cu")
		(net 761)
	)
	(segment
		(start 184.4 189.95)
		(end 184.9 189.45)
		(width 0.198)
		(layer "B.Cu")
		(net 761)
	)
	(segment
		(start 184.999 191.151)
		(end 185 191.15)
		(width 0.198)
		(layer "F.Cu")
		(net 762)
	)
	(segment
		(start 183.001 191.151)
		(end 184.999 191.151)
		(width 0.198)
		(layer "F.Cu")
		(net 762)
	)
	(via
		(at 185 191.15)
		(size 0.45)
		(drill 0.1)
		(layers "F.Cu" "B.Cu")
		(net 762)
	)
	(segment
		(start 184.4 191.15)
		(end 184.25 191)
		(width 0.198)
		(layer "B.Cu")
		(net 762)
	)
	(segment
		(start 185 191.15)
		(end 184.4 191.15)
		(width 0.198)
		(layer "B.Cu")
		(net 762)
	)
	(segment
		(start 182.25 189.5)
		(end 179.4 189.5)
		(width 0.15)
		(layer "B.Cu")
		(net 762)
	)
	(segment
		(start 183.75 191)
		(end 184.25 191)
		(width 0.15)
		(layer "B.Cu")
		(net 762)
	)
	(segment
		(start 182.25 189.5)
		(end 183.75 191)
		(width 0.15)
		(layer "B.Cu")
		(net 762)
	)
	(zone
		(net 227)
		(net_name "+1V0")
		(layer "F.Cu")
		(hatch edge 0.508)
		(priority 1)
		(connect_pads yes
			(clearance 0.12)
		)
		(min_thickness 0.254)
		(filled_areas_thickness no)
		(fill yes
			(thermal_gap 0.508)
			(thermal_bridge_width 0.508)
		)
		(polygon
			(pts
				(xy 168.216501 200.843) (xy 164.200501 200.843) (xy 164.200501 187.476) (xy 166.85 187.472491) (xy 166.85 189.05)
				(xy 165.916501 190) (xy 165.916501 198.076) (xy 168.216501 198.076)
			)
		)
	)
	(zone
		(net 1)
		(net_name "GND")
		(layer "F.Cu")
		(hatch edge 0.508)
		(connect_pads yes
			(clearance 0.12)
		)
		(min_thickness 0.254)
		(filled_areas_thickness no)
		(fill yes
			(thermal_gap 0.508)
			(thermal_bridge_width 0.508)
		)
		(polygon
			(pts
				(xy 169.034501 192.1) (xy 169.034501 200.876) (xy 172.700501 200.876) (xy 172.700501 193.859) (xy 170.484501 193.859)
				(xy 170.484501 191.659) (xy 169.45 191.659)
			)
		)
	)
	(zone
		(net 227)
		(net_name "+1V0")
		(layer "F.Cu")
		(hatch edge 0.508)
		(connect_pads yes
			(clearance 0.15)
		)
		(min_thickness 0.254)
		(filled_areas_thickness no)
		(fill yes
			(thermal_gap 0.508)
			(thermal_bridge_width 0.508)
		)
		(polygon
			(pts
				(xy 132.200501 191.576) (xy 128.6 191.576) (xy 126.9 193.376) (xy 122.400501 193.376) (xy 122.400501 189.676)
				(xy 132.200501 189.676)
			)
		)
	)
	(zone
		(net 1)
		(net_name "GND")
		(layer "F.Cu")
		(hatch edge 0.508)
		(priority 1)
		(connect_pads yes
			(clearance 0.12)
		)
		(min_thickness 0.254)
		(filled_areas_thickness no)
		(fill yes
			(thermal_gap 0.508)
			(thermal_bridge_width 0.508)
		)
		(polygon
			(pts
				(xy 167.1 185.9) (xy 164.2 185.9) (xy 162.4 184.1) (xy 162.4 183.7) (xy 167.1 183.7)
			)
		)
	)
	(zone
		(net 596)
		(net_name "/Supply/12V_PCIE_fused")
		(layer "F.Cu")
		(hatch edge 0.508)
		(priority 3)
		(connect_pads
			(clearance 0.2)
		)
		(min_thickness 0.2)
		(filled_areas_thickness no)
		(fill yes
			(thermal_gap 0.3)
			(thermal_bridge_width 0.3)
		)
		(polygon
			(pts
				(xy 117.2 201.7) (xy 117.6645 202.1645) (xy 120 202.1645) (xy 120.4 202.6) (xy 121.5355 202.6) (xy 121.5355 205.3)
				(xy 120.5 205.3) (xy 119.9 204.6645) (xy 117.3 204.6645) (xy 117 204.3645) (xy 113.9 204.3645) (xy 113.9 200.5)
				(xy 117.2 200.5)
			)
		)
	)
	(zone
		(net 38)
		(net_name "VDC")
		(layer "F.Cu")
		(hatch edge 0.508)
		(priority 3)
		(connect_pads yes
			(clearance 0.12)
		)
		(min_thickness 0.254)
		(filled_areas_thickness no)
		(fill yes
			(thermal_gap 0.508)
			(thermal_bridge_width 0.508)
		)
		(polygon
			(pts
				(xy 206.400501 166.876) (xy 200.300501 166.876) (xy 200.300501 165.576) (xy 202.400501 165.576)
				(xy 202.400501 164.976) (xy 203.500501 164.976) (xy 203.500501 158.701) (xy 206.400501 158.701)
			)
		)
	)
	(zone
		(net 42)
		(net_name "/Supply/MGTAVCC_local")
		(layer "F.Cu")
		(hatch edge 0.508)
		(priority 4)
		(connect_pads yes
			(clearance 0.12)
		)
		(min_thickness 0.254)
		(filled_areas_thickness no)
		(fill yes
			(thermal_gap 0.508)
			(thermal_bridge_width 0.508)
		)
		(polygon
			(pts
				(xy 193.595501 185.423) (xy 193.895501 185.623) (xy 195.595501 185.623) (xy 195.595501 186.923)
				(xy 193.995501 186.923) (xy 192.295501 190.123) (xy 191.195501 190.123) (xy 189.595501 190.123)
				(xy 189.6 188.25) (xy 189.4 188.05) (xy 188.7 188.05) (xy 188.695501 185.423)
			)
		)
	)
	(zone
		(net 239)
		(net_name "/Supply/spare")
		(layer "F.Cu")
		(hatch edge 0.508)
		(priority 1)
		(connect_pads yes
			(clearance 0.12)
		)
		(min_thickness 0.254)
		(filled_areas_thickness no)
		(fill yes
			(thermal_gap 0.508)
			(thermal_bridge_width 0.508)
		)
		(polygon
			(pts
				(xy 185.81 176.1) (xy 198.601 176.1) (xy 198.601 178.217) (xy 185.81 178.217)
			)
		)
	)
	(zone
		(net 38)
		(net_name "VDC")
		(layer "F.Cu")
		(hatch edge 0.508)
		(priority 3)
		(connect_pads yes
			(clearance 0.12)
		)
		(min_thickness 0.254)
		(filled_areas_thickness no)
		(fill yes
			(thermal_gap 0.508)
			(thermal_bridge_width 0.508)
		)
		(polygon
			(pts
				(xy 206.400501 184.376) (xy 200.300501 184.376) (xy 200.300501 183.076) (xy 202.400501 183.076)
				(xy 202.4 182.85) (xy 203.500501 181.75) (xy 203.500501 176.876) (xy 206.400501 176.876)
			)
		)
	)
	(zone
		(net 38)
		(net_name "VDC")
		(layer "F.Cu")
		(hatch edge 0.508)
		(priority 4)
		(connect_pads
			(clearance 0.2)
		)
		(min_thickness 0.254)
		(filled_areas_thickness no)
		(fill yes
			(thermal_gap 0.3)
			(thermal_bridge_width 0.3)
		)
		(polygon
			(pts
				(xy 121.05 198.3) (xy 121.6 198.85) (xy 121.6 202) (xy 120.65 202) (xy 120.25 201.65) (xy 118.05 201.65)
				(xy 118.05 200.426) (xy 113.900501 200.426) (xy 113.900501 200.326) (xy 113.900501 198.676) (xy 116.800501 195.726)
				(xy 121.05 195.726)
			)
		)
	)
	(zone
		(net 1)
		(net_name "GND")
		(layer "F.Cu")
		(hatch edge 0.508)
		(priority 1)
		(connect_pads yes
			(clearance 0.2)
		)
		(min_thickness 0.254)
		(filled_areas_thickness no)
		(fill yes
			(thermal_gap 0.508)
			(thermal_bridge_width 0.508)
		)
		(polygon
			(pts
				(xy 184.825 137.325) (xy 179.825 137.325) (xy 179.825 128.875) (xy 184.825 128.875)
			)
		)
	)
	(zone
		(net 41)
		(net_name "+3V3_AON")
		(layer "F.Cu")
		(hatch edge 0.508)
		(priority 1)
		(connect_pads yes
			(clearance 0.1)
		)
		(min_thickness 0.254)
		(filled_areas_thickness no)
		(fill yes
			(thermal_gap 0.508)
			(thermal_bridge_width 0.508)
		)
		(polygon
			(pts
				(xy 200.913499 135.4) (xy 197.333499 135.4) (xy 197.333499 133.96) (xy 200.913499 133.96)
			)
		)
	)
	(zone
		(net 1)
		(net_name "GND")
		(layer "F.Cu")
		(hatch edge 0.508)
		(priority 2)
		(connect_pads
			(clearance 0.2)
		)
		(min_thickness 0.254)
		(filled_areas_thickness no)
		(fill yes
			(thermal_gap 0.3)
			(thermal_bridge_width 0.3)
		)
		(polygon
			(pts
				(xy 132.2 195.6) (xy 126 201.8) (xy 126 205.65) (xy 125.3 205.65) (xy 124.7 206.25) (xy 124.700501 208.276)
				(xy 117.2 208.276) (xy 117.2 207.35) (xy 118.1 206.45) (xy 118.1 204.8) (xy 119.8 204.8) (xy 120.5 205.476)
				(xy 121.600501 205.476) (xy 121.6 202.1) (xy 123.550992 202.1) (xy 123.553141 200.854049) (xy 122.05 200.85)
				(xy 122.0533 199.181238) (xy 121.1503 198.25) (xy 121.148282 195.675051) (xy 121.200501 195.676)
				(xy 122.400503 194.50108) (xy 126.8 194.5) (xy 129.1 192.201122) (xy 132.197546 192.201189)
			)
		)
	)
	(zone
		(net 60)
		(net_name "/Supply/5V_local")
		(layer "F.Cu")
		(hatch edge 0.508)
		(priority 2)
		(connect_pads yes
			(clearance 0.12)
		)
		(min_thickness 0.254)
		(filled_areas_thickness no)
		(fill yes
			(thermal_gap 0.508)
			(thermal_bridge_width 0.508)
		)
		(polygon
			(pts
				(xy 193.568501 165.672) (xy 193.868501 165.472) (xy 195.568501 165.472) (xy 195.568501 164.172)
				(xy 193.968501 164.172) (xy 192.268501 160.972) (xy 189.55 160.972) (xy 189.5555 162.9) (xy 189.4 163.05)
				(xy 188.625 163.05) (xy 188.625 165.672)
			)
		)
	)
	(zone
		(net 200)
		(net_name "+3V3")
		(layer "F.Cu")
		(hatch edge 0.508)
		(priority 4)
		(connect_pads yes
			(clearance 0.12)
		)
		(min_thickness 0.254)
		(filled_areas_thickness no)
		(fill yes
			(thermal_gap 0.508)
			(thermal_bridge_width 0.508)
		)
		(polygon
			(pts
				(xy 188.55 166.844) (xy 188.55 170.65) (xy 187.95 170.65) (xy 187.8 170.8) (xy 187.8 172.66) (xy 185.783 172.66)
				(xy 185.783 166.844)
			)
		)
	)
	(zone
		(net 188)
		(net_name "+1V8")
		(layer "F.Cu")
		(hatch edge 0.508)
		(priority 2)
		(connect_pads yes
			(clearance 0.12)
		)
		(min_thickness 0.254)
		(filled_areas_thickness no)
		(fill yes
			(thermal_gap 0.508)
			(thermal_bridge_width 0.508)
		)
		(polygon
			(pts
				(xy 187.8 178.476) (xy 187.8 180.3) (xy 188.6 181.1) (xy 188.6 184.192) (xy 185.783 184.192) (xy 185.783 178.476)
			)
		)
	)
	(zone
		(net 11)
		(net_name "+12V")
		(layer "F.Cu")
		(hatch edge 0.508)
		(priority 1)
		(connect_pads
			(clearance 0.2)
		)
		(min_thickness 0.254)
		(filled_areas_thickness no)
		(fill yes
			(thermal_gap 0.3)
			(thermal_bridge_width 0.256)
		)
		(polygon
			(pts
				(xy 117.2 204.8) (xy 117.95 204.8) (xy 117.95 206.45) (xy 117.100501 207.3) (xy 117.100501 208.276)
				(xy 113.900501 208.276) (xy 113.900501 204.476) (xy 116.9 204.476)
			)
		)
	)
	(zone
		(net 56)
		(net_name "/Supply/1V2_local")
		(layer "F.Cu")
		(hatch edge 0.508)
		(priority 2)
		(connect_pads yes
			(clearance 0.12)
		)
		(min_thickness 0.254)
		(filled_areas_thickness no)
		(fill yes
			(thermal_gap 0.508)
			(thermal_bridge_width 0.508)
		)
		(polygon
			(pts
				(xy 200.418501 171.572) (xy 200.418501 175.522) (xy 203.368501 175.522) (xy 203.368501 170.272)
				(xy 202.668501 170.272) (xy 201.768501 169.372) (xy 199.268501 169.372) (xy 199.268501 170.55)
			)
		)
	)
	(zone
		(net 53)
		(net_name "/Supply/1V1_local")
		(layer "F.Cu")
		(hatch edge 0.508)
		(priority 2)
		(connect_pads yes
			(clearance 0.12)
		)
		(min_thickness 0.254)
		(filled_areas_thickness no)
		(fill yes
			(thermal_gap 0.508)
			(thermal_bridge_width 0.508)
		)
		(polygon
			(pts
				(xy 199.943501 162.172) (xy 199.943501 158.672) (xy 203.368501 158.672) (xy 203.368501 163.472)
				(xy 202.668501 163.472) (xy 201.768501 164.372) (xy 199.268501 164.372) (xy 199.268501 162.672)
			)
		)
	)
	(zone
		(net 35)
		(net_name "/Supply/spare_local")
		(layer "F.Cu")
		(hatch edge 0.508)
		(priority 2)
		(connect_pads yes
			(clearance 0.12)
		)
		(min_thickness 0.254)
		(filled_areas_thickness no)
		(fill yes
			(thermal_gap 0.508)
			(thermal_bridge_width 0.508)
		)
		(polygon
			(pts
				(xy 200.395501 179.2) (xy 200.395501 175.673) (xy 203.395501 175.673) (xy 203.395501 180.973) (xy 202.695501 180.973)
				(xy 201.795501 181.873) (xy 199.295501 181.873) (xy 199.295501 180.173)
			)
		)
	)
	(zone
		(net 1)
		(net_name "GND")
		(layer "F.Cu")
		(hatch edge 0.508)
		(connect_pads yes
			(clearance 0.12)
		)
		(min_thickness 0.254)
		(filled_areas_thickness no)
		(fill yes
			(thermal_gap 0.508)
			(thermal_bridge_width 0.508)
		)
		(polygon
			(pts
				(xy 192.368501 165.772) (xy 192.368501 161.372) (xy 192.368501 161.022) (xy 199.243501 161.022)
				(xy 199.243501 162.572) (xy 202.168501 162.572) (xy 202.168501 167.072) (xy 206.368501 167.072)
				(xy 206.368501 176.722) (xy 203.493501 176.722) (xy 203.493501 170.572) (xy 199.768501 170.572)
				(xy 199.768501 172.672) (xy 192.368501 172.672) (xy 192.368501 172.272) (xy 192.368501 167.872)
				(xy 188.618501 167.872) (xy 188.618501 165.772)
			)
		)
	)
	(zone
		(net 206)
		(net_name "+1V1")
		(layer "F.Cu")
		(hatch edge 0.508)
		(priority 1)
		(connect_pads yes
			(clearance 0.1)
		)
		(min_thickness 0.254)
		(filled_areas_thickness no)
		(fill yes
			(thermal_gap 0.508)
			(thermal_bridge_width 0.508)
		)
		(polygon
			(pts
				(xy 198.166501 160.747) (xy 185.770501 160.747) (xy 185.770501 158.68) (xy 198.166501 158.68)
			)
		)
	)
	(zone
		(net 1)
		(net_name "GND")
		(layer "F.Cu")
		(hatch edge 0.508)
		(connect_pads
			(clearance 0.15)
		)
		(min_thickness 0.254)
		(filled_areas_thickness no)
		(fill yes
			(thermal_gap 0.508)
			(thermal_bridge_width 0.508)
		)
		(polygon
			(pts
				(xy 186.9 128.625) (xy 184.975 128.625) (xy 184.975 125.35) (xy 186.9 125.35)
			)
		)
	)
	(zone
		(net 78)
		(net_name "/Supply/1V0_REG")
		(layer "F.Cu")
		(hatch edge 0.508)
		(priority 1)
		(connect_pads yes
			(clearance 0.12)
		)
		(min_thickness 0.254)
		(filled_areas_thickness no)
		(fill yes
			(thermal_gap 0.508)
			(thermal_bridge_width 0.508)
		)
		(polygon
			(pts
				(xy 170.416501 191.492999) (xy 169.35 191.5) (xy 168.850501 192) (xy 168.850501 197.792999) (xy 166.100501 197.792999)
				(xy 166.100501 190.2) (xy 167.300501 189) (xy 167.300501 183.726) (xy 168.1 183.726) (xy 169.2 184.826)
				(xy 170.416501 184.826) (xy 170.416501 189.276001)
			)
		)
	)
	(zone
		(net 595)
		(net_name "/Supply/12V_aux_fused")
		(layer "F.Cu")
		(hatch edge 0.508)
		(connect_pads yes
			(clearance 0.2)
		)
		(min_thickness 0.254)
		(filled_areas_thickness no)
		(fill yes
			(thermal_gap 0.508)
			(thermal_bridge_width 0.508)
		)
		(polygon
			(pts
				(xy 191.840501 133.426) (xy 184.990501 133.426) (xy 184.990501 128.886) (xy 191.840501 128.886)
			)
		)
	)
	(zone
		(net 64)
		(net_name "/Supply/1V7")
		(layer "F.Cu")
		(hatch edge 0.508)
		(priority 1)
		(connect_pads yes
			(clearance 0.1)
		)
		(min_thickness 0.254)
		(filled_areas_thickness no)
		(fill yes
			(thermal_gap 0.508)
			(thermal_bridge_width 0.508)
		)
		(polygon
			(pts
				(xy 185.784 190.308) (xy 198.1 190.308) (xy 198.1 192.425) (xy 185.784 192.425)
			)
		)
	)
	(zone
		(net 201)
		(net_name "+5V")
		(layer "F.Cu")
		(hatch edge 0.508)
		(priority 3)
		(connect_pads yes
			(clearance 0.12)
		)
		(min_thickness 0.254)
		(filled_areas_thickness no)
		(fill yes
			(thermal_gap 0.508)
			(thermal_bridge_width 0.508)
		)
		(polygon
			(pts
				(xy 187.75 160.95) (xy 187.75 162.9) (xy 187.9 163.05) (xy 188.55 163.05) (xy 188.55 166.766) (xy 185.783 166.766)
				(xy 185.783 160.95)
			)
		)
	)
	(zone
		(net 226)
		(net_name "+1V2_MGTAVTT")
		(layer "F.Cu")
		(hatch edge 0.508)
		(priority 1)
		(connect_pads yes
			(clearance 0.1)
		)
		(min_thickness 0.254)
		(filled_areas_thickness no)
		(fill yes
			(thermal_gap 0.508)
			(thermal_bridge_width 0.508)
		)
		(polygon
			(pts
				(xy 188.4 192.575) (xy 190.325 192.575) (xy 190.325 195.8) (xy 190.325 201) (xy 185.783 201) (xy 185.780858 192.573448)
			)
		)
	)
	(zone
		(net 52)
		(net_name "/Supply/3V3_local")
		(layer "F.Cu")
		(hatch edge 0.508)
		(priority 5)
		(connect_pads yes
			(clearance 0.12)
		)
		(min_thickness 0.254)
		(filled_areas_thickness no)
		(fill yes
			(thermal_gap 0.508)
			(thermal_bridge_width 0.508)
		)
		(polygon
			(pts
				(xy 193.568501 167.972) (xy 193.868501 168.172) (xy 195.568501 168.172) (xy 195.568501 169.472)
				(xy 193.968501 169.472) (xy 192.268501 172.672) (xy 189.568502 172.671788) (xy 189.576001 170.85)
				(xy 189.4 170.65) (xy 188.618501 170.65) (xy 188.618501 167.972)
			)
		)
	)
	(zone
		(net 51)
		(net_name "/Supply/1V8_local")
		(layer "F.Cu")
		(hatch edge 0.508)
		(priority 1)
		(connect_pads yes
			(clearance 0.12)
		)
		(min_thickness 0.254)
		(filled_areas_thickness no)
		(fill yes
			(thermal_gap 0.508)
			(thermal_bridge_width 0.508)
		)
		(polygon
			(pts
				(xy 193.595501 183.173) (xy 193.895501 182.973) (xy 195.595501 182.973) (xy 195.595501 181.673)
				(xy 193.995501 181.673) (xy 192.295501 178.473) (xy 189.575 178.473) (xy 189.575 180.219) (xy 188.695501 181.1)
				(xy 188.695501 183.173)
			)
		)
	)
	(zone
		(net 58)
		(net_name "/Supply/1V7_local")
		(layer "F.Cu")
		(hatch edge 0.508)
		(priority 2)
		(connect_pads yes
			(clearance 0.12)
		)
		(min_thickness 0.254)
		(filled_areas_thickness no)
		(fill yes
			(thermal_gap 0.508)
			(thermal_bridge_width 0.508)
		)
		(polygon
			(pts
				(xy 199.895501 188.973) (xy 199.895501 192.358) (xy 203.395501 192.358) (xy 203.395501 187.673)
				(xy 202.695501 187.673) (xy 201.795501 186.773) (xy 199.295501 186.773) (xy 199.295501 188.473)
			)
		)
	)
	(zone
		(net 38)
		(net_name "VDC")
		(layer "F.Cu")
		(hatch edge 0.508)
		(connect_pads yes
			(clearance 0.12)
		)
		(min_thickness 0.254)
		(filled_areas_thickness no)
		(fill yes
			(thermal_gap 0.508)
			(thermal_bridge_width 0.508)
		)
		(polygon
			(pts
				(xy 178.800501 200.993) (xy 172.984501 200.993) (xy 172.984501 193.976) (xy 175.600501 193.976)
				(xy 175.600501 198.776) (xy 178.800501 198.776)
			)
		)
	)
	(zone
		(net 0)
		(net_name "")
		(layer "F.Cu")
		(hatch edge 0.508)
		(connect_pads yes
			(clearance 0)
		)
		(min_thickness 0.254)
		(filled_areas_thickness no)
		(keepout
			(tracks allowed)
			(vias allowed)
			(pads allowed)
			(copperpour not_allowed)
			(footprints allowed)
		)
		(placement
			(enabled no)
			(sheetname "")
		)
		(fill
			(thermal_gap 0.508)
			(thermal_bridge_width 0.508)
		)
		(polygon
			(pts
				(xy 206.734146 197.551) (xy 206.714006 197.15343) (xy 206.653792 196.75993) (xy 206.554121 196.37453)
				(xy 206.416013 196.001175) (xy 206.240882 195.643688) (xy 206.030521 195.30573) (xy 205.787084 194.990759)
				(xy 205.513064 194.702002) (xy 205.211266 194.442415) (xy 204.88478 194.214655) (xy 204.536948 194.021055)
				(xy 204.171333 193.863596) (xy 203.791678 193.743891) (xy 203.401869 193.663165) (xy 203.005897 193.622246)
				(xy 202.607818 193.621551) (xy 202.211706 193.661088) (xy 201.821618 193.740452) (xy 201.441546 193.858831)
				(xy 201.075384 194.015013) (xy 200.726879 194.207398) (xy 200.3996 194.434017) (xy 200.096897 194.692549)
				(xy 199.821871 194.980348) (xy 199.577336 195.294467) (xy 199.365797 195.631689) (xy 199.189419 195.988562)
				(xy 199.050009 196.361433) (xy 198.948993 196.746483) (xy 198.887406 197.13977) (xy 198.865878 197.537267)
				(xy 198.88463 197.934905) (xy 198.94347 198.328613) (xy 199.041795 198.714359) (xy 199.1786 199.088193)
				(xy 199.352482 199.446289) (xy 199.561661 199.78498) (xy 199.803997 200.100798) (xy 200.077008 200.39051)
				(xy 200.377898 200.651149) (xy 200.703587 200.880047) (xy 201.05074 201.074861) (xy 201.415804 201.233595)
				(xy 201.795039 201.354624) (xy 202.184564 201.43671) (xy 202.58039 201.479012) (xy 202.978465 201.481096)
				(xy 203.374712 201.442942) (xy 203.765075 201.36494) (xy 204.145557 201.247888) (xy 204.512263 201.092985)
				(xy 204.861437 200.901818) (xy 205.189505 200.676343) (xy 205.493108 200.418869) (xy 205.769138 200.132032)
				(xy 206.014767 199.818769) (xy 206.227482 199.482287) (xy 206.405105 199.126032) (xy 206.545816 198.75365)
				(xy 206.648175 198.368955) (xy 206.711135 197.975885) (xy 206.73405 197.578465)
			)
		)
	)
	(zone
		(net 201)
		(net_name "+5V")
		(layer "F.Cu")
		(hatch edge 0.508)
		(priority 1)
		(connect_pads yes
			(clearance 0.12)
		)
		(min_thickness 0.2)
		(filled_areas_thickness no)
		(fill yes
			(thermal_gap 0.35)
			(thermal_bridge_width 0.2)
		)
		(polygon
			(pts
				(xy 107.175001 150.6025) (xy 105.175001 150.6025) (xy 105.175001 147.4025) (xy 106.075001 147.4025)
				(xy 107.175001 147.4025)
			)
		)
	)
	(zone
		(net 187)
		(net_name "+1V0_MGTAVCC")
		(layer "F.Cu")
		(hatch edge 0.508)
		(priority 3)
		(connect_pads yes
			(clearance 0.12)
		)
		(min_thickness 0.254)
		(filled_areas_thickness no)
		(fill yes
			(thermal_gap 0.508)
			(thermal_bridge_width 0.508)
		)
		(polygon
			(pts
				(xy 188.596 188.05) (xy 187.975 188.05) (xy 187.8 188.224787) (xy 187.796 190.091787) (xy 185.78 190.092)
				(xy 185.78 184.3) (xy 188.596 184.3)
			)
		)
	)
	(zone
		(net 1)
		(net_name "GND")
		(layer "F.Cu")
		(hatch edge 0.508)
		(connect_pads yes
			(clearance 0.12)
		)
		(min_thickness 0.3)
		(filled_areas_thickness no)
		(fill yes
			(thermal_gap 0.508)
			(thermal_bridge_width 0.508)
		)
		(polygon
			(pts
				(xy 192.195501 183.223) (xy 192.195501 178.473) (xy 199.695501 178.473) (xy 199.695501 180.023)
				(xy 202.195501 180.023) (xy 202.195501 184.523) (xy 206.395501 184.523) (xy 206.395501 200.998)
				(xy 190.395501 200.998) (xy 190.395501 196.3) (xy 196.2 196.3) (xy 196.195501 192.55) (xy 203.4 192.55)
				(xy 203.395501 188.023) (xy 199.120501 188.023) (xy 199.120501 190.048) (xy 192.595501 190.048)
				(xy 192.595501 189.723) (xy 192.595501 185.323) (xy 188.695501 185.323) (xy 188.695501 183.223)
			)
		)
	)
	(zone
		(net 1)
		(net_name "GND")
		(layer "F.Cu")
		(hatch edge 0.508)
		(connect_pads yes
			(clearance 0.12)
		)
		(min_thickness 0.2)
		(filled_areas_thickness no)
		(fill yes
			(thermal_gap 0.35)
			(thermal_bridge_width 0.2)
		)
		(polygon
			(pts
				(xy 105.075001 149.4025) (xy 102.975001 149.4025) (xy 102.975001 147.4025) (xy 105.075001 147.4025)
			)
		)
	)
	(zone
		(net 1)
		(net_name "GND")
		(layer "F.Cu")
		(hatch edge 0.508)
		(connect_pads no
			(clearance 2)
		)
		(min_thickness 2)
		(filled_areas_thickness no)
		(fill yes
			(thermal_gap 2)
			(thermal_bridge_width 2)
		)
		(polygon
			(pts
				(xy 197.3 120.8) (xy 178.2 120.8) (xy 176.5 122.5) (xy 176.5 135.4) (xy 103.6 135.4) (xy 103.6 127.85)
				(xy 106.1 125.35) (xy 106.1 111.55) (xy 197.3 111.55)
			)
		)
	)
	(zone
		(net 76)
		(net_name "/Supply/MGTAVTT_OUT")
		(layer "F.Cu")
		(hatch edge 0.508)
		(priority 1)
		(connect_pads yes
			(clearance 0.1)
		)
		(min_thickness 0.254)
		(filled_areas_thickness no)
		(fill yes
			(thermal_gap 0.508)
			(thermal_bridge_width 0.508)
		)
		(polygon
			(pts
				(xy 192.65 192.575) (xy 192.95 192.575) (xy 192.95 193.4) (xy 193.55 194) (xy 193.550007 194.474988)
				(xy 191.13298 194.474829) (xy 191.130831 192.573289)
			)
		)
	)
	(zone
		(net 38)
		(net_name "VDC")
		(layer "F.Cu")
		(hatch edge 0.508)
		(priority 3)
		(connect_pads yes
			(clearance 0.1)
		)
		(min_thickness 0.254)
		(filled_areas_thickness no)
		(fill yes
			(thermal_gap 0.508)
			(thermal_bridge_width 0.508)
		)
		(polygon
			(pts
				(xy 191.816759 137.507099) (xy 184.966759 137.507099) (xy 184.966759 133.807099) (xy 191.816759 133.807099)
			)
		)
	)
	(zone
		(net 597)
		(net_name "/Supply/12V_aux")
		(layer "F.Cu")
		(hatch edge 0.508)
		(priority 1)
		(connect_pads yes
			(clearance 0.1)
		)
		(min_thickness 0.254)
		(filled_areas_thickness no)
		(fill yes
			(thermal_gap 0.508)
			(thermal_bridge_width 0.508)
		)
		(polygon
			(pts
				(xy 194.810501 131.086) (xy 191.870501 131.086) (xy 189.430501 128.686) (xy 187.021774 128.6829)
				(xy 187.025269 125.349325) (xy 194.81077 125.335325)
			)
		)
	)
	(zone
		(net 1)
		(net_name "GND")
		(layer "F.Cu")
		(hatch edge 0.508)
		(priority 2)
		(connect_pads yes
			(clearance 0.12)
		)
		(min_thickness 0.254)
		(filled_areas_thickness no)
		(fill yes
			(thermal_gap 0.508)
			(thermal_bridge_width 0.508)
		)
		(polygon
			(pts
				(xy 81.7 149.8) (xy 81.7 152.8) (xy 81.35 153.15) (xy 80.65 153.15) (xy 80.35 152.85) (xy 80.35 151.4)
				(xy 79.15 151.4) (xy 79.15 150.8) (xy 80.35 150.8) (xy 80.35 149.8) (xy 80.6 149.55) (xy 81.45 149.55)
			)
		)
	)
	(zone
		(net 66)
		(net_name "/Supply/1V0_SW")
		(layer "F.Cu")
		(hatch edge 0.508)
		(priority 1)
		(connect_pads yes
			(clearance 0.12)
		)
		(min_thickness 0.254)
		(filled_areas_thickness no)
		(fill yes
			(thermal_gap 0.508)
			(thermal_bridge_width 0.508)
		)
		(polygon
			(pts
				(xy 174.3 189.2) (xy 175.3 190.2) (xy 175.300501 191.076) (xy 174.260501 191.076) (xy 173.166501 192.166)
				(xy 173.166501 194.393) (xy 172.620501 194.393) (xy 172.620501 193.9) (xy 171.8 193.1) (xy 171.8 192.7)
				(xy 170.6 191.5) (xy 170.600885 184.82509) (xy 174.283886 184.824521)
			)
		)
	)
	(zone
		(net 0)
		(net_name "")
		(layers "F.Cu" "B.Cu" "In1.Cu" "In2.Cu")
		(hatch edge 0.508)
		(connect_pads
			(clearance 0)
		)
		(min_thickness 0.254)
		(filled_areas_thickness no)
		(keepout
			(tracks not_allowed)
			(vias not_allowed)
			(pads allowed)
			(copperpour not_allowed)
			(footprints allowed)
		)
		(placement
			(enabled no)
			(sheetname "")
		)
		(fill
			(thermal_gap 0.508)
			(thermal_bridge_width 0.508)
		)
		(polygon
			(pts
				(xy 102.225501 206.301) (xy 110.225501 206.301) (xy 110.225501 209.801) (xy 102.225501 209.801)
			)
		)
	)
	(zone
		(net 0)
		(net_name "")
		(layers "F.Cu" "B.Cu" "In1.Cu" "In2.Cu")
		(hatch edge 0.508)
		(connect_pads
			(clearance 0)
		)
		(min_thickness 0.254)
		(filled_areas_thickness no)
		(keepout
			(tracks not_allowed)
			(vias not_allowed)
			(pads allowed)
			(copperpour allowed)
			(footprints allowed)
		)
		(placement
			(enabled no)
			(sheetname "")
		)
		(fill
			(thermal_gap 0.508)
			(thermal_bridge_width 0.508)
		)
		(polygon
			(pts
				(xy 149.025501 203.851) (xy 149.025501 202.851) (xy 232.295501 202.851) (xy 232.295501 108.451)
				(xy 206.875501 108.451) (xy 206.875501 106.451) (xy 82.425501 106.451) (xy 82.425501 124.701) (xy 69.725501 124.701)
				(xy 69.725501 105.451) (xy 237.375501 105.451) (xy 237.375501 203.851)
			)
		)
	)
	(zone
		(net 0)
		(net_name "")
		(layers "F.Cu" "B.Cu" "In1.Cu" "In2.Cu")
		(hatch edge 0.508)
		(connect_pads
			(clearance 0)
		)
		(min_thickness 0.254)
		(filled_areas_thickness no)
		(keepout
			(tracks not_allowed)
			(vias not_allowed)
			(pads allowed)
			(copperpour allowed)
			(footprints allowed)
		)
		(placement
			(enabled no)
			(sheetname "")
		)
		(fill
			(thermal_gap 0.508)
			(thermal_bridge_width 0.508)
		)
		(polygon
			(pts
				(xy 68.875501 200.551) (xy 113.875501 200.551) (xy 113.875501 203.376) (xy 110.225501 203.376) (xy 110.225501 206.301)
				(xy 102.225501 206.301) (xy 102.225501 201.551) (xy 83.875501 201.551) (xy 83.875501 209.801) (xy 68.875501 209.801)
			)
		)
	)
	(zone
		(net 0)
		(net_name "")
		(layers "F.Cu" "B.Cu" "In1.Cu" "In2.Cu" "In3.Cu" "In4.Cu" "In5.Cu" "In6.Cu"
			"In7.Cu" "In8.Cu" "In9.Cu" "In10.Cu"
		)
		(hatch edge 0.508)
		(connect_pads yes
			(clearance 0)
		)
		(min_thickness 0.254)
		(filled_areas_thickness no)
		(keepout
			(tracks allowed)
			(vias allowed)
			(pads allowed)
			(copperpour not_allowed)
			(footprints allowed)
		)
		(placement
			(enabled no)
			(sheetname "")
		)
		(fill
			(thermal_gap 0.508)
			(thermal_bridge_width 0.508)
		)
		(polygon
			(pts
				(xy 147.9 185.15) (xy 146.85 185.15) (xy 146.85 184.45) (xy 147.9 184.45)
			)
		)
	)
	(zone
		(net 0)
		(net_name "")
		(layers "F.Cu" "B.Cu" "In1.Cu" "In2.Cu" "In3.Cu" "In4.Cu" "In5.Cu" "In6.Cu"
			"In7.Cu" "In8.Cu" "In9.Cu" "In10.Cu"
		)
		(hatch edge 0.508)
		(connect_pads yes
			(clearance 0)
		)
		(min_thickness 0.254)
		(filled_areas_thickness no)
		(keepout
			(tracks allowed)
			(vias allowed)
			(pads allowed)
			(copperpour not_allowed)
			(footprints allowed)
		)
		(placement
			(enabled no)
			(sheetname "")
		)
		(fill
			(thermal_gap 0.508)
			(thermal_bridge_width 0.508)
		)
		(polygon
			(pts
				(xy 151.9 187.15) (xy 150.85 187.15) (xy 150.85 186.45) (xy 151.9 186.45)
			)
		)
	)
	(zone
		(net 0)
		(net_name "")
		(layers "F.Cu" "B.Cu" "In1.Cu" "In2.Cu" "In3.Cu" "In4.Cu" "In5.Cu" "In6.Cu"
			"In7.Cu" "In8.Cu" "In9.Cu" "In10.Cu"
		)
		(hatch edge 0.508)
		(connect_pads yes
			(clearance 0)
		)
		(min_thickness 0.254)
		(filled_areas_thickness no)
		(keepout
			(tracks allowed)
			(vias allowed)
			(pads allowed)
			(copperpour not_allowed)
			(footprints allowed)
		)
		(placement
			(enabled no)
			(sheetname "")
		)
		(fill
			(thermal_gap 0.508)
			(thermal_bridge_width 0.508)
		)
		(polygon
			(pts
				(xy 151.9 185.15) (xy 150.85 185.15) (xy 150.85 184.45) (xy 151.9 184.45)
			)
		)
	)
	(zone
		(net 0)
		(net_name "")
		(layers "F.Cu" "B.Cu" "In1.Cu" "In2.Cu" "In3.Cu" "In4.Cu" "In5.Cu" "In6.Cu"
			"In7.Cu" "In8.Cu" "In9.Cu" "In10.Cu"
		)
		(hatch edge 0.508)
		(connect_pads yes
			(clearance 0)
		)
		(min_thickness 0.254)
		(filled_areas_thickness no)
		(keepout
			(tracks allowed)
			(vias allowed)
			(pads allowed)
			(copperpour not_allowed)
			(footprints allowed)
		)
		(placement
			(enabled no)
			(sheetname "")
		)
		(fill
			(thermal_gap 0.508)
			(thermal_bridge_width 0.508)
		)
		(polygon
			(pts
				(xy 151.9 183.15) (xy 150.85 183.15) (xy 150.85 182.45) (xy 151.9 182.45)
			)
		)
	)
	(zone
		(net 1)
		(net_name "GND")
		(layer "B.Cu")
		(hatch edge 0.508)
		(priority 2)
		(connect_pads no
			(clearance 1.5)
		)
		(min_thickness 2)
		(filled_areas_thickness no)
		(fill yes
			(thermal_gap 2)
			(thermal_bridge_width 2)
		)
		(polygon
			(pts
				(xy 180.4 158.5) (xy 168.6 170.3) (xy 159 170.3) (xy 157.2 172.1) (xy 153.4 172.1) (xy 153.4 168.7)
				(xy 154.5 168.7) (xy 155.3 167.9) (xy 155.3 162.1) (xy 153.4 160.2) (xy 148.6 160.2) (xy 148.6 154.4)
				(xy 150.4 152.6) (xy 180.4 152.6)
			)
		)
	)
	(zone
		(net 0)
		(net_name "")
		(layer "B.Cu")
		(hatch edge 0.508)
		(connect_pads
			(clearance 0)
		)
		(min_thickness 0.254)
		(filled_areas_thickness no)
		(keepout
			(tracks allowed)
			(vias allowed)
			(pads allowed)
			(copperpour not_allowed)
			(footprints allowed)
		)
		(placement
			(enabled no)
			(sheetname "")
		)
		(fill
			(thermal_gap 0.508)
			(thermal_bridge_width 0.508)
		)
		(polygon
			(pts
				(xy 82.5 124.75) (xy 68.75 124.75) (xy 68.75 111.5) (xy 82.5 111.5)
			)
		)
	)
	(zone
		(net 1)
		(net_name "GND")
		(layer "B.Cu")
		(hatch edge 0.508)
		(connect_pads
			(clearance 0.1)
		)
		(min_thickness 0.254)
		(filled_areas_thickness no)
		(fill yes
			(thermal_gap 0.508)
			(thermal_bridge_width 0.508)
		)
		(polygon
			(pts
				(xy 202.2 188.525) (xy 188.75 188.525) (xy 188.75 180.025) (xy 202.2 180.025)
			)
		)
	)
	(zone
		(net 11)
		(net_name "+12V")
		(layer "B.Cu")
		(hatch edge 0.508)
		(priority 1)
		(connect_pads
			(clearance 0.2)
		)
		(min_thickness 0.254)
		(filled_areas_thickness no)
		(fill yes
			(thermal_gap 0.3)
			(thermal_bridge_width 0.3)
		)
		(polygon
			(pts
				(xy 117.100501 208.276) (xy 114.300501 208.276) (xy 114.300501 203.376) (xy 117.100501 203.376)
			)
		)
	)
	(zone
		(net 1)
		(net_name "GND")
		(layer "B.Cu")
		(hatch edge 0.508)
		(connect_pads
			(clearance 0.2)
		)
		(min_thickness 0.254)
		(filled_areas_thickness no)
		(fill yes
			(thermal_gap 0.3)
			(thermal_bridge_width 0.3)
		)
		(polygon
			(pts
				(xy 120.000501 208.276) (xy 117.200501 208.276) (xy 117.200501 203.376) (xy 120.000501 203.376)
			)
		)
	)
	(zone
		(net 1)
		(net_name "GND")
		(layer "B.Cu")
		(hatch edge 0.508)
		(priority 2)
		(connect_pads no
			(clearance 1.5)
		)
		(min_thickness 2)
		(filled_areas_thickness no)
		(fill yes
			(thermal_gap 2)
			(thermal_bridge_width 2)
		)
		(polygon
			(pts
				(xy 124.39 170.95) (xy 106.15 170.95) (xy 106.15 148.02) (xy 124.39 148.02)
			)
		)
	)
	(zone
		(net 1)
		(net_name "GND")
		(layer "B.Cu")
		(hatch edge 0.508)
		(connect_pads
			(clearance 0.1)
		)
		(min_thickness 0.254)
		(filled_areas_thickness no)
		(fill yes
			(thermal_gap 0.508)
			(thermal_bridge_width 0.508)
		)
		(polygon
			(pts
				(xy 202.2 171) (xy 188.75 171) (xy 188.75 162.5) (xy 202.2 162.5)
			)
		)
	)
	(zone
		(net 1)
		(net_name "GND")
		(layer "B.Cu")
		(hatch edge 0.508)
		(priority 2)
		(connect_pads no
			(clearance 1.5)
		)
		(min_thickness 2)
		(filled_areas_thickness no)
		(fill yes
			(thermal_gap 2)
			(thermal_bridge_width 2)
		)
		(polygon
			(pts
				(xy 114.2 199.6) (xy 98.6 199.6) (xy 98.6 186) (xy 114.2 186)
			)
		)
	)
	(zone
		(net 0)
		(net_name "")
		(layer "B.Cu")
		(hatch edge 0.508)
		(connect_pads
			(clearance 0)
		)
		(min_thickness 0.254)
		(filled_areas_thickness no)
		(keepout
			(tracks allowed)
			(vias not_allowed)
			(pads allowed)
			(copperpour allowed)
			(footprints allowed)
		)
		(placement
			(enabled no)
			(sheetname "")
		)
		(fill
			(thermal_gap 0.508)
			(thermal_bridge_width 0.508)
		)
		(polygon
			(pts
				(xy 68.875501 200.551) (xy 73.955501 200.551) (xy 73.955501 124.601) (xy 68.875501 124.601)
			)
		)
	)
	(zone
		(net 1)
		(net_name "GND")
		(layers "B.Cu" "In2.Cu" "In4.Cu" "In6.Cu" "In9.Cu")
		(hatch edge 0.508)
		(connect_pads no
			(clearance 2)
		)
		(min_thickness 2)
		(filled_areas_thickness no)
		(fill yes
			(thermal_gap 2)
			(thermal_bridge_width 2)
		)
		(polygon
			(pts
				(xy 207 158.9) (xy 176.3 158.9) (xy 176.3 138) (xy 174.9 136.6) (xy 139.75 136.6) (xy 103.7 136.6)
				(xy 103.1 137.2) (xy 103.1 149.2) (xy 91.4 149.2) (xy 91.4 130.4) (xy 90.600018 129.596018) (xy 68.9 129.5)
				(xy 68.9 111.6) (xy 207 111.6)
			)
		)
	)
	(zone
		(net 1)
		(net_name "GND")
		(layers "In1.Cu" "In3.Cu" "In5.Cu" "In7.Cu")
		(hatch edge 0.508)
		(connect_pads
			(clearance 0.15)
		)
		(min_thickness 0.254)
		(filled_areas_thickness no)
		(fill yes
			(thermal_gap 0.508)
			(thermal_bridge_width 0.508)
		)
		(polygon
			(pts
				(xy 206.875501 214.301) (xy 68.875501 214.301) (xy 68.875501 108.501) (xy 206.875501 108.501)
			)
		)
	)
	(zone
		(net 0)
		(net_name "")
		(layer "F.SilkS")
		(hatch edge 0.508)
		(connect_pads yes
			(clearance 0.125)
		)
		(min_thickness 0.125)
		(filled_areas_thickness no)
		(fill yes
			(thermal_gap 0.15)
			(thermal_bridge_width 0.151)
		)
		(polygon
			(pts
				(xy 195.93946 117.45) (xy 183.2 117.45) (xy 183.2 113.55) (xy 195.93946 113.55)
			)
		)
	)
	(zone
		(net 227)
		(net_name "+1V0")
		(layer "In2.Cu")
		(hatch edge 0.508)
		(priority 2)
		(connect_pads
			(clearance 0.15)
		)
		(min_thickness 0.254)
		(filled_areas_thickness no)
		(fill yes
			(thermal_gap 0.508)
			(thermal_bridge_width 0.508)
		)
		(polygon
			(pts
				(xy 147.820499 178.2) (xy 167.675 178.2) (xy 167.675 200.5) (xy 122.100501 200.5) (xy 122.100501 195.2)
				(xy 122.9 194.4) (xy 122.9 192) (xy 122.100501 191.2) (xy 122.100501 188.7) (xy 122.6 188.200501)
				(xy 131.9 188.200501) (xy 132.500501 187.6) (xy 132.500501 175.7) (xy 133.2 175) (xy 134.2 175)
				(xy 136.700501 172.5) (xy 136.700501 170.8025) (xy 136.877001 170.8025) (xy 137 170.679501) (xy 137.7 170.679501)
				(xy 137.9 170.479501) (xy 140.1 170.479501)
			)
		)
	)
	(zone
		(net 1)
		(net_name "GND")
		(layers "In2.Cu" "In4.Cu" "In6.Cu" "In9.Cu")
		(hatch edge 0.508)
		(connect_pads no
			(clearance 2)
		)
		(min_thickness 2)
		(filled_areas_thickness no)
		(fill yes
			(thermal_gap 2)
			(thermal_bridge_width 2)
		)
		(polygon
			(pts
				(xy 90.8 209.7) (xy 68.7 209.7) (xy 68.7 149.1) (xy 77.6 149.1) (xy 77.514576 161.800049) (xy 81.7 166.1)
				(xy 90.8 166.1)
			)
		)
	)
	(zone
		(net 0)
		(net_name "")
		(layer "In6.Cu")
		(hatch edge 0.508)
		(connect_pads no
			(clearance 0)
		)
		(min_thickness 2)
		(filled_areas_thickness no)
		(keepout
			(tracks allowed)
			(vias allowed)
			(pads allowed)
			(copperpour not_allowed)
			(footprints allowed)
		)
		(placement
			(enabled no)
			(sheetname "")
		)
		(fill
			(thermal_gap 2)
			(thermal_bridge_width 2)
		)
		(polygon
			(pts
				(xy 91.2 197) (xy 88.3 197) (xy 83.4 192.1) (xy 83.4 176.5) (xy 91.2 176.5)
			)
		)
	)
	(zone
		(net 199)
		(net_name "+1V2")
		(layer "In6.Cu")
		(hatch edge 0.508)
		(priority 2)
		(connect_pads
			(clearance 0.15)
		)
		(min_thickness 0.254)
		(filled_areas_thickness no)
		(fill yes
			(thermal_gap 0.508)
			(thermal_bridge_width 0.508)
		)
		(polygon
			(pts
				(xy 99.100501 150.526) (xy 107.100501 150.526) (xy 107.850501 151.276) (xy 107.850501 157.526) (xy 105.600501 159.776)
				(xy 89.350501 159.776) (xy 85.600501 156.026) (xy 85.600501 150.526) (xy 87.600501 148.526) (xy 99.100501 148.526)
			)
		)
	)
	(zone
		(net 188)
		(net_name "+1V8")
		(layer "In6.Cu")
		(hatch edge 0.508)
		(priority 2)
		(connect_pads yes
			(clearance 0.12)
		)
		(min_thickness 0.254)
		(filled_areas_thickness no)
		(fill yes
			(thermal_gap 0.508)
			(thermal_bridge_width 0.508)
		)
		(polygon
			(pts
				(xy 206.9 201.55) (xy 148.15 201.55) (xy 148.15 195) (xy 148.15 182.3) (xy 146.15 180.3) (xy 140.8 180.3)
				(xy 140.3 179.8) (xy 140.3 171.8) (xy 141.5 170.6) (xy 165.6 170.6) (xy 176.25 160.05) (xy 176.3 111.7)
				(xy 206.9 111.55)
			)
		)
	)
	(zone
		(net 201)
		(net_name "+5V")
		(layer "In8.Cu")
		(hatch edge 0.508)
		(priority 2)
		(connect_pads
			(clearance 0.12)
		)
		(min_thickness 0.254)
		(filled_areas_thickness no)
		(fill yes
			(thermal_gap 0.508)
			(thermal_bridge_width 0.508)
		)
		(polygon
			(pts
				(xy 206.800501 165.376) (xy 185.7 165.375) (xy 185.699993 161.250011) (xy 190.575 161.250122) (xy 191.55 160.275)
				(xy 191.55 155.9) (xy 176.9 141.2) (xy 176.9 137) (xy 107.2 137) (xy 107.205345 150.453199) (xy 99.274434 150.451564)
				(xy 99.275001 109.0025) (xy 206.800501 109.276)
			)
		)
	)
	(zone
		(net 188)
		(net_name "+1V8")
		(layer "In8.Cu")
		(hatch edge 0.508)
		(priority 1)
		(connect_pads
			(clearance 0.12)
		)
		(min_thickness 0.254)
		(filled_areas_thickness no)
		(fill yes
			(thermal_gap 0.508)
			(thermal_bridge_width 0.508)
		)
		(polygon
			(pts
				(xy 185.575 165.575) (xy 206.825 165.475) (xy 206.85 182.425) (xy 186.900501 182.376) (xy 182.075001 177.60235)
				(xy 151.175001 177.6025) (xy 150.075001 176.5025) (xy 146.975001 176.5025) (xy 145.850501 175.406)
				(xy 144.150501 175.406) (xy 143.350501 176.206) (xy 143.350501 177.1025) (xy 142.450501 178.006)
				(xy 141.350501 178.006) (xy 140.550501 177.2025) (xy 140.550501 172.806) (xy 141.250501 172.106)
				(xy 141.250501 171.106) (xy 142.075001 170.1025) (xy 144.9 170.1025) (xy 145.3 170.5) (xy 145.3 171.9)
				(xy 145.6 172.205128) (xy 147.9 172.2) (xy 149.075001 171.1025) (xy 150.075001 171.1025) (xy 150.175001 171.0025)
				(xy 150.175001 170.4025) (xy 152.275001 168.3025) (xy 152.275001 167.4025) (xy 152.275001 167.1025)
				(xy 158.075001 161.306) (xy 185.575 161.276)
			)
		)
	)
	(zone
		(net 206)
		(net_name "+1V1")
		(layer "In8.Cu")
		(hatch edge 0.508)
		(priority 4)
		(connect_pads
			(clearance 0.12)
		)
		(min_thickness 0.15)
		(filled_areas_thickness no)
		(fill yes
			(thermal_gap 0.2)
			(thermal_bridge_width 0.2)
		)
		(polygon
			(pts
				(xy 176.7 141.4) (xy 191.35 156.2) (xy 191.35 160.25) (xy 190.425 161.175) (xy 179.95 161.175) (xy 179.500501 161.176)
				(xy 157.975001 161.2025) (xy 152.175001 167.0025) (xy 152.175001 167.2025) (xy 152.2 168.5) (xy 150.075 170.625)
				(xy 150.075001 170.9025) (xy 149.975001 171.0025) (xy 149.075001 171.0025) (xy 147.9 172.1025) (xy 145.6 172.1)
				(xy 145.4 171.9) (xy 145.4 170.5) (xy 144.9 170.0025) (xy 137.075001 170.0025) (xy 136.275001 170.2025)
				(xy 131.975001 170.202487) (xy 131.975274 161.499999) (xy 127 156.5) (xy 127 137.3) (xy 176.7 137.2)
			)
		)
	)
	(zone
		(net 187)
		(net_name "+1V0_MGTAVCC")
		(layer "In8.Cu")
		(hatch edge 0.508)
		(priority 2)
		(connect_pads
			(clearance 0.12)
		)
		(min_thickness 0.15)
		(filled_areas_thickness no)
		(fill yes
			(thermal_gap 0.508)
			(thermal_bridge_width 0.508)
		)
		(polygon
			(pts
				(xy 149.543444 187.001) (xy 149.775501 187.201) (xy 153.1 187.201) (xy 156.67502 183.700676) (xy 180.8 183.7067)
				(xy 183.36001 186.25) (xy 188.45877 186.249773) (xy 188.447844 195.104932) (xy 182.1 195.1) (xy 177.2 190.2)
				(xy 155.8 190.2) (xy 154.2 191.8) (xy 147.6 191.8) (xy 145.151799 189.306) (xy 145.150501 183.906)
				(xy 145.450501 183.606) (xy 146.050501 183.606) (xy 146.550501 183.106) (xy 146.550501 177.406)
				(xy 147.175001 177.408489) (xy 149.575001 179.8025)
			)
		)
	)
	(zone
		(net 227)
		(net_name "+1V0")
		(layer "In8.Cu")
		(hatch edge 0.508)
		(connect_pads
			(clearance 0.12)
		)
		(min_thickness 0.15)
		(filled_areas_thickness no)
		(fill yes
			(thermal_gap 0.508)
			(thermal_bridge_width 0.508)
		)
		(polygon
			(pts
				(xy 206.940501 214.306) (xy 68.850501 214.306) (xy 68.850501 103.106) (xy 206.940501 103.106)
			)
		)
	)
	(zone
		(net 226)
		(net_name "+1V2_MGTAVTT")
		(layer "In8.Cu")
		(hatch edge 0.508)
		(priority 3)
		(connect_pads
			(clearance 0.12)
		)
		(min_thickness 0.15)
		(filled_areas_thickness no)
		(fill yes
			(thermal_gap 0.508)
			(thermal_bridge_width 0.508)
		)
		(polygon
			(pts
				(xy 186.9 182.6) (xy 206.7998 182.59946) (xy 206.800217 195.115329) (xy 188.600457 195.115857) (xy 188.600476 186.083901)
				(xy 183.480238 186.09) (xy 180.9 183.514109) (xy 156.575396 183.512714) (xy 153 187.1) (xy 149.875501 187.101)
				(xy 149.650501 186.901) (xy 149.675001 179.7025) (xy 147.275001 177.4025) (xy 147.275001 176.9025)
				(xy 147.275174 176.6025) (xy 150.075001 176.59782) (xy 151.175001 177.7025) (xy 182.049296 177.7025)
			)
		)
	)
	(zone
		(net 6)
		(net_name "/Debug FTDI/FTDI_3V3")
		(layer "In8.Cu")
		(hatch edge 0.508)
		(priority 3)
		(connect_pads yes
			(clearance 0.12)
		)
		(min_thickness 0.254)
		(filled_areas_thickness no)
		(fill yes
			(thermal_gap 0.508)
			(thermal_bridge_width 0.508)
		)
		(polygon
			(pts
				(xy 103.564172 170.214172) (xy 105.11 170.219713) (xy 105.11 171.76) (xy 105.385 172.035) (xy 105.75 172.4)
				(xy 105.75 176.05) (xy 108.8 179.1) (xy 108.8 181.2) (xy 108.25 181.75) (xy 102.45 181.75) (xy 102 181.3)
				(xy 91.2 181.3) (xy 88.75 178.8) (xy 88.75 171.35) (xy 90.15 169.95) (xy 94.45 169.95) (xy 96.55 167.85)
				(xy 101.2 167.85)
			)
		)
	)
	(zone
		(net 1)
		(net_name "GND")
		(layer "In8.Cu")
		(hatch edge 0.508)
		(priority 2)
		(connect_pads
			(clearance 0.12)
		)
		(min_thickness 0.254)
		(filled_areas_thickness no)
		(fill yes
			(thermal_gap 0.508)
			(thermal_bridge_width 0.508)
		)
		(polygon
			(pts
				(xy 99.3 150.6) (xy 107.4 150.6) (xy 107.4 137.3) (xy 126.8 137.3) (xy 126.8 156.2) (xy 131.9 161.3)
				(xy 131.9 170.8) (xy 129.8 173.3) (xy 106.9 173.3) (xy 105.219122 171.619122) (xy 105.220251 170.1)
				(xy 103.699778 170.099778) (xy 101.3 167.7) (xy 97 167.7) (xy 93.8 164.5) (xy 89.6 164.5) (xy 84.5 159.4)
				(xy 84.5 155) (xy 86.1 153.4) (xy 96.5 153.4)
			)
		)
	)
	(zone
		(net 10)
		(net_name "/FPGA banks HP/VREF")
		(layer "In9.Cu")
		(hatch edge 0.508)
		(priority 2)
		(connect_pads yes
			(clearance 0.12)
		)
		(min_thickness 0.1)
		(filled_areas_thickness no)
		(fill yes
			(thermal_gap 0.508)
			(thermal_bridge_width 0.508)
		)
		(polygon
			(pts
				(xy 136.6 162.7) (xy 136.6 168.1) (xy 138.8 170.3) (xy 141.5 170.3) (xy 142.1 169.7) (xy 142.1 164.1)
				(xy 141.3 163.3) (xy 141.3 162.7) (xy 141.8 162.2) (xy 143.1 162.2) (xy 145.1 164.2) (xy 147.3 164.2)
				(xy 148.4 163.1) (xy 149.9 163.1) (xy 150.1 163.3) (xy 150.1 163.6) (xy 149.8 163.9) (xy 148.6 163.9)
				(xy 147.3 165.2) (xy 147.3 167.4) (xy 147.9 168) (xy 148.7 168) (xy 149 168.3) (xy 149 168.9) (xy 146.9 168.9)
				(xy 142.2 173.6) (xy 134.5 173.6) (xy 133.4 172.5) (xy 133.4 162.7) (xy 133.9 162.2) (xy 136.1 162.2)
			)
		)
	)
	(zone
		(net 41)
		(net_name "+3V3_AON")
		(layer "In9.Cu")
		(hatch edge 0.508)
		(priority 3)
		(connect_pads yes
			(clearance 0.1)
		)
		(min_thickness 0.254)
		(filled_areas_thickness no)
		(fill yes
			(thermal_gap 0.508)
			(thermal_bridge_width 0.508)
		)
		(polygon
			(pts
				(xy 206.890501 149.356) (xy 191.500501 149.356) (xy 191.500501 133.586) (xy 206.890501 133.586)
			)
		)
	)
	(zone
		(net 38)
		(net_name "VDC")
		(layer "In9.Cu")
		(hatch edge 0.508)
		(priority 2)
		(connect_pads
			(clearance 0.12)
		)
		(min_thickness 0.254)
		(filled_areas_thickness no)
		(fill yes
			(thermal_gap 0.3)
			(thermal_bridge_width 0.3)
		)
		(polygon
			(pts
				(xy 206.900501 204.376) (xy 114.100501 204.376) (xy 114.100501 195.176) (xy 136.97 195.16) (xy 142.55 189.5)
				(xy 156.2 189.5) (xy 177.900501 168.1) (xy 177.900501 111.476) (xy 206.900501 111.476)
			)
		)
	)
	(zone
		(net 200)
		(net_name "+3V3")
		(layer "In10.Cu")
		(hatch edge 0.508)
		(connect_pads
			(clearance 0.15)
		)
		(min_thickness 0.254)
		(filled_areas_thickness no)
		(fill yes
			(thermal_gap 0.508)
			(thermal_bridge_width 0.508)
		)
		(polygon
			(pts
				(xy 206.900501 214.276) (xy 68.900501 214.276) (xy 68.900501 103.176) (xy 206.900501 103.176)
			)
		)
	)
	(zone
		(net 1)
		(net_name "GND")
		(layer "In10.Cu")
		(hatch edge 0.508)
		(priority 2)
		(connect_pads yes
			(clearance 0.12)
		)
		(min_thickness 0.254)
		(filled_areas_thickness no)
		(fill yes
			(thermal_gap 0.508)
			(thermal_bridge_width 0.508)
		)
		(polygon
			(pts
				(xy 157.2 164.1) (xy 149.875001 171.324999) (xy 146.7 171.324999) (xy 146.2 171.824999) (xy 141.75 171.824999)
				(xy 141.4 171.45) (xy 141.4 170.5) (xy 141 170.1) (xy 139.1 170.1) (xy 135.275001 166.3) (xy 131.7 166.3)
				(xy 131.3 165.9) (xy 131.3 160.8) (xy 127 156.5) (xy 127 135.4) (xy 157.2 135.4)
			)
		)
	)
	(zone
		(net 1)
		(net_name "GND")
		(layer "In10.Cu")
		(hatch edge 0.508)
		(priority 1)
		(connect_pads
			(clearance 0.15)
		)
		(min_thickness 0.254)
		(filled_areas_thickness no)
		(fill yes
			(thermal_gap 0.508)
			(thermal_bridge_width 0.508)
		)
		(polygon
			(pts
				(xy 164.300501 186.726) (xy 164.300501 201.476) (xy 148.200501 201.476) (xy 148.200501 214.276)
				(xy 127.400501 214.276) (xy 127.400501 198.076) (xy 137.000501 188.376) (xy 145.000501 188.376)
				(xy 145.400501 187.976) (xy 145.400501 183.9) (xy 149.800501 179.526) (xy 157.1 179.55)
			)
		)
	)
)
